G04 ================== begin FILE IDENTIFICATION RECORD ==================*
G04 Layout Name:  D:/<user>/Wistron_project/16316-1/gbr-0621/16316-1.brd*
G04 Film Name:    BSILK*
G04 File Format:  Gerber RS274X*
G04 File Origin:  Cadence Allegro 16.5-S056*
G04 Origin Date:  Wed Jun 21 09:31:34 2017*
G04 *
G04 Layer:  VIA CLASS/FILMMASKBOTTOM*
G04 Layer:  REF DES/ASSEMBLY_BOTTOM*
G04 Layer:  PACKAGE GEOMETRY/SILKSCREEN_BOTTOM*
G04 Layer:  DRAWING FORMAT/LAYER_PCB_STORY*
G04 Layer:  DRAWING FORMAT/LAYER_SILK_B*
G04 Layer:  BOARD GEOMETRY/SILKSCREEN_BOTTOM*
G04 *
G04 Offset:    (0.00 0.00)*
G04 Mirror:    No*
G04 Mode:      Positive*
G04 Rotation:  0*
G04 FullContactRelief:  No*
G04 UndefLineWidth:     6.00*
G04 ================== end FILE IDENTIFICATION RECORD ====================*
%FSLAX35Y35*MOIN*%
%IR0*IPPOS*OFA0.00000B0.00000*MIA0B0*SFA1.00000B1.00000*%
%ADD10C,.026*%
%ADD11C,.02*%
%ADD12C,.012*%
%ADD13C,.013*%
%ADD14C,.015*%
%ADD15C,.006*%
%ADD16C,.008*%
G75*
%LPD*%
G75*
G36*
G01X359292Y454711D02*
Y431089D01*
X233308D01*
Y454711D01*
X359292D01*
G37*
G36*
G01Y488711D02*
Y465089D01*
X233308D01*
Y488711D01*
X359292D01*
G37*
G36*
G01X359800Y327700D02*
X349800D01*
Y322700D01*
X359800D01*
Y327700D01*
G37*
G36*
G01X371160Y323565D02*
Y326435D01*
X366040D01*
Y323565D01*
X371160D01*
G37*
G36*
G01X531612Y449171D02*
Y460371D01*
X549012D01*
Y449171D01*
X531612D01*
G37*
G36*
G01X673739Y247884D02*
X683739D01*
Y252884D01*
X673739D01*
Y247884D01*
G37*
G36*
G01X718112Y472071D02*
X729312D01*
Y454671D01*
X718112D01*
Y472071D01*
G37*
G36*
G01X801200Y167600D02*
Y156400D01*
X783800D01*
Y167600D01*
X801200D01*
G37*
G54D10*
X54900Y204700D03*
X49900Y209700D03*
X59900D03*
X54900Y214700D03*
Y209700D03*
X201400Y174400D03*
X192400D03*
X196900D03*
X179800Y133500D03*
X175800Y129500D03*
X179800D03*
X175800Y133500D03*
X192400Y191600D03*
X196900D03*
X201400D03*
X192400Y187300D03*
X196900D03*
X201400D03*
Y178700D03*
X192400Y183000D03*
X196900D03*
X201400D03*
X192400Y178700D03*
X196900D03*
X246493Y399567D03*
X242893D03*
X257020Y390670D03*
X253420D03*
X249820D03*
X246220D03*
X256120Y395170D03*
X243120D03*
X247620D03*
X251870D03*
X242620Y390670D03*
X260893Y399567D03*
X257293D03*
X260620Y390670D03*
Y395170D03*
X253693Y399567D03*
X250093D03*
X609400Y446850D03*
X604400Y456100D03*
Y451850D03*
Y447350D03*
Y460350D03*
X609400Y450450D03*
Y454050D03*
Y457650D03*
Y461250D03*
X599503Y447123D03*
Y450723D03*
Y454323D03*
Y457923D03*
X604400Y464850D03*
X609400D03*
X599503Y461523D03*
Y465123D03*
X694400Y452900D03*
Y457400D03*
Y461900D03*
X689900Y457400D03*
Y452950D03*
X689700Y461850D03*
X698900Y457400D03*
X699000Y452950D03*
X698950Y461800D03*
G54D11*
G01X-34018Y-300855D02*
G02I-12000J0D01*
G01X-39168D02*
G02I-6850J0D01*
G01X-30018D02*
X-62018D01*
G01X-30018Y-316855D02*
Y-396855D01*
G01D02*
X1320682D01*
G01X-30018Y-352355D02*
X1320682D01*
G01X-46018Y-316855D02*
Y-284855D01*
G01X-30018Y-316855D02*
X1320682D01*
G01X151938Y421370D02*
Y426370D01*
G01X168938Y428370D02*
Y423370D01*
G01Y420370D02*
Y415370D01*
G01X151938Y428970D02*
Y433970D01*
G01X244800Y241000D02*
Y236000D01*
G01Y233400D02*
Y228400D01*
G01Y225800D02*
Y220800D01*
G01Y218200D02*
Y213200D01*
G01Y210600D02*
Y205600D01*
G01X259000Y373250D02*
Y378250D01*
G01X288000Y369200D02*
Y378000D01*
G01X362550Y322900D02*
Y315900D01*
G01X362600Y326435D02*
Y332175D01*
G01X533182Y-316855D02*
Y-396855D01*
G01X519012Y472571D02*
Y467571D01*
G01X519200Y464900D02*
Y459900D01*
G01X627781Y131508D02*
X622781D01*
G01X621526Y241952D02*
Y246952D01*
G01X607026D02*
Y241952D01*
G01X630070Y456730D02*
X625070D01*
G01X616700Y437400D02*
X621700D01*
G01X624400D02*
X629400D01*
G01X670682Y-316855D02*
Y-396855D01*
G01X671797Y180441D02*
Y175441D01*
G01X671662Y164683D02*
Y159683D01*
G01X689875Y181504D02*
X684875D01*
G01X671935Y189851D02*
Y184851D01*
G01X699261Y181483D02*
X694261D01*
G01X642000Y246500D02*
Y241500D01*
G01X656500D02*
Y246500D01*
G01X670989Y252684D02*
Y259684D01*
G01X646900Y362400D02*
Y367400D01*
G01X685800Y464200D02*
Y469200D01*
G01Y471866D02*
Y476866D01*
G01X728530Y235871D02*
X719730D01*
G01X708695Y181458D02*
X703695D01*
G01X723104Y342538D02*
Y347538D01*
G01Y350538D02*
Y355538D01*
G01X742680Y441740D02*
X736680D01*
G01X785682Y-316855D02*
Y-396855D01*
G01X785500Y111500D02*
X780500D01*
G01X787650Y101600D02*
X792300D01*
G01X774150D02*
X778800D01*
G01X779007Y125593D02*
X784007D01*
G01X953182Y-316855D02*
Y-396855D01*
G01X1123182Y-316855D02*
Y-396855D01*
G01X1320682Y-316855D02*
Y-396855D01*
G01X1348682Y-300855D02*
G02I-12000J0D01*
G01X1343532D02*
G02I-6850J0D01*
G01X1336682Y-316855D02*
Y-284855D01*
G01X1352682Y-300855D02*
X1320682D01*
G54D12*
G01X15748Y0D02*
X46456D01*
G01X326770D02*
X287400D01*
G01X334655Y555512D02*
Y530315D01*
G01X492136Y555512D02*
Y530315D01*
G01X597707Y0D02*
X628416D01*
G01X811023D02*
X780315D01*
G54D13*
G01X176838Y441736D02*
Y436736D01*
X171838D01*
G01X661966Y36700D02*
Y39550D01*
X659266D01*
G01X787050Y102000D02*
Y100150D01*
G01X792950Y102000D02*
Y100150D01*
G01X773550Y102000D02*
Y100150D01*
G01X779450Y102000D02*
Y100150D01*
G54D14*
G01X407669Y218693D02*
X383669Y194693D01*
G01X407669Y308867D02*
X383669Y332867D01*
G01X395669Y218693D02*
Y206693D01*
X407669D01*
G01Y320867D02*
X395669D01*
Y308867D01*
G01X497843Y218693D02*
X521843Y194693D01*
G01X509843Y218693D02*
Y206693D01*
X497843D01*
G01Y308867D02*
X521843Y332867D01*
G01X497843Y320867D02*
X509843D01*
Y308867D01*
G01X529962Y468321D02*
Y460571D01*
G01X737262Y473721D02*
X729512D01*
G01X802850Y148450D02*
Y156200D01*
G54D15*
G01X121778Y-377522D02*
X122652Y-376647D01*
X123307Y-375189D01*
X123744Y-373146D01*
X123307Y-371397D01*
X122434Y-370230D01*
X120905Y-369355D01*
X115010D01*
Y-386855D01*
X122215D01*
X123744Y-385689D01*
X124617Y-383938D01*
X125054Y-381897D01*
X124617Y-379855D01*
X123307Y-378105D01*
X121778Y-377522D01*
X115010D01*
G01X134475Y-386855D02*
Y-375189D01*
G01Y-377522D02*
X135567Y-376355D01*
X136659Y-375480D01*
X138187Y-375189D01*
X139278Y-375480D01*
X140589Y-376355D01*
G01X150447Y-392105D02*
X151757Y-392688D01*
X153504Y-392105D01*
X154595Y-390939D01*
X155469Y-389480D01*
X156778Y-384814D01*
X159617Y-375189D01*
G01X152630D02*
X156778Y-384814D01*
G01X176025Y-376647D02*
X174497Y-375480D01*
X173187Y-375189D01*
X171440Y-375772D01*
X170130Y-376938D01*
X169257Y-378980D01*
X169038Y-381022D01*
X169257Y-383064D01*
X170130Y-384814D01*
X171440Y-386272D01*
X173187Y-386855D01*
X174715Y-386272D01*
X176025Y-385105D01*
G01X186757Y-378980D02*
X193744D01*
X193089Y-376938D01*
X191997Y-375772D01*
X190469Y-375189D01*
X188940Y-375480D01*
X187630Y-376355D01*
X186757Y-378397D01*
X186320Y-380147D01*
Y-381897D01*
X186757Y-383647D01*
X187849Y-385397D01*
X189159Y-386563D01*
X190687Y-386855D01*
X192215Y-386272D01*
X193744Y-384522D01*
G01X229835Y-370814D02*
X228525Y-369938D01*
X226997Y-369355D01*
X225250D01*
X223285Y-370230D01*
X221757Y-371688D01*
X220665Y-373439D01*
X219792Y-376355D01*
X219573Y-378980D01*
X220010Y-381605D01*
X220665Y-383355D01*
X221975Y-385105D01*
X223504Y-386272D01*
X225032Y-386855D01*
X226560D01*
X228089Y-386272D01*
X229399Y-385397D01*
X230491Y-384231D01*
G01X246462Y-386855D02*
Y-375189D01*
G01Y-377230D02*
X245589Y-376064D01*
X244278Y-375480D01*
X242750Y-375189D01*
X241222Y-375772D01*
X239912Y-376938D01*
X239038Y-378688D01*
X238602Y-381022D01*
X239038Y-383355D01*
X239912Y-385105D01*
X241222Y-386272D01*
X242750Y-386855D01*
X244278Y-386563D01*
X245589Y-385689D01*
X246462Y-384522D01*
G01X256320Y-386855D02*
Y-375189D01*
G01Y-378105D02*
X257194Y-376647D01*
X258504Y-375480D01*
X260250Y-375189D01*
X261778Y-375480D01*
X263089Y-376647D01*
X263744Y-378688D01*
Y-386855D01*
G01X272947Y-392105D02*
X274257Y-392688D01*
X276004Y-392105D01*
X277095Y-390939D01*
X277969Y-389480D01*
X279278Y-384814D01*
X282117Y-375189D01*
G01X275130D02*
X279278Y-384814D01*
G01X295032Y-386855D02*
X293722Y-386563D01*
X292412Y-385397D01*
X291538Y-383355D01*
X291102Y-381022D01*
X291538Y-378688D01*
X292412Y-376647D01*
X293722Y-375480D01*
X295032Y-375189D01*
X296342Y-375480D01*
X297652Y-376647D01*
X298525Y-378688D01*
X298744Y-381022D01*
X298525Y-383355D01*
X297652Y-385397D01*
X296342Y-386563D01*
X295032Y-386855D01*
G01X308820D02*
Y-375189D01*
G01Y-378105D02*
X309694Y-376647D01*
X311004Y-375480D01*
X312750Y-375189D01*
X314278Y-375480D01*
X315589Y-376647D01*
X316244Y-378688D01*
Y-386855D01*
G01X342947Y-384522D02*
X344694Y-385980D01*
X346659Y-386855D01*
X348405D01*
X350152Y-385980D01*
X351462Y-384522D01*
X352117Y-382480D01*
X351680Y-380439D01*
X350589Y-378688D01*
X348624Y-377522D01*
X346004Y-376938D01*
X344475Y-375772D01*
X343820Y-373730D01*
X344257Y-371688D01*
X345349Y-370230D01*
X346877Y-369355D01*
X348405D01*
X349934Y-369938D01*
X351244Y-371397D01*
G01X369835Y-370814D02*
X368525Y-369938D01*
X366997Y-369355D01*
X365250D01*
X363285Y-370230D01*
X361757Y-371688D01*
X360665Y-373439D01*
X359792Y-376355D01*
X359573Y-378980D01*
X360010Y-381605D01*
X360665Y-383355D01*
X361975Y-385105D01*
X363504Y-386272D01*
X365032Y-386855D01*
X366560D01*
X368089Y-386272D01*
X369399Y-385397D01*
X370491Y-384231D01*
G01X387335Y-370814D02*
X386025Y-369938D01*
X384497Y-369355D01*
X382750D01*
X380785Y-370230D01*
X379257Y-371688D01*
X378165Y-373439D01*
X377292Y-376355D01*
X377073Y-378980D01*
X377510Y-381605D01*
X378165Y-383355D01*
X379475Y-385105D01*
X381004Y-386272D01*
X382532Y-386855D01*
X384060D01*
X385589Y-386272D01*
X386899Y-385397D01*
X387991Y-384231D01*
G01X210605Y-341855D02*
Y-324355D01*
X216282Y-338938D01*
X221959Y-324355D01*
Y-341855D01*
G01X233782D02*
X232472Y-341563D01*
X231162Y-340397D01*
X230288Y-338355D01*
X229852Y-336022D01*
X230288Y-333688D01*
X231162Y-331647D01*
X232472Y-330480D01*
X233782Y-330189D01*
X235092Y-330480D01*
X236402Y-331647D01*
X237275Y-333688D01*
X237494Y-336022D01*
X237275Y-338355D01*
X236402Y-340397D01*
X235092Y-341563D01*
X233782Y-341855D01*
G01X255212Y-324355D02*
Y-341855D01*
G01Y-339231D02*
X254339Y-340689D01*
X253028Y-341563D01*
X251500Y-341855D01*
X249754Y-341272D01*
X248444Y-339814D01*
X247570Y-338064D01*
X247352Y-336022D01*
X247570Y-333980D01*
X248444Y-332230D01*
X249754Y-330772D01*
X251500Y-330189D01*
X253028Y-330480D01*
X254120Y-331064D01*
X255212Y-332230D01*
G01X265507Y-333980D02*
X272494D01*
X271839Y-331938D01*
X270747Y-330772D01*
X269219Y-330189D01*
X267690Y-330480D01*
X266380Y-331355D01*
X265507Y-333397D01*
X265070Y-335147D01*
Y-336897D01*
X265507Y-338647D01*
X266599Y-340397D01*
X267909Y-341563D01*
X269437Y-341855D01*
X270965Y-341272D01*
X272494Y-339522D01*
G01X286282Y-341855D02*
Y-324355D01*
G01X566882Y-386855D02*
Y-369355D01*
X564262Y-372855D01*
G01Y-386855D02*
X569502D01*
G01X580234Y-379564D02*
X581762Y-377522D01*
X583072Y-376355D01*
X584819Y-375772D01*
X586347Y-376355D01*
X587439Y-377522D01*
X588312Y-379272D01*
X588530Y-381313D01*
X588312Y-383064D01*
X587439Y-384814D01*
X586128Y-386272D01*
X584600Y-386855D01*
X582854Y-386272D01*
X581325Y-384522D01*
X580452Y-381897D01*
X580234Y-378980D01*
X580670Y-375189D01*
X581325Y-373146D01*
X582417Y-371105D01*
X583945Y-369647D01*
X585474Y-369355D01*
X587002Y-369938D01*
X588094Y-371397D01*
G01X597079Y-383355D02*
X598388Y-385397D01*
X600135Y-386563D01*
X602100Y-386855D01*
X603847Y-386563D01*
X605594Y-385105D01*
X606685Y-383355D01*
X606904Y-381605D01*
X606467Y-379564D01*
X604939Y-378105D01*
X603410Y-377522D01*
X601445D01*
G01X603410D02*
X604720Y-376647D01*
X605812Y-375189D01*
X606249Y-373439D01*
X605812Y-371688D01*
X604720Y-370230D01*
X602755Y-369355D01*
X600790Y-369647D01*
X598825Y-370814D01*
G01X619382Y-386855D02*
Y-369355D01*
X616762Y-372855D01*
G01Y-386855D02*
X622002D01*
G01X632734Y-379564D02*
X634262Y-377522D01*
X635572Y-376355D01*
X637319Y-375772D01*
X638847Y-376355D01*
X639939Y-377522D01*
X640812Y-379272D01*
X641030Y-381313D01*
X640812Y-383064D01*
X639939Y-384814D01*
X638628Y-386272D01*
X637100Y-386855D01*
X635354Y-386272D01*
X633825Y-384522D01*
X632952Y-381897D01*
X632734Y-378980D01*
X633170Y-375189D01*
X633825Y-373146D01*
X634917Y-371105D01*
X636445Y-369647D01*
X637974Y-369355D01*
X639502Y-369938D01*
X640594Y-371397D01*
G01X553765Y-341855D02*
Y-324355D01*
X559005D01*
X560752Y-325230D01*
X562062Y-327272D01*
X562499Y-329605D01*
X562062Y-331938D01*
X560970Y-333688D01*
X559005Y-334564D01*
X553765D01*
G01X580435Y-325814D02*
X579125Y-324938D01*
X577597Y-324355D01*
X575850D01*
X573885Y-325230D01*
X572357Y-326688D01*
X571265Y-328439D01*
X570392Y-331355D01*
X570173Y-333980D01*
X570610Y-336605D01*
X571265Y-338355D01*
X572575Y-340105D01*
X574104Y-341272D01*
X575632Y-341855D01*
X577160D01*
X578689Y-341272D01*
X579999Y-340397D01*
X581091Y-339231D01*
G01X594878Y-332522D02*
X595752Y-331647D01*
X596407Y-330189D01*
X596844Y-328146D01*
X596407Y-326397D01*
X595534Y-325230D01*
X594005Y-324355D01*
X588110D01*
Y-341855D01*
X595315D01*
X596844Y-340689D01*
X597717Y-338938D01*
X598154Y-336897D01*
X597717Y-334855D01*
X596407Y-333105D01*
X594878Y-332522D01*
X588110D01*
G01X604082Y-347688D02*
X617182D01*
G01X623110Y-341855D02*
Y-324355D01*
X633154Y-341855D01*
Y-324355D01*
G01X645632Y-341855D02*
X643885Y-341563D01*
X642357Y-340397D01*
X641047Y-338647D01*
X640173Y-336605D01*
X639737Y-334272D01*
Y-331938D01*
X640173Y-329605D01*
X641047Y-327563D01*
X642357Y-325814D01*
X643885Y-324647D01*
X645632Y-324355D01*
X647378Y-324647D01*
X648907Y-325814D01*
X650217Y-327563D01*
X651091Y-329605D01*
X651527Y-331938D01*
Y-334272D01*
X651091Y-336605D01*
X650217Y-338647D01*
X648907Y-340397D01*
X647378Y-341563D01*
X645632Y-341855D01*
G01X696473Y-324355D02*
X701932Y-341855D01*
X707391Y-324355D01*
G01X723799Y-341855D02*
X715065D01*
Y-324355D01*
X723799D01*
G01X720305Y-332813D02*
X715065D01*
G01X732565Y-341855D02*
Y-324355D01*
X738024D01*
X739770Y-325230D01*
X740862Y-326397D01*
X741299Y-328730D01*
X740862Y-331064D01*
X739552Y-332522D01*
X738024Y-333397D01*
X732565D01*
G01X738024D02*
X741299Y-341855D01*
G01X754432Y-342438D02*
X753995Y-342147D01*
Y-341563D01*
X754432Y-341272D01*
X754869Y-341563D01*
Y-342147D01*
X754432Y-342438D01*
G01X728182Y-386855D02*
Y-369355D01*
X725562Y-372855D01*
G01Y-386855D02*
X730802D01*
G01X902636Y-377522D02*
X901762Y-376647D01*
X901107Y-375189D01*
X900670Y-373146D01*
X901107Y-371397D01*
X901980Y-370230D01*
X903509Y-369355D01*
X909404D01*
Y-386855D01*
X902199D01*
X900670Y-385689D01*
X899797Y-383938D01*
X899360Y-381897D01*
X899797Y-379855D01*
X901107Y-378105D01*
X902636Y-377522D01*
X909404D01*
G01X891467Y-384522D02*
X889720Y-385980D01*
X887755Y-386855D01*
X886009D01*
X884262Y-385980D01*
X882952Y-384522D01*
X882297Y-382480D01*
X882734Y-380439D01*
X883825Y-378688D01*
X885790Y-377522D01*
X888410Y-376938D01*
X889939Y-375772D01*
X890594Y-373730D01*
X890157Y-371688D01*
X889065Y-370230D01*
X887537Y-369355D01*
X886009D01*
X884480Y-369938D01*
X883170Y-371397D01*
G01X872002Y-369355D02*
X866762D01*
G01X869382D02*
Y-386855D01*
G01X872002D02*
X866762D01*
G01X856249Y-369355D02*
Y-386855D01*
X847515D01*
G01X839185D02*
Y-369355D01*
G01X830889D02*
X839185Y-380147D01*
G01X829579Y-386855D02*
X835474Y-375189D01*
G01X830015Y-324355D02*
Y-341855D01*
X838749D01*
G01X855812D02*
Y-330189D01*
G01Y-332230D02*
X854939Y-331064D01*
X853628Y-330480D01*
X852100Y-330189D01*
X850572Y-330772D01*
X849262Y-331938D01*
X848388Y-333688D01*
X847952Y-336022D01*
X848388Y-338355D01*
X849262Y-340105D01*
X850572Y-341272D01*
X852100Y-341855D01*
X853628Y-341563D01*
X854939Y-340689D01*
X855812Y-339522D01*
G01X864797Y-347105D02*
X866107Y-347688D01*
X867854Y-347105D01*
X868945Y-345939D01*
X869819Y-344480D01*
X871128Y-339814D01*
X873967Y-330189D01*
G01X866980D02*
X871128Y-339814D01*
G01X883607Y-333980D02*
X890594D01*
X889939Y-331938D01*
X888847Y-330772D01*
X887319Y-330189D01*
X885790Y-330480D01*
X884480Y-331355D01*
X883607Y-333397D01*
X883170Y-335147D01*
Y-336897D01*
X883607Y-338647D01*
X884699Y-340397D01*
X886009Y-341563D01*
X887537Y-341855D01*
X889065Y-341272D01*
X890594Y-339522D01*
G01X901325Y-341855D02*
Y-330189D01*
G01Y-332522D02*
X902417Y-331355D01*
X903509Y-330480D01*
X905037Y-330189D01*
X906128Y-330480D01*
X907439Y-331355D01*
G01X994432Y-386855D02*
X992685Y-386563D01*
X991157Y-385397D01*
X989847Y-383647D01*
X988973Y-381605D01*
X988537Y-379272D01*
Y-376938D01*
X988973Y-374605D01*
X989847Y-372563D01*
X991157Y-370814D01*
X992685Y-369647D01*
X994432Y-369355D01*
X996178Y-369647D01*
X997707Y-370814D01*
X999017Y-372563D01*
X999891Y-374605D01*
X1000327Y-376938D01*
Y-379272D01*
X999891Y-381605D01*
X999017Y-383647D01*
X997707Y-385397D01*
X996178Y-386563D01*
X994432Y-386855D01*
G01X996178Y-382188D02*
X998799Y-386855D01*
G01X1007129Y-369355D02*
Y-381897D01*
X1008002Y-384522D01*
X1009749Y-386272D01*
X1011932Y-386855D01*
X1014115Y-386272D01*
X1015862Y-384522D01*
X1016735Y-381897D01*
Y-369355D01*
G01X1026812D02*
X1032052D01*
G01X1029432D02*
Y-386855D01*
G01X1026812D02*
X1032052D01*
G01X1041910D02*
Y-369355D01*
X1051954Y-386855D01*
Y-369355D01*
G01X1069235Y-370814D02*
X1067925Y-369938D01*
X1066397Y-369355D01*
X1064650D01*
X1062685Y-370230D01*
X1061157Y-371688D01*
X1060065Y-373439D01*
X1059192Y-376355D01*
X1058973Y-378980D01*
X1059410Y-381605D01*
X1060065Y-383355D01*
X1061375Y-385105D01*
X1062904Y-386272D01*
X1064432Y-386855D01*
X1065960D01*
X1067489Y-386272D01*
X1068799Y-385397D01*
X1069891Y-384231D01*
G01X1081932Y-386855D02*
Y-378980D01*
X1077565Y-369355D01*
G01X1086299D02*
X1081932Y-378980D01*
G01X972129Y-341855D02*
Y-324355D01*
X976495D01*
X978242Y-325230D01*
X979552Y-326397D01*
X980644Y-328146D01*
X981517Y-330189D01*
X981735Y-333105D01*
X981517Y-336022D01*
X980644Y-338064D01*
X979552Y-339814D01*
X978242Y-340980D01*
X976495Y-341855D01*
X972129D01*
G01X991157Y-333980D02*
X998144D01*
X997489Y-331938D01*
X996397Y-330772D01*
X994869Y-330189D01*
X993340Y-330480D01*
X992030Y-331355D01*
X991157Y-333397D01*
X990720Y-335147D01*
Y-336897D01*
X991157Y-338647D01*
X992249Y-340397D01*
X993559Y-341563D01*
X995087Y-341855D01*
X996615Y-341272D01*
X998144Y-339522D01*
G01X1008657Y-339814D02*
X1009749Y-340980D01*
X1011277Y-341855D01*
X1012587D01*
X1013897Y-341272D01*
X1014770Y-340397D01*
X1015207Y-339231D01*
X1014989Y-337480D01*
X1014115Y-336605D01*
X1010185Y-334855D01*
X1009312Y-332813D01*
X1009749Y-331355D01*
X1010622Y-330480D01*
X1011932Y-330189D01*
X1013242Y-330480D01*
X1014552Y-331355D01*
G01X1029432Y-330189D02*
Y-341855D01*
G01Y-325522D02*
X1028995Y-325230D01*
Y-324647D01*
X1029432Y-324355D01*
X1029869Y-324647D01*
Y-325230D01*
X1029432Y-325522D01*
G01X1043875Y-346230D02*
X1045404Y-347397D01*
X1047150Y-347688D01*
X1048678Y-347397D01*
X1049989Y-345939D01*
X1050862Y-343897D01*
Y-330189D01*
G01Y-332522D02*
X1049989Y-331355D01*
X1048678Y-330480D01*
X1047150Y-330189D01*
X1045404Y-330772D01*
X1044312Y-331938D01*
X1043438Y-333980D01*
X1043002Y-336022D01*
X1043220Y-337772D01*
X1044094Y-339814D01*
X1045404Y-341272D01*
X1047150Y-341855D01*
X1048460Y-341563D01*
X1049989Y-340397D01*
X1050862Y-339231D01*
G01X1060720Y-341855D02*
Y-330189D01*
G01Y-333105D02*
X1061594Y-331647D01*
X1062904Y-330480D01*
X1064650Y-330189D01*
X1066178Y-330480D01*
X1067489Y-331647D01*
X1068144Y-333688D01*
Y-341855D01*
G01X1078657Y-333980D02*
X1085644D01*
X1084989Y-331938D01*
X1083897Y-330772D01*
X1082369Y-330189D01*
X1080840Y-330480D01*
X1079530Y-331355D01*
X1078657Y-333397D01*
X1078220Y-335147D01*
Y-336897D01*
X1078657Y-338647D01*
X1079749Y-340397D01*
X1081059Y-341563D01*
X1082587Y-341855D01*
X1084115Y-341272D01*
X1085644Y-339522D01*
G01X1096375Y-341855D02*
Y-330189D01*
G01Y-332522D02*
X1097467Y-331355D01*
X1098559Y-330480D01*
X1100087Y-330189D01*
X1101178Y-330480D01*
X1102489Y-331355D01*
G01X1143132Y-369355D02*
X1141385Y-369938D01*
X1140075Y-371397D01*
X1139202Y-373146D01*
X1138547Y-375480D01*
X1138329Y-378105D01*
X1138547Y-380730D01*
X1139202Y-383064D01*
X1140075Y-384814D01*
X1141385Y-386272D01*
X1143132Y-386855D01*
X1144878Y-386272D01*
X1146189Y-384814D01*
X1147062Y-383064D01*
X1147717Y-380730D01*
X1147935Y-378105D01*
X1147717Y-375480D01*
X1147062Y-373146D01*
X1146189Y-371397D01*
X1144878Y-369938D01*
X1143132Y-369355D01*
G01X1156484Y-379564D02*
X1158012Y-377522D01*
X1159322Y-376355D01*
X1161069Y-375772D01*
X1162597Y-376355D01*
X1163689Y-377522D01*
X1164562Y-379272D01*
X1164780Y-381313D01*
X1164562Y-383064D01*
X1163689Y-384814D01*
X1162378Y-386272D01*
X1160850Y-386855D01*
X1159104Y-386272D01*
X1157575Y-384522D01*
X1156702Y-381897D01*
X1156484Y-378980D01*
X1156920Y-375189D01*
X1157575Y-373146D01*
X1158667Y-371105D01*
X1160195Y-369647D01*
X1161724Y-369355D01*
X1163252Y-369938D01*
X1164344Y-371397D01*
G01X1174202Y-387438D02*
X1182062Y-369355D01*
G01X1191484Y-372272D02*
X1192794Y-370522D01*
X1194322Y-369647D01*
X1196069Y-369355D01*
X1198252Y-369938D01*
X1199780Y-371397D01*
X1200217Y-373146D01*
X1199999Y-374897D01*
X1199125Y-376355D01*
X1194759Y-379272D01*
X1192794Y-381313D01*
X1191484Y-384231D01*
X1191047Y-386855D01*
X1200217D01*
G01X1213132D02*
Y-369355D01*
X1210512Y-372855D01*
G01Y-386855D02*
X1215752D01*
G01X1226702Y-387438D02*
X1234562Y-369355D01*
G01X1243984Y-372272D02*
X1245294Y-370522D01*
X1246822Y-369647D01*
X1248569Y-369355D01*
X1250752Y-369938D01*
X1252280Y-371397D01*
X1252717Y-373146D01*
X1252499Y-374897D01*
X1251625Y-376355D01*
X1247259Y-379272D01*
X1245294Y-381313D01*
X1243984Y-384231D01*
X1243547Y-386855D01*
X1252717D01*
G01X1265632Y-369355D02*
X1263885Y-369938D01*
X1262575Y-371397D01*
X1261702Y-373146D01*
X1261047Y-375480D01*
X1260829Y-378105D01*
X1261047Y-380730D01*
X1261702Y-383064D01*
X1262575Y-384814D01*
X1263885Y-386272D01*
X1265632Y-386855D01*
X1267378Y-386272D01*
X1268689Y-384814D01*
X1269562Y-383064D01*
X1270217Y-380730D01*
X1270435Y-378105D01*
X1270217Y-375480D01*
X1269562Y-373146D01*
X1268689Y-371397D01*
X1267378Y-369938D01*
X1265632Y-369355D01*
G01X1283132Y-386855D02*
Y-369355D01*
X1280512Y-372855D01*
G01Y-386855D02*
X1285752D01*
G01X1300195D02*
X1300632Y-383064D01*
X1301287Y-379855D01*
X1302160Y-376938D01*
X1303252Y-373730D01*
X1304999Y-369355D01*
X1296265D01*
G01X1190829Y-341855D02*
Y-324355D01*
X1195195D01*
X1196942Y-325230D01*
X1198252Y-326397D01*
X1199344Y-328146D01*
X1200217Y-330189D01*
X1200435Y-333105D01*
X1200217Y-336022D01*
X1199344Y-338064D01*
X1198252Y-339814D01*
X1196942Y-340980D01*
X1195195Y-341855D01*
X1190829D01*
G01X1217062D02*
Y-330189D01*
G01Y-332230D02*
X1216189Y-331064D01*
X1214878Y-330480D01*
X1213350Y-330189D01*
X1211822Y-330772D01*
X1210512Y-331938D01*
X1209638Y-333688D01*
X1209202Y-336022D01*
X1209638Y-338355D01*
X1210512Y-340105D01*
X1211822Y-341272D01*
X1213350Y-341855D01*
X1214878Y-341563D01*
X1216189Y-340689D01*
X1217062Y-339522D01*
G01X1230632Y-324355D02*
Y-341855D01*
G01X1227575Y-330189D02*
X1233689D01*
G01X1244857Y-333980D02*
X1251844D01*
X1251189Y-331938D01*
X1250097Y-330772D01*
X1248569Y-330189D01*
X1247040Y-330480D01*
X1245730Y-331355D01*
X1244857Y-333397D01*
X1244420Y-335147D01*
Y-336897D01*
X1244857Y-338647D01*
X1245949Y-340397D01*
X1247259Y-341563D01*
X1248787Y-341855D01*
X1250315Y-341272D01*
X1251844Y-339522D01*
G01X10190Y249000D02*
Y234000D01*
X145000D01*
Y243000D01*
G01X13982Y238767D02*
X14107Y238517D01*
X14190Y238225D01*
Y237892D01*
X14065Y237517D01*
X13857Y237225D01*
X13607Y237017D01*
X13190Y236850D01*
X12815Y236808D01*
X12440Y236892D01*
X12190Y237017D01*
X11940Y237267D01*
X11773Y237558D01*
X11690Y237850D01*
Y238142D01*
X11773Y238433D01*
X11898Y238683D01*
X12065Y238892D01*
G01X11690Y240950D02*
X11732Y241242D01*
X11857Y241575D01*
X12065Y241783D01*
X12357Y241867D01*
X12648Y241783D01*
X12898Y241533D01*
X13023Y241158D01*
Y240742D01*
X13107Y240492D01*
X13315Y240283D01*
X13607Y240200D01*
X13898Y240325D01*
X14107Y240617D01*
X14190Y240950D01*
X14107Y241283D01*
X13898Y241575D01*
X13607Y241700D01*
X13315Y241617D01*
X13107Y241408D01*
X13023Y241158D01*
Y240742D01*
X12898Y240367D01*
X12648Y240117D01*
X12357Y240033D01*
X12065Y240117D01*
X11857Y240325D01*
X11732Y240658D01*
X11690Y240950D01*
G01X11982Y243342D02*
X11773Y243633D01*
X11690Y243967D01*
X11773Y244300D01*
X12023Y244592D01*
X12398Y244800D01*
X12773Y244883D01*
X13232D01*
X13607Y244800D01*
X13940Y244592D01*
X14107Y244342D01*
X14190Y244050D01*
X14107Y243717D01*
X13940Y243467D01*
X13690Y243300D01*
X13357Y243217D01*
X13065Y243300D01*
X12773Y243508D01*
X12607Y243758D01*
X12565Y244050D01*
X12648Y244383D01*
X12857Y244633D01*
X13232Y244883D01*
G01X123690Y365500D02*
X107500D01*
Y352000D01*
X91500D01*
Y336850D01*
X3000D01*
Y313500D01*
X10190D01*
Y249000D01*
X134900D01*
G02X135000Y248900I0J-100D01*
G01Y243000D01*
X154000D01*
G01X21233Y298792D02*
X21483Y298917D01*
X21775Y299000D01*
X22108D01*
X22483Y298875D01*
X22775Y298667D01*
X22983Y298417D01*
X23150Y298000D01*
X23192Y297625D01*
X23108Y297250D01*
X22983Y297000D01*
X22733Y296750D01*
X22442Y296583D01*
X22150Y296500D01*
X21858D01*
X21567Y296583D01*
X21317Y296708D01*
X21108Y296875D01*
G01X19050Y296500D02*
Y299000D01*
X19550Y298500D01*
G01Y296500D02*
X18550D01*
G01X16867Y296875D02*
X16617Y296667D01*
X16325Y296542D01*
X15950Y296500D01*
X15575Y296583D01*
X15283Y296750D01*
X15075Y297042D01*
X15033Y297375D01*
X15117Y297708D01*
X15325Y297917D01*
X15617Y298083D01*
X15908Y298125D01*
X16200Y298083D01*
X16575Y297917D01*
X16450Y299000D01*
X15325D01*
G01X12350Y296500D02*
Y299000D01*
X13892Y297208D01*
X11808D01*
G01X18561Y326835D02*
Y329335D01*
X17520D01*
X17186Y329210D01*
X16978Y329043D01*
X16895Y328710D01*
X16978Y328377D01*
X17228Y328168D01*
X17520Y328043D01*
X18561D01*
G01X17520D02*
X16895Y326835D01*
G01X15545Y327335D02*
X15295Y327043D01*
X14961Y326877D01*
X14586Y326835D01*
X14253Y326877D01*
X13920Y327085D01*
X13711Y327335D01*
X13670Y327585D01*
X13753Y327877D01*
X14045Y328085D01*
X14336Y328168D01*
X14711D01*
G01X14336D02*
X14086Y328293D01*
X13878Y328502D01*
X13795Y328752D01*
X13878Y329002D01*
X14086Y329210D01*
X14461Y329335D01*
X14836Y329293D01*
X15211Y329127D01*
G01X11528Y326835D02*
X11236Y326877D01*
X10903Y327002D01*
X10695Y327210D01*
X10611Y327502D01*
X10695Y327793D01*
X10945Y328043D01*
X11320Y328168D01*
X11736D01*
X11986Y328252D01*
X12195Y328460D01*
X12278Y328752D01*
X12153Y329043D01*
X11861Y329252D01*
X11528Y329335D01*
X11195Y329252D01*
X10903Y329043D01*
X10778Y328752D01*
X10861Y328460D01*
X11070Y328252D01*
X11320Y328168D01*
X11736D01*
X12111Y328043D01*
X12361Y327793D01*
X12445Y327502D01*
X12361Y327210D01*
X12153Y327002D01*
X11820Y326877D01*
X11528Y326835D01*
G01X8428Y329335D02*
X8761Y329252D01*
X9011Y329043D01*
X9178Y328793D01*
X9303Y328460D01*
X9345Y328085D01*
X9303Y327710D01*
X9178Y327377D01*
X9011Y327127D01*
X8761Y326918D01*
X8428Y326835D01*
X8095Y326918D01*
X7845Y327127D01*
X7678Y327377D01*
X7553Y327710D01*
X7511Y328085D01*
X7553Y328460D01*
X7678Y328793D01*
X7845Y329043D01*
X8095Y329252D01*
X8428Y329335D01*
G01X17682Y238767D02*
X17807Y238517D01*
X17890Y238225D01*
Y237892D01*
X17765Y237517D01*
X17557Y237225D01*
X17307Y237017D01*
X16890Y236850D01*
X16515Y236808D01*
X16140Y236892D01*
X15890Y237017D01*
X15640Y237267D01*
X15473Y237558D01*
X15390Y237850D01*
Y238142D01*
X15473Y238433D01*
X15598Y238683D01*
X15765Y238892D01*
G01X15390Y240950D02*
X15432Y241242D01*
X15557Y241575D01*
X15765Y241783D01*
X16057Y241867D01*
X16348Y241783D01*
X16598Y241533D01*
X16723Y241158D01*
Y240742D01*
X16807Y240492D01*
X17015Y240283D01*
X17307Y240200D01*
X17598Y240325D01*
X17807Y240617D01*
X17890Y240950D01*
X17807Y241283D01*
X17598Y241575D01*
X17307Y241700D01*
X17015Y241617D01*
X16807Y241408D01*
X16723Y241158D01*
Y240742D01*
X16598Y240367D01*
X16348Y240117D01*
X16057Y240033D01*
X15765Y240117D01*
X15557Y240325D01*
X15432Y240658D01*
X15390Y240950D01*
G01Y243967D02*
X15932Y244050D01*
X16390Y244175D01*
X16807Y244342D01*
X17265Y244550D01*
X17890Y244883D01*
Y243217D01*
G01X21982Y238767D02*
X22107Y238517D01*
X22190Y238225D01*
Y237892D01*
X22065Y237517D01*
X21857Y237225D01*
X21607Y237017D01*
X21190Y236850D01*
X20815Y236808D01*
X20440Y236892D01*
X20190Y237017D01*
X19940Y237267D01*
X19773Y237558D01*
X19690Y237850D01*
Y238142D01*
X19773Y238433D01*
X19898Y238683D01*
X20065Y238892D01*
G01X19690Y240950D02*
X19732Y241242D01*
X19857Y241575D01*
X20065Y241783D01*
X20357Y241867D01*
X20648Y241783D01*
X20898Y241533D01*
X21023Y241158D01*
Y240742D01*
X21107Y240492D01*
X21315Y240283D01*
X21607Y240200D01*
X21898Y240325D01*
X22107Y240617D01*
X22190Y240950D01*
X22107Y241283D01*
X21898Y241575D01*
X21607Y241700D01*
X21315Y241617D01*
X21107Y241408D01*
X21023Y241158D01*
Y240742D01*
X20898Y240367D01*
X20648Y240117D01*
X20357Y240033D01*
X20065Y240117D01*
X19857Y240325D01*
X19732Y240658D01*
X19690Y240950D01*
G01X20732Y243258D02*
X21023Y243550D01*
X21190Y243800D01*
X21273Y244133D01*
X21190Y244425D01*
X21023Y244633D01*
X20773Y244800D01*
X20482Y244842D01*
X20232Y244800D01*
X19982Y244633D01*
X19773Y244383D01*
X19690Y244092D01*
X19773Y243758D01*
X20023Y243467D01*
X20398Y243300D01*
X20815Y243258D01*
X21357Y243342D01*
X21648Y243467D01*
X21940Y243675D01*
X22148Y243967D01*
X22190Y244258D01*
X22107Y244550D01*
X21898Y244758D01*
G01X25482Y238667D02*
X25607Y238417D01*
X25690Y238125D01*
Y237792D01*
X25565Y237417D01*
X25357Y237125D01*
X25107Y236917D01*
X24690Y236750D01*
X24315Y236708D01*
X23940Y236792D01*
X23690Y236917D01*
X23440Y237167D01*
X23273Y237458D01*
X23190Y237750D01*
Y238042D01*
X23273Y238333D01*
X23398Y238583D01*
X23565Y238792D01*
G01X23190Y240850D02*
X23232Y241142D01*
X23357Y241475D01*
X23565Y241683D01*
X23857Y241767D01*
X24148Y241683D01*
X24398Y241433D01*
X24523Y241058D01*
Y240642D01*
X24607Y240392D01*
X24815Y240183D01*
X25107Y240100D01*
X25398Y240225D01*
X25607Y240517D01*
X25690Y240850D01*
X25607Y241183D01*
X25398Y241475D01*
X25107Y241600D01*
X24815Y241517D01*
X24607Y241308D01*
X24523Y241058D01*
Y240642D01*
X24398Y240267D01*
X24148Y240017D01*
X23857Y239933D01*
X23565Y240017D01*
X23357Y240225D01*
X23232Y240558D01*
X23190Y240850D01*
G01X23565Y243033D02*
X23357Y243283D01*
X23232Y243575D01*
X23190Y243950D01*
X23273Y244325D01*
X23440Y244617D01*
X23732Y244825D01*
X24065Y244867D01*
X24398Y244783D01*
X24607Y244575D01*
X24773Y244283D01*
X24815Y243992D01*
X24773Y243700D01*
X24607Y243325D01*
X25690Y243450D01*
Y244575D01*
G01X29982Y238667D02*
X30107Y238417D01*
X30190Y238125D01*
Y237792D01*
X30065Y237417D01*
X29857Y237125D01*
X29607Y236917D01*
X29190Y236750D01*
X28815Y236708D01*
X28440Y236792D01*
X28190Y236917D01*
X27940Y237167D01*
X27773Y237458D01*
X27690Y237750D01*
Y238042D01*
X27773Y238333D01*
X27898Y238583D01*
X28065Y238792D01*
G01X27690Y240850D02*
X27732Y241142D01*
X27857Y241475D01*
X28065Y241683D01*
X28357Y241767D01*
X28648Y241683D01*
X28898Y241433D01*
X29023Y241058D01*
Y240642D01*
X29107Y240392D01*
X29315Y240183D01*
X29607Y240100D01*
X29898Y240225D01*
X30107Y240517D01*
X30190Y240850D01*
X30107Y241183D01*
X29898Y241475D01*
X29607Y241600D01*
X29315Y241517D01*
X29107Y241308D01*
X29023Y241058D01*
Y240642D01*
X28898Y240267D01*
X28648Y240017D01*
X28357Y239933D01*
X28065Y240017D01*
X27857Y240225D01*
X27732Y240558D01*
X27690Y240850D01*
G01Y244450D02*
X30190D01*
X28398Y242908D01*
Y244992D01*
G01X33682Y238767D02*
X33807Y238517D01*
X33890Y238225D01*
Y237892D01*
X33765Y237517D01*
X33557Y237225D01*
X33307Y237017D01*
X32890Y236850D01*
X32515Y236808D01*
X32140Y236892D01*
X31890Y237017D01*
X31640Y237267D01*
X31473Y237558D01*
X31390Y237850D01*
Y238142D01*
X31473Y238433D01*
X31598Y238683D01*
X31765Y238892D01*
G01X31390Y240950D02*
X31432Y241242D01*
X31557Y241575D01*
X31765Y241783D01*
X32057Y241867D01*
X32348Y241783D01*
X32598Y241533D01*
X32723Y241158D01*
Y240742D01*
X32807Y240492D01*
X33015Y240283D01*
X33307Y240200D01*
X33598Y240325D01*
X33807Y240617D01*
X33890Y240950D01*
X33807Y241283D01*
X33598Y241575D01*
X33307Y241700D01*
X33015Y241617D01*
X32807Y241408D01*
X32723Y241158D01*
Y240742D01*
X32598Y240367D01*
X32348Y240117D01*
X32057Y240033D01*
X31765Y240117D01*
X31557Y240325D01*
X31432Y240658D01*
X31390Y240950D01*
G01X31890Y243133D02*
X31598Y243383D01*
X31432Y243717D01*
X31390Y244092D01*
X31432Y244425D01*
X31640Y244758D01*
X31890Y244967D01*
X32140Y245008D01*
X32432Y244925D01*
X32640Y244633D01*
X32723Y244342D01*
Y243967D01*
G01Y244342D02*
X32848Y244592D01*
X33057Y244800D01*
X33307Y244883D01*
X33557Y244800D01*
X33765Y244592D01*
X33890Y244217D01*
X33848Y243842D01*
X33682Y243467D01*
G01X37982Y238667D02*
X38107Y238417D01*
X38190Y238125D01*
Y237792D01*
X38065Y237417D01*
X37857Y237125D01*
X37607Y236917D01*
X37190Y236750D01*
X36815Y236708D01*
X36440Y236792D01*
X36190Y236917D01*
X35940Y237167D01*
X35773Y237458D01*
X35690Y237750D01*
Y238042D01*
X35773Y238333D01*
X35898Y238583D01*
X36065Y238792D01*
G01X35690Y240850D02*
X35732Y241142D01*
X35857Y241475D01*
X36065Y241683D01*
X36357Y241767D01*
X36648Y241683D01*
X36898Y241433D01*
X37023Y241058D01*
Y240642D01*
X37107Y240392D01*
X37315Y240183D01*
X37607Y240100D01*
X37898Y240225D01*
X38107Y240517D01*
X38190Y240850D01*
X38107Y241183D01*
X37898Y241475D01*
X37607Y241600D01*
X37315Y241517D01*
X37107Y241308D01*
X37023Y241058D01*
Y240642D01*
X36898Y240267D01*
X36648Y240017D01*
X36357Y239933D01*
X36065Y240017D01*
X35857Y240225D01*
X35732Y240558D01*
X35690Y240850D01*
G01X37773Y243158D02*
X38023Y243408D01*
X38148Y243700D01*
X38190Y244033D01*
X38107Y244450D01*
X37898Y244742D01*
X37648Y244825D01*
X37398Y244783D01*
X37190Y244617D01*
X36773Y243783D01*
X36482Y243408D01*
X36065Y243158D01*
X35690Y243075D01*
Y244825D01*
G01X41682Y238767D02*
X41807Y238517D01*
X41890Y238225D01*
Y237892D01*
X41765Y237517D01*
X41557Y237225D01*
X41307Y237017D01*
X40890Y236850D01*
X40515Y236808D01*
X40140Y236892D01*
X39890Y237017D01*
X39640Y237267D01*
X39473Y237558D01*
X39390Y237850D01*
Y238142D01*
X39473Y238433D01*
X39598Y238683D01*
X39765Y238892D01*
G01X39390Y240950D02*
X39432Y241242D01*
X39557Y241575D01*
X39765Y241783D01*
X40057Y241867D01*
X40348Y241783D01*
X40598Y241533D01*
X40723Y241158D01*
Y240742D01*
X40807Y240492D01*
X41015Y240283D01*
X41307Y240200D01*
X41598Y240325D01*
X41807Y240617D01*
X41890Y240950D01*
X41807Y241283D01*
X41598Y241575D01*
X41307Y241700D01*
X41015Y241617D01*
X40807Y241408D01*
X40723Y241158D01*
Y240742D01*
X40598Y240367D01*
X40348Y240117D01*
X40057Y240033D01*
X39765Y240117D01*
X39557Y240325D01*
X39432Y240658D01*
X39390Y240950D01*
G01Y244050D02*
X41890D01*
X41390Y243550D01*
G01X39390D02*
Y244550D01*
G01X45982Y238667D02*
X46107Y238417D01*
X46190Y238125D01*
Y237792D01*
X46065Y237417D01*
X45857Y237125D01*
X45607Y236917D01*
X45190Y236750D01*
X44815Y236708D01*
X44440Y236792D01*
X44190Y236917D01*
X43940Y237167D01*
X43773Y237458D01*
X43690Y237750D01*
Y238042D01*
X43773Y238333D01*
X43898Y238583D01*
X44065Y238792D01*
G01X43690Y240850D02*
X43732Y241142D01*
X43857Y241475D01*
X44065Y241683D01*
X44357Y241767D01*
X44648Y241683D01*
X44898Y241433D01*
X45023Y241058D01*
Y240642D01*
X45107Y240392D01*
X45315Y240183D01*
X45607Y240100D01*
X45898Y240225D01*
X46107Y240517D01*
X46190Y240850D01*
X46107Y241183D01*
X45898Y241475D01*
X45607Y241600D01*
X45315Y241517D01*
X45107Y241308D01*
X45023Y241058D01*
Y240642D01*
X44898Y240267D01*
X44648Y240017D01*
X44357Y239933D01*
X44065Y240017D01*
X43857Y240225D01*
X43732Y240558D01*
X43690Y240850D01*
G01X46190Y243950D02*
X46107Y243617D01*
X45898Y243367D01*
X45648Y243200D01*
X45315Y243075D01*
X44940Y243033D01*
X44565Y243075D01*
X44232Y243200D01*
X43982Y243367D01*
X43773Y243617D01*
X43690Y243950D01*
X43773Y244283D01*
X43982Y244533D01*
X44232Y244700D01*
X44565Y244825D01*
X44940Y244867D01*
X45315Y244825D01*
X45648Y244700D01*
X45898Y244533D01*
X46107Y244283D01*
X46190Y243950D01*
G01X49482Y238667D02*
X49607Y238417D01*
X49690Y238125D01*
Y237792D01*
X49565Y237417D01*
X49357Y237125D01*
X49107Y236917D01*
X48690Y236750D01*
X48315Y236708D01*
X47940Y236792D01*
X47690Y236917D01*
X47440Y237167D01*
X47273Y237458D01*
X47190Y237750D01*
Y238042D01*
X47273Y238333D01*
X47398Y238583D01*
X47565Y238792D01*
G01X47190Y240767D02*
X47732Y240850D01*
X48190Y240975D01*
X48607Y241142D01*
X49065Y241350D01*
X49690Y241683D01*
Y240017D01*
G01X47482Y243242D02*
X47273Y243533D01*
X47190Y243867D01*
X47273Y244200D01*
X47523Y244492D01*
X47898Y244700D01*
X48273Y244783D01*
X48732D01*
X49107Y244700D01*
X49440Y244492D01*
X49607Y244242D01*
X49690Y243950D01*
X49607Y243617D01*
X49440Y243367D01*
X49190Y243200D01*
X48857Y243117D01*
X48565Y243200D01*
X48273Y243408D01*
X48107Y243658D01*
X48065Y243950D01*
X48148Y244283D01*
X48357Y244533D01*
X48732Y244783D01*
G01X56982Y238667D02*
X57107Y238417D01*
X57190Y238125D01*
Y237792D01*
X57065Y237417D01*
X56857Y237125D01*
X56607Y236917D01*
X56190Y236750D01*
X55815Y236708D01*
X55440Y236792D01*
X55190Y236917D01*
X54940Y237167D01*
X54773Y237458D01*
X54690Y237750D01*
Y238042D01*
X54773Y238333D01*
X54898Y238583D01*
X55065Y238792D01*
G01X54690Y240767D02*
X55232Y240850D01*
X55690Y240975D01*
X56107Y241142D01*
X56565Y241350D01*
X57190Y241683D01*
Y240017D01*
G01X54690Y243950D02*
X54732Y244242D01*
X54857Y244575D01*
X55065Y244783D01*
X55357Y244867D01*
X55648Y244783D01*
X55898Y244533D01*
X56023Y244158D01*
Y243742D01*
X56107Y243492D01*
X56315Y243283D01*
X56607Y243200D01*
X56898Y243325D01*
X57107Y243617D01*
X57190Y243950D01*
X57107Y244283D01*
X56898Y244575D01*
X56607Y244700D01*
X56315Y244617D01*
X56107Y244408D01*
X56023Y244158D01*
Y243742D01*
X55898Y243367D01*
X55648Y243117D01*
X55357Y243033D01*
X55065Y243117D01*
X54857Y243325D01*
X54732Y243658D01*
X54690Y243950D01*
G01X53482Y238667D02*
X53607Y238417D01*
X53690Y238125D01*
Y237792D01*
X53565Y237417D01*
X53357Y237125D01*
X53107Y236917D01*
X52690Y236750D01*
X52315Y236708D01*
X51940Y236792D01*
X51690Y236917D01*
X51440Y237167D01*
X51273Y237458D01*
X51190Y237750D01*
Y238042D01*
X51273Y238333D01*
X51398Y238583D01*
X51565Y238792D01*
G01X51190Y240767D02*
X51732Y240850D01*
X52190Y240975D01*
X52607Y241142D01*
X53065Y241350D01*
X53690Y241683D01*
Y240017D01*
G01X51190Y243867D02*
X51732Y243950D01*
X52190Y244075D01*
X52607Y244242D01*
X53065Y244450D01*
X53690Y244783D01*
Y243117D01*
G01X60982Y238667D02*
X61107Y238417D01*
X61190Y238125D01*
Y237792D01*
X61065Y237417D01*
X60857Y237125D01*
X60607Y236917D01*
X60190Y236750D01*
X59815Y236708D01*
X59440Y236792D01*
X59190Y236917D01*
X58940Y237167D01*
X58773Y237458D01*
X58690Y237750D01*
Y238042D01*
X58773Y238333D01*
X58898Y238583D01*
X59065Y238792D01*
G01X58690Y240767D02*
X59232Y240850D01*
X59690Y240975D01*
X60107Y241142D01*
X60565Y241350D01*
X61190Y241683D01*
Y240017D01*
G01X59732Y243158D02*
X60023Y243450D01*
X60190Y243700D01*
X60273Y244033D01*
X60190Y244325D01*
X60023Y244533D01*
X59773Y244700D01*
X59482Y244742D01*
X59232Y244700D01*
X58982Y244533D01*
X58773Y244283D01*
X58690Y243992D01*
X58773Y243658D01*
X59023Y243367D01*
X59398Y243200D01*
X59815Y243158D01*
X60357Y243242D01*
X60648Y243367D01*
X60940Y243575D01*
X61148Y243867D01*
X61190Y244158D01*
X61107Y244450D01*
X60898Y244658D01*
G01X64682Y238767D02*
X64807Y238517D01*
X64890Y238225D01*
Y237892D01*
X64765Y237517D01*
X64557Y237225D01*
X64307Y237017D01*
X63890Y236850D01*
X63515Y236808D01*
X63140Y236892D01*
X62890Y237017D01*
X62640Y237267D01*
X62473Y237558D01*
X62390Y237850D01*
Y238142D01*
X62473Y238433D01*
X62598Y238683D01*
X62765Y238892D01*
G01X62390Y240867D02*
X62932Y240950D01*
X63390Y241075D01*
X63807Y241242D01*
X64265Y241450D01*
X64890Y241783D01*
Y240117D01*
G01X62765Y243133D02*
X62557Y243383D01*
X62432Y243675D01*
X62390Y244050D01*
X62473Y244425D01*
X62640Y244717D01*
X62932Y244925D01*
X63265Y244967D01*
X63598Y244883D01*
X63807Y244675D01*
X63973Y244383D01*
X64015Y244092D01*
X63973Y243800D01*
X63807Y243425D01*
X64890Y243550D01*
Y244675D01*
G01X68982Y238767D02*
X69107Y238517D01*
X69190Y238225D01*
Y237892D01*
X69065Y237517D01*
X68857Y237225D01*
X68607Y237017D01*
X68190Y236850D01*
X67815Y236808D01*
X67440Y236892D01*
X67190Y237017D01*
X66940Y237267D01*
X66773Y237558D01*
X66690Y237850D01*
Y238142D01*
X66773Y238433D01*
X66898Y238683D01*
X67065Y238892D01*
G01X66690Y240867D02*
X67232Y240950D01*
X67690Y241075D01*
X68107Y241242D01*
X68565Y241450D01*
X69190Y241783D01*
Y240117D01*
G01X66690Y244550D02*
X69190D01*
X67398Y243008D01*
Y245092D01*
G01X76982Y238667D02*
X77107Y238417D01*
X77190Y238125D01*
Y237792D01*
X77065Y237417D01*
X76857Y237125D01*
X76607Y236917D01*
X76190Y236750D01*
X75815Y236708D01*
X75440Y236792D01*
X75190Y236917D01*
X74940Y237167D01*
X74773Y237458D01*
X74690Y237750D01*
Y238042D01*
X74773Y238333D01*
X74898Y238583D01*
X75065Y238792D01*
G01X74690Y240767D02*
X75232Y240850D01*
X75690Y240975D01*
X76107Y241142D01*
X76565Y241350D01*
X77190Y241683D01*
Y240017D01*
G01X75190Y243033D02*
X74898Y243283D01*
X74732Y243617D01*
X74690Y243992D01*
X74732Y244325D01*
X74940Y244658D01*
X75190Y244867D01*
X75440Y244908D01*
X75732Y244825D01*
X75940Y244533D01*
X76023Y244242D01*
Y243867D01*
G01Y244242D02*
X76148Y244492D01*
X76357Y244700D01*
X76607Y244783D01*
X76857Y244700D01*
X77065Y244492D01*
X77190Y244117D01*
X77148Y243742D01*
X76982Y243367D01*
G01X72682Y238767D02*
X72807Y238517D01*
X72890Y238225D01*
Y237892D01*
X72765Y237517D01*
X72557Y237225D01*
X72307Y237017D01*
X71890Y236850D01*
X71515Y236808D01*
X71140Y236892D01*
X70890Y237017D01*
X70640Y237267D01*
X70473Y237558D01*
X70390Y237850D01*
Y238142D01*
X70473Y238433D01*
X70598Y238683D01*
X70765Y238892D01*
G01X70390Y240867D02*
X70932Y240950D01*
X71390Y241075D01*
X71807Y241242D01*
X72265Y241450D01*
X72890Y241783D01*
Y240117D01*
G01X72473Y243258D02*
X72723Y243508D01*
X72848Y243800D01*
X72890Y244133D01*
X72807Y244550D01*
X72598Y244842D01*
X72348Y244925D01*
X72098Y244883D01*
X71890Y244717D01*
X71473Y243883D01*
X71182Y243508D01*
X70765Y243258D01*
X70390Y243175D01*
Y244925D01*
G01X46683Y211467D02*
Y213967D01*
X45683D01*
X45350Y213842D01*
X45100Y213550D01*
X45017Y213217D01*
X45100Y212884D01*
X45308Y212634D01*
X45683Y212509D01*
X46683D01*
G01X42750Y211467D02*
Y213967D01*
X43250Y213467D01*
G01Y211467D02*
X42250D01*
G01X18433Y266733D02*
X17900Y267083D01*
X17500Y267667D01*
X17233Y268483D01*
X17500Y269183D01*
X18033Y269650D01*
X18967Y270000D01*
X22567D01*
Y263000D01*
X18167D01*
X17233Y263467D01*
X16700Y264167D01*
X16433Y264983D01*
X16700Y265800D01*
X17500Y266500D01*
X18433Y266733D01*
X22567D01*
G01X45733Y267292D02*
X45983Y267417D01*
X46275Y267500D01*
X46608D01*
X46983Y267375D01*
X47275Y267167D01*
X47483Y266917D01*
X47650Y266500D01*
X47692Y266125D01*
X47608Y265750D01*
X47483Y265500D01*
X47233Y265250D01*
X46942Y265083D01*
X46650Y265000D01*
X46358D01*
X46067Y265083D01*
X45817Y265208D01*
X45608Y265375D01*
G01X44342Y267083D02*
X44092Y267333D01*
X43800Y267458D01*
X43467Y267500D01*
X43050Y267417D01*
X42758Y267208D01*
X42675Y266958D01*
X42717Y266708D01*
X42883Y266500D01*
X43717Y266083D01*
X44092Y265792D01*
X44342Y265375D01*
X44425Y265000D01*
X42675D01*
G01X41158Y265292D02*
X40867Y265083D01*
X40533Y265000D01*
X40200Y265083D01*
X39908Y265333D01*
X39700Y265708D01*
X39617Y266083D01*
Y266542D01*
X39700Y266917D01*
X39908Y267250D01*
X40158Y267417D01*
X40450Y267500D01*
X40783Y267417D01*
X41033Y267250D01*
X41200Y267000D01*
X41283Y266667D01*
X41200Y266375D01*
X40992Y266083D01*
X40742Y265917D01*
X40450Y265875D01*
X40117Y265958D01*
X39867Y266167D01*
X39617Y266542D01*
G01X36850Y265000D02*
Y267500D01*
X38392Y265708D01*
X36308D01*
G01X45733Y271792D02*
X45983Y271917D01*
X46275Y272000D01*
X46608D01*
X46983Y271875D01*
X47275Y271667D01*
X47483Y271417D01*
X47650Y271000D01*
X47692Y270625D01*
X47608Y270250D01*
X47483Y270000D01*
X47233Y269750D01*
X46942Y269583D01*
X46650Y269500D01*
X46358D01*
X46067Y269583D01*
X45817Y269708D01*
X45608Y269875D01*
G01X44342Y271583D02*
X44092Y271833D01*
X43800Y271958D01*
X43467Y272000D01*
X43050Y271917D01*
X42758Y271708D01*
X42675Y271458D01*
X42717Y271208D01*
X42883Y271000D01*
X43717Y270583D01*
X44092Y270292D01*
X44342Y269875D01*
X44425Y269500D01*
X42675D01*
G01X41367Y269875D02*
X41117Y269667D01*
X40825Y269542D01*
X40450Y269500D01*
X40075Y269583D01*
X39783Y269750D01*
X39575Y270042D01*
X39533Y270375D01*
X39617Y270708D01*
X39825Y270917D01*
X40117Y271083D01*
X40408Y271125D01*
X40700Y271083D01*
X41075Y270917D01*
X40950Y272000D01*
X39825D01*
G01X37350D02*
X37683Y271917D01*
X37933Y271708D01*
X38100Y271458D01*
X38225Y271125D01*
X38267Y270750D01*
X38225Y270375D01*
X38100Y270042D01*
X37933Y269792D01*
X37683Y269583D01*
X37350Y269500D01*
X37017Y269583D01*
X36767Y269792D01*
X36600Y270042D01*
X36475Y270375D01*
X36433Y270750D01*
X36475Y271125D01*
X36600Y271458D01*
X36767Y271708D01*
X37017Y271917D01*
X37350Y272000D01*
G01X64292Y280767D02*
X64417Y280517D01*
X64500Y280225D01*
Y279892D01*
X64375Y279517D01*
X64167Y279225D01*
X63917Y279017D01*
X63500Y278850D01*
X63125Y278808D01*
X62750Y278892D01*
X62500Y279017D01*
X62250Y279267D01*
X62083Y279558D01*
X62000Y279850D01*
Y280142D01*
X62083Y280433D01*
X62208Y280683D01*
X62375Y280892D01*
G01X62000Y282950D02*
X64500D01*
X64000Y282450D01*
G01X62000D02*
Y283450D01*
G01X64083Y285258D02*
X64333Y285508D01*
X64458Y285800D01*
X64500Y286133D01*
X64417Y286550D01*
X64208Y286842D01*
X63958Y286925D01*
X63708Y286883D01*
X63500Y286717D01*
X63083Y285883D01*
X62792Y285508D01*
X62375Y285258D01*
X62000Y285175D01*
Y286925D01*
G01X62292Y288442D02*
X62083Y288733D01*
X62000Y289067D01*
X62083Y289400D01*
X62333Y289692D01*
X62708Y289900D01*
X63083Y289983D01*
X63542D01*
X63917Y289900D01*
X64250Y289692D01*
X64417Y289442D01*
X64500Y289150D01*
X64417Y288817D01*
X64250Y288567D01*
X64000Y288400D01*
X63667Y288317D01*
X63375Y288400D01*
X63083Y288608D01*
X62917Y288858D01*
X62875Y289150D01*
X62958Y289483D01*
X63167Y289733D01*
X63542Y289983D01*
G01X45292Y253767D02*
X45417Y253517D01*
X45500Y253225D01*
Y252892D01*
X45375Y252517D01*
X45167Y252225D01*
X44917Y252017D01*
X44500Y251850D01*
X44125Y251808D01*
X43750Y251892D01*
X43500Y252017D01*
X43250Y252267D01*
X43083Y252558D01*
X43000Y252850D01*
Y253142D01*
X43083Y253433D01*
X43208Y253683D01*
X43375Y253892D01*
G01Y255033D02*
X43167Y255283D01*
X43042Y255575D01*
X43000Y255950D01*
X43083Y256325D01*
X43250Y256617D01*
X43542Y256825D01*
X43875Y256867D01*
X44208Y256783D01*
X44417Y256575D01*
X44583Y256283D01*
X44625Y255992D01*
X44583Y255700D01*
X44417Y255325D01*
X45500Y255450D01*
Y256575D01*
G01X43000Y259050D02*
X43042Y259342D01*
X43167Y259675D01*
X43375Y259883D01*
X43667Y259967D01*
X43958Y259883D01*
X44208Y259633D01*
X44333Y259258D01*
Y258842D01*
X44417Y258592D01*
X44625Y258383D01*
X44917Y258300D01*
X45208Y258425D01*
X45417Y258717D01*
X45500Y259050D01*
X45417Y259383D01*
X45208Y259675D01*
X44917Y259800D01*
X44625Y259717D01*
X44417Y259508D01*
X44333Y259258D01*
Y258842D01*
X44208Y258467D01*
X43958Y258217D01*
X43667Y258133D01*
X43375Y258217D01*
X43167Y258425D01*
X43042Y258758D01*
X43000Y259050D01*
G01Y262150D02*
X45500D01*
X45000Y261650D01*
G01X43000D02*
Y262650D01*
G01X63032Y253817D02*
X63157Y253567D01*
X63240Y253275D01*
Y252942D01*
X63115Y252567D01*
X62907Y252275D01*
X62657Y252067D01*
X62240Y251900D01*
X61865Y251858D01*
X61490Y251942D01*
X61240Y252067D01*
X60990Y252317D01*
X60823Y252608D01*
X60740Y252900D01*
Y253192D01*
X60823Y253483D01*
X60948Y253733D01*
X61115Y253942D01*
G01Y255083D02*
X60907Y255333D01*
X60782Y255625D01*
X60740Y256000D01*
X60823Y256375D01*
X60990Y256667D01*
X61282Y256875D01*
X61615Y256917D01*
X61948Y256833D01*
X62157Y256625D01*
X62323Y256333D01*
X62365Y256042D01*
X62323Y255750D01*
X62157Y255375D01*
X63240Y255500D01*
Y256625D01*
G01X60740Y259100D02*
X60782Y259392D01*
X60907Y259725D01*
X61115Y259933D01*
X61407Y260017D01*
X61698Y259933D01*
X61948Y259683D01*
X62073Y259308D01*
Y258892D01*
X62157Y258642D01*
X62365Y258433D01*
X62657Y258350D01*
X62948Y258475D01*
X63157Y258767D01*
X63240Y259100D01*
X63157Y259433D01*
X62948Y259725D01*
X62657Y259850D01*
X62365Y259767D01*
X62157Y259558D01*
X62073Y259308D01*
Y258892D01*
X61948Y258517D01*
X61698Y258267D01*
X61407Y258183D01*
X61115Y258267D01*
X60907Y258475D01*
X60782Y258808D01*
X60740Y259100D01*
G01X63240Y262200D02*
X63157Y261867D01*
X62948Y261617D01*
X62698Y261450D01*
X62365Y261325D01*
X61990Y261283D01*
X61615Y261325D01*
X61282Y261450D01*
X61032Y261617D01*
X60823Y261867D01*
X60740Y262200D01*
X60823Y262533D01*
X61032Y262783D01*
X61282Y262950D01*
X61615Y263075D01*
X61990Y263117D01*
X62365Y263075D01*
X62698Y262950D01*
X62948Y262783D01*
X63157Y262533D01*
X63240Y262200D01*
G01X57582Y253817D02*
X57707Y253567D01*
X57790Y253275D01*
Y252942D01*
X57665Y252567D01*
X57457Y252275D01*
X57207Y252067D01*
X56790Y251900D01*
X56415Y251858D01*
X56040Y251942D01*
X55790Y252067D01*
X55540Y252317D01*
X55373Y252608D01*
X55290Y252900D01*
Y253192D01*
X55373Y253483D01*
X55498Y253733D01*
X55665Y253942D01*
G01Y255083D02*
X55457Y255333D01*
X55332Y255625D01*
X55290Y256000D01*
X55373Y256375D01*
X55540Y256667D01*
X55832Y256875D01*
X56165Y256917D01*
X56498Y256833D01*
X56707Y256625D01*
X56873Y256333D01*
X56915Y256042D01*
X56873Y255750D01*
X56707Y255375D01*
X57790Y255500D01*
Y256625D01*
G01X55290Y259017D02*
X55832Y259100D01*
X56290Y259225D01*
X56707Y259392D01*
X57165Y259600D01*
X57790Y259933D01*
Y258267D01*
G01X55582Y261492D02*
X55373Y261783D01*
X55290Y262117D01*
X55373Y262450D01*
X55623Y262742D01*
X55998Y262950D01*
X56373Y263033D01*
X56832D01*
X57207Y262950D01*
X57540Y262742D01*
X57707Y262492D01*
X57790Y262200D01*
X57707Y261867D01*
X57540Y261617D01*
X57290Y261450D01*
X56957Y261367D01*
X56665Y261450D01*
X56373Y261658D01*
X56207Y261908D01*
X56165Y262200D01*
X56248Y262533D01*
X56457Y262783D01*
X56832Y263033D01*
G01X66632Y253817D02*
X66757Y253567D01*
X66840Y253275D01*
Y252942D01*
X66715Y252567D01*
X66507Y252275D01*
X66257Y252067D01*
X65840Y251900D01*
X65465Y251858D01*
X65090Y251942D01*
X64840Y252067D01*
X64590Y252317D01*
X64423Y252608D01*
X64340Y252900D01*
Y253192D01*
X64423Y253483D01*
X64548Y253733D01*
X64715Y253942D01*
G01Y255083D02*
X64507Y255333D01*
X64382Y255625D01*
X64340Y256000D01*
X64423Y256375D01*
X64590Y256667D01*
X64882Y256875D01*
X65215Y256917D01*
X65548Y256833D01*
X65757Y256625D01*
X65923Y256333D01*
X65965Y256042D01*
X65923Y255750D01*
X65757Y255375D01*
X66840Y255500D01*
Y256625D01*
G01X64340Y259600D02*
X66840D01*
X65048Y258058D01*
Y260142D01*
G01X66840Y262200D02*
X66757Y261867D01*
X66548Y261617D01*
X66298Y261450D01*
X65965Y261325D01*
X65590Y261283D01*
X65215Y261325D01*
X64882Y261450D01*
X64632Y261617D01*
X64423Y261867D01*
X64340Y262200D01*
X64423Y262533D01*
X64632Y262783D01*
X64882Y262950D01*
X65215Y263075D01*
X65590Y263117D01*
X65965Y263075D01*
X66298Y262950D01*
X66548Y262783D01*
X66757Y262533D01*
X66840Y262200D01*
G01X64292Y266267D02*
X64417Y266017D01*
X64500Y265725D01*
Y265392D01*
X64375Y265017D01*
X64167Y264725D01*
X63917Y264517D01*
X63500Y264350D01*
X63125Y264308D01*
X62750Y264392D01*
X62500Y264517D01*
X62250Y264767D01*
X62083Y265058D01*
X62000Y265350D01*
Y265642D01*
X62083Y265933D01*
X62208Y266183D01*
X62375Y266392D01*
G01Y267533D02*
X62167Y267783D01*
X62042Y268075D01*
X62000Y268450D01*
X62083Y268825D01*
X62250Y269117D01*
X62542Y269325D01*
X62875Y269367D01*
X63208Y269283D01*
X63417Y269075D01*
X63583Y268783D01*
X63625Y268492D01*
X63583Y268200D01*
X63417Y267825D01*
X64500Y267950D01*
Y269075D01*
G01X62500Y270633D02*
X62208Y270883D01*
X62042Y271217D01*
X62000Y271592D01*
X62042Y271925D01*
X62250Y272258D01*
X62500Y272467D01*
X62750Y272508D01*
X63042Y272425D01*
X63250Y272133D01*
X63333Y271842D01*
Y271467D01*
G01Y271842D02*
X63458Y272092D01*
X63667Y272300D01*
X63917Y272383D01*
X64167Y272300D01*
X64375Y272092D01*
X64500Y271717D01*
X64458Y271342D01*
X64292Y270967D01*
G01X62292Y273942D02*
X62083Y274233D01*
X62000Y274567D01*
X62083Y274900D01*
X62333Y275192D01*
X62708Y275400D01*
X63083Y275483D01*
X63542D01*
X63917Y275400D01*
X64250Y275192D01*
X64417Y274942D01*
X64500Y274650D01*
X64417Y274317D01*
X64250Y274067D01*
X64000Y273900D01*
X63667Y273817D01*
X63375Y273900D01*
X63083Y274108D01*
X62917Y274358D01*
X62875Y274650D01*
X62958Y274983D01*
X63167Y275233D01*
X63542Y275483D01*
G01X75582Y253817D02*
X75707Y253567D01*
X75790Y253275D01*
Y252942D01*
X75665Y252567D01*
X75457Y252275D01*
X75207Y252067D01*
X74790Y251900D01*
X74415Y251858D01*
X74040Y251942D01*
X73790Y252067D01*
X73540Y252317D01*
X73373Y252608D01*
X73290Y252900D01*
Y253192D01*
X73373Y253483D01*
X73498Y253733D01*
X73665Y253942D01*
G01Y255083D02*
X73457Y255333D01*
X73332Y255625D01*
X73290Y256000D01*
X73373Y256375D01*
X73540Y256667D01*
X73832Y256875D01*
X74165Y256917D01*
X74498Y256833D01*
X74707Y256625D01*
X74873Y256333D01*
X74915Y256042D01*
X74873Y255750D01*
X74707Y255375D01*
X75790Y255500D01*
Y256625D01*
G01X73790Y258183D02*
X73498Y258433D01*
X73332Y258767D01*
X73290Y259142D01*
X73332Y259475D01*
X73540Y259808D01*
X73790Y260017D01*
X74040Y260058D01*
X74332Y259975D01*
X74540Y259683D01*
X74623Y259392D01*
Y259017D01*
G01Y259392D02*
X74748Y259642D01*
X74957Y259850D01*
X75207Y259933D01*
X75457Y259850D01*
X75665Y259642D01*
X75790Y259267D01*
X75748Y258892D01*
X75582Y258517D01*
G01X73290Y262200D02*
X73332Y262492D01*
X73457Y262825D01*
X73665Y263033D01*
X73957Y263117D01*
X74248Y263033D01*
X74498Y262783D01*
X74623Y262408D01*
Y261992D01*
X74707Y261742D01*
X74915Y261533D01*
X75207Y261450D01*
X75498Y261575D01*
X75707Y261867D01*
X75790Y262200D01*
X75707Y262533D01*
X75498Y262825D01*
X75207Y262950D01*
X74915Y262867D01*
X74707Y262658D01*
X74623Y262408D01*
Y261992D01*
X74498Y261617D01*
X74248Y261367D01*
X73957Y261283D01*
X73665Y261367D01*
X73457Y261575D01*
X73332Y261908D01*
X73290Y262200D01*
G01X56292Y266267D02*
X56417Y266017D01*
X56500Y265725D01*
Y265392D01*
X56375Y265017D01*
X56167Y264725D01*
X55917Y264517D01*
X55500Y264350D01*
X55125Y264308D01*
X54750Y264392D01*
X54500Y264517D01*
X54250Y264767D01*
X54083Y265058D01*
X54000Y265350D01*
Y265642D01*
X54083Y265933D01*
X54208Y266183D01*
X54375Y266392D01*
G01Y267533D02*
X54167Y267783D01*
X54042Y268075D01*
X54000Y268450D01*
X54083Y268825D01*
X54250Y269117D01*
X54542Y269325D01*
X54875Y269367D01*
X55208Y269283D01*
X55417Y269075D01*
X55583Y268783D01*
X55625Y268492D01*
X55583Y268200D01*
X55417Y267825D01*
X56500Y267950D01*
Y269075D01*
G01X54500Y270633D02*
X54208Y270883D01*
X54042Y271217D01*
X54000Y271592D01*
X54042Y271925D01*
X54250Y272258D01*
X54500Y272467D01*
X54750Y272508D01*
X55042Y272425D01*
X55250Y272133D01*
X55333Y271842D01*
Y271467D01*
G01Y271842D02*
X55458Y272092D01*
X55667Y272300D01*
X55917Y272383D01*
X56167Y272300D01*
X56375Y272092D01*
X56500Y271717D01*
X56458Y271342D01*
X56292Y270967D01*
G01X54000Y274567D02*
X54542Y274650D01*
X55000Y274775D01*
X55417Y274942D01*
X55875Y275150D01*
X56500Y275483D01*
Y273817D01*
G01X72292Y266267D02*
X72417Y266017D01*
X72500Y265725D01*
Y265392D01*
X72375Y265017D01*
X72167Y264725D01*
X71917Y264517D01*
X71500Y264350D01*
X71125Y264308D01*
X70750Y264392D01*
X70500Y264517D01*
X70250Y264767D01*
X70083Y265058D01*
X70000Y265350D01*
Y265642D01*
X70083Y265933D01*
X70208Y266183D01*
X70375Y266392D01*
G01X72083Y267658D02*
X72333Y267908D01*
X72458Y268200D01*
X72500Y268533D01*
X72417Y268950D01*
X72208Y269242D01*
X71958Y269325D01*
X71708Y269283D01*
X71500Y269117D01*
X71083Y268283D01*
X70792Y267908D01*
X70375Y267658D01*
X70000Y267575D01*
Y269325D01*
G01Y271550D02*
X70042Y271842D01*
X70167Y272175D01*
X70375Y272383D01*
X70667Y272467D01*
X70958Y272383D01*
X71208Y272133D01*
X71333Y271758D01*
Y271342D01*
X71417Y271092D01*
X71625Y270883D01*
X71917Y270800D01*
X72208Y270925D01*
X72417Y271217D01*
X72500Y271550D01*
X72417Y271883D01*
X72208Y272175D01*
X71917Y272300D01*
X71625Y272217D01*
X71417Y272008D01*
X71333Y271758D01*
Y271342D01*
X71208Y270967D01*
X70958Y270717D01*
X70667Y270633D01*
X70375Y270717D01*
X70167Y270925D01*
X70042Y271258D01*
X70000Y271550D01*
G01Y275150D02*
X72500D01*
X70708Y273608D01*
Y275692D01*
G01X53982Y253817D02*
X54107Y253567D01*
X54190Y253275D01*
Y252942D01*
X54065Y252567D01*
X53857Y252275D01*
X53607Y252067D01*
X53190Y251900D01*
X52815Y251858D01*
X52440Y251942D01*
X52190Y252067D01*
X51940Y252317D01*
X51773Y252608D01*
X51690Y252900D01*
Y253192D01*
X51773Y253483D01*
X51898Y253733D01*
X52065Y253942D01*
G01X53773Y255208D02*
X54023Y255458D01*
X54148Y255750D01*
X54190Y256083D01*
X54107Y256500D01*
X53898Y256792D01*
X53648Y256875D01*
X53398Y256833D01*
X53190Y256667D01*
X52773Y255833D01*
X52482Y255458D01*
X52065Y255208D01*
X51690Y255125D01*
Y256875D01*
G01X52732Y258308D02*
X53023Y258600D01*
X53190Y258850D01*
X53273Y259183D01*
X53190Y259475D01*
X53023Y259683D01*
X52773Y259850D01*
X52482Y259892D01*
X52232Y259850D01*
X51982Y259683D01*
X51773Y259433D01*
X51690Y259142D01*
X51773Y258808D01*
X52023Y258517D01*
X52398Y258350D01*
X52815Y258308D01*
X53357Y258392D01*
X53648Y258517D01*
X53940Y258725D01*
X54148Y259017D01*
X54190Y259308D01*
X54107Y259600D01*
X53898Y259808D01*
G01X51690Y262200D02*
X54190D01*
X53690Y261700D01*
G01X51690D02*
Y262700D01*
G01X49482Y253817D02*
X49607Y253567D01*
X49690Y253275D01*
Y252942D01*
X49565Y252567D01*
X49357Y252275D01*
X49107Y252067D01*
X48690Y251900D01*
X48315Y251858D01*
X47940Y251942D01*
X47690Y252067D01*
X47440Y252317D01*
X47273Y252608D01*
X47190Y252900D01*
Y253192D01*
X47273Y253483D01*
X47398Y253733D01*
X47565Y253942D01*
G01X49273Y255208D02*
X49523Y255458D01*
X49648Y255750D01*
X49690Y256083D01*
X49607Y256500D01*
X49398Y256792D01*
X49148Y256875D01*
X48898Y256833D01*
X48690Y256667D01*
X48273Y255833D01*
X47982Y255458D01*
X47565Y255208D01*
X47190Y255125D01*
Y256875D01*
G01X47565Y258183D02*
X47357Y258433D01*
X47232Y258725D01*
X47190Y259100D01*
X47273Y259475D01*
X47440Y259767D01*
X47732Y259975D01*
X48065Y260017D01*
X48398Y259933D01*
X48607Y259725D01*
X48773Y259433D01*
X48815Y259142D01*
X48773Y258850D01*
X48607Y258475D01*
X49690Y258600D01*
Y259725D01*
G01X47690Y261283D02*
X47398Y261533D01*
X47232Y261867D01*
X47190Y262242D01*
X47232Y262575D01*
X47440Y262908D01*
X47690Y263117D01*
X47940Y263158D01*
X48232Y263075D01*
X48440Y262783D01*
X48523Y262492D01*
Y262117D01*
G01Y262492D02*
X48648Y262742D01*
X48857Y262950D01*
X49107Y263033D01*
X49357Y262950D01*
X49565Y262742D01*
X49690Y262367D01*
X49648Y261992D01*
X49482Y261617D01*
G01X68292Y266267D02*
X68417Y266017D01*
X68500Y265725D01*
Y265392D01*
X68375Y265017D01*
X68167Y264725D01*
X67917Y264517D01*
X67500Y264350D01*
X67125Y264308D01*
X66750Y264392D01*
X66500Y264517D01*
X66250Y264767D01*
X66083Y265058D01*
X66000Y265350D01*
Y265642D01*
X66083Y265933D01*
X66208Y266183D01*
X66375Y266392D01*
G01X68083Y267658D02*
X68333Y267908D01*
X68458Y268200D01*
X68500Y268533D01*
X68417Y268950D01*
X68208Y269242D01*
X67958Y269325D01*
X67708Y269283D01*
X67500Y269117D01*
X67083Y268283D01*
X66792Y267908D01*
X66375Y267658D01*
X66000Y267575D01*
Y269325D01*
G01Y272050D02*
X68500D01*
X66708Y270508D01*
Y272592D01*
G01X66000Y274567D02*
X66542Y274650D01*
X67000Y274775D01*
X67417Y274942D01*
X67875Y275150D01*
X68500Y275483D01*
Y273817D01*
G01X60292Y266267D02*
X60417Y266017D01*
X60500Y265725D01*
Y265392D01*
X60375Y265017D01*
X60167Y264725D01*
X59917Y264517D01*
X59500Y264350D01*
X59125Y264308D01*
X58750Y264392D01*
X58500Y264517D01*
X58250Y264767D01*
X58083Y265058D01*
X58000Y265350D01*
Y265642D01*
X58083Y265933D01*
X58208Y266183D01*
X58375Y266392D01*
G01X60083Y267658D02*
X60333Y267908D01*
X60458Y268200D01*
X60500Y268533D01*
X60417Y268950D01*
X60208Y269242D01*
X59958Y269325D01*
X59708Y269283D01*
X59500Y269117D01*
X59083Y268283D01*
X58792Y267908D01*
X58375Y267658D01*
X58000Y267575D01*
Y269325D01*
G01Y272050D02*
X60500D01*
X58708Y270508D01*
Y272592D01*
G01X60500Y274650D02*
X60417Y274317D01*
X60208Y274067D01*
X59958Y273900D01*
X59625Y273775D01*
X59250Y273733D01*
X58875Y273775D01*
X58542Y273900D01*
X58292Y274067D01*
X58083Y274317D01*
X58000Y274650D01*
X58083Y274983D01*
X58292Y275233D01*
X58542Y275400D01*
X58875Y275525D01*
X59250Y275567D01*
X59625Y275525D01*
X59958Y275400D01*
X60208Y275233D01*
X60417Y274983D01*
X60500Y274650D01*
G01X52792Y266267D02*
X52917Y266017D01*
X53000Y265725D01*
Y265392D01*
X52875Y265017D01*
X52667Y264725D01*
X52417Y264517D01*
X52000Y264350D01*
X51625Y264308D01*
X51250Y264392D01*
X51000Y264517D01*
X50750Y264767D01*
X50583Y265058D01*
X50500Y265350D01*
Y265642D01*
X50583Y265933D01*
X50708Y266183D01*
X50875Y266392D01*
G01X52583Y267658D02*
X52833Y267908D01*
X52958Y268200D01*
X53000Y268533D01*
X52917Y268950D01*
X52708Y269242D01*
X52458Y269325D01*
X52208Y269283D01*
X52000Y269117D01*
X51583Y268283D01*
X51292Y267908D01*
X50875Y267658D01*
X50500Y267575D01*
Y269325D01*
G01X51000Y270633D02*
X50708Y270883D01*
X50542Y271217D01*
X50500Y271592D01*
X50542Y271925D01*
X50750Y272258D01*
X51000Y272467D01*
X51250Y272508D01*
X51542Y272425D01*
X51750Y272133D01*
X51833Y271842D01*
Y271467D01*
G01Y271842D02*
X51958Y272092D01*
X52167Y272300D01*
X52417Y272383D01*
X52667Y272300D01*
X52875Y272092D01*
X53000Y271717D01*
X52958Y271342D01*
X52792Y270967D01*
G01X50792Y273942D02*
X50583Y274233D01*
X50500Y274567D01*
X50583Y274900D01*
X50833Y275192D01*
X51208Y275400D01*
X51583Y275483D01*
X52042D01*
X52417Y275400D01*
X52750Y275192D01*
X52917Y274942D01*
X53000Y274650D01*
X52917Y274317D01*
X52750Y274067D01*
X52500Y273900D01*
X52167Y273817D01*
X51875Y273900D01*
X51583Y274108D01*
X51417Y274358D01*
X51375Y274650D01*
X51458Y274983D01*
X51667Y275233D01*
X52042Y275483D01*
G01X76292Y266267D02*
X76417Y266017D01*
X76500Y265725D01*
Y265392D01*
X76375Y265017D01*
X76167Y264725D01*
X75917Y264517D01*
X75500Y264350D01*
X75125Y264308D01*
X74750Y264392D01*
X74500Y264517D01*
X74250Y264767D01*
X74083Y265058D01*
X74000Y265350D01*
Y265642D01*
X74083Y265933D01*
X74208Y266183D01*
X74375Y266392D01*
G01X76083Y267658D02*
X76333Y267908D01*
X76458Y268200D01*
X76500Y268533D01*
X76417Y268950D01*
X76208Y269242D01*
X75958Y269325D01*
X75708Y269283D01*
X75500Y269117D01*
X75083Y268283D01*
X74792Y267908D01*
X74375Y267658D01*
X74000Y267575D01*
Y269325D01*
G01X74500Y270633D02*
X74208Y270883D01*
X74042Y271217D01*
X74000Y271592D01*
X74042Y271925D01*
X74250Y272258D01*
X74500Y272467D01*
X74750Y272508D01*
X75042Y272425D01*
X75250Y272133D01*
X75333Y271842D01*
Y271467D01*
G01Y271842D02*
X75458Y272092D01*
X75667Y272300D01*
X75917Y272383D01*
X76167Y272300D01*
X76375Y272092D01*
X76500Y271717D01*
X76458Y271342D01*
X76292Y270967D01*
G01X74000Y274567D02*
X74542Y274650D01*
X75000Y274775D01*
X75417Y274942D01*
X75875Y275150D01*
X76500Y275483D01*
Y273817D01*
G01X71982Y253817D02*
X72107Y253567D01*
X72190Y253275D01*
Y252942D01*
X72065Y252567D01*
X71857Y252275D01*
X71607Y252067D01*
X71190Y251900D01*
X70815Y251858D01*
X70440Y251942D01*
X70190Y252067D01*
X69940Y252317D01*
X69773Y252608D01*
X69690Y252900D01*
Y253192D01*
X69773Y253483D01*
X69898Y253733D01*
X70065Y253942D01*
G01X71773Y255208D02*
X72023Y255458D01*
X72148Y255750D01*
X72190Y256083D01*
X72107Y256500D01*
X71898Y256792D01*
X71648Y256875D01*
X71398Y256833D01*
X71190Y256667D01*
X70773Y255833D01*
X70482Y255458D01*
X70065Y255208D01*
X69690Y255125D01*
Y256875D01*
G01X70190Y258183D02*
X69898Y258433D01*
X69732Y258767D01*
X69690Y259142D01*
X69732Y259475D01*
X69940Y259808D01*
X70190Y260017D01*
X70440Y260058D01*
X70732Y259975D01*
X70940Y259683D01*
X71023Y259392D01*
Y259017D01*
G01Y259392D02*
X71148Y259642D01*
X71357Y259850D01*
X71607Y259933D01*
X71857Y259850D01*
X72065Y259642D01*
X72190Y259267D01*
X72148Y258892D01*
X71982Y258517D01*
G01X69690Y262200D02*
X72190D01*
X71690Y261700D01*
G01X69690D02*
Y262700D01*
G01X72432Y297467D02*
X72557Y297217D01*
X72640Y296925D01*
Y296592D01*
X72515Y296217D01*
X72307Y295925D01*
X72057Y295717D01*
X71640Y295550D01*
X71265Y295508D01*
X70890Y295592D01*
X70640Y295717D01*
X70390Y295967D01*
X70223Y296258D01*
X70140Y296550D01*
Y296842D01*
X70223Y297133D01*
X70348Y297383D01*
X70515Y297592D01*
G01X70140Y299650D02*
X72640D01*
X72140Y299150D01*
G01X70140D02*
Y300150D01*
G01Y302667D02*
X70682Y302750D01*
X71140Y302875D01*
X71557Y303042D01*
X72015Y303250D01*
X72640Y303583D01*
Y301917D01*
G01X70515Y304933D02*
X70307Y305183D01*
X70182Y305475D01*
X70140Y305850D01*
X70223Y306225D01*
X70390Y306517D01*
X70682Y306725D01*
X71015Y306767D01*
X71348Y306683D01*
X71557Y306475D01*
X71723Y306183D01*
X71765Y305892D01*
X71723Y305600D01*
X71557Y305225D01*
X72640Y305350D01*
Y306475D01*
G01X64482Y297467D02*
X64607Y297217D01*
X64690Y296925D01*
Y296592D01*
X64565Y296217D01*
X64357Y295925D01*
X64107Y295717D01*
X63690Y295550D01*
X63315Y295508D01*
X62940Y295592D01*
X62690Y295717D01*
X62440Y295967D01*
X62273Y296258D01*
X62190Y296550D01*
Y296842D01*
X62273Y297133D01*
X62398Y297383D01*
X62565Y297592D01*
G01X62190Y299650D02*
X64690D01*
X64190Y299150D01*
G01X62190D02*
Y300150D01*
G01Y302667D02*
X62732Y302750D01*
X63190Y302875D01*
X63607Y303042D01*
X64065Y303250D01*
X64690Y303583D01*
Y301917D01*
G01Y305850D02*
X64607Y305517D01*
X64398Y305267D01*
X64148Y305100D01*
X63815Y304975D01*
X63440Y304933D01*
X63065Y304975D01*
X62732Y305100D01*
X62482Y305267D01*
X62273Y305517D01*
X62190Y305850D01*
X62273Y306183D01*
X62482Y306433D01*
X62732Y306600D01*
X63065Y306725D01*
X63440Y306767D01*
X63815Y306725D01*
X64148Y306600D01*
X64398Y306433D01*
X64607Y306183D01*
X64690Y305850D01*
G01X76432Y297467D02*
X76557Y297217D01*
X76640Y296925D01*
Y296592D01*
X76515Y296217D01*
X76307Y295925D01*
X76057Y295717D01*
X75640Y295550D01*
X75265Y295508D01*
X74890Y295592D01*
X74640Y295717D01*
X74390Y295967D01*
X74223Y296258D01*
X74140Y296550D01*
Y296842D01*
X74223Y297133D01*
X74348Y297383D01*
X74515Y297592D01*
G01X74140Y299650D02*
X76640D01*
X76140Y299150D01*
G01X74140D02*
Y300150D01*
G01X75182Y301958D02*
X75473Y302250D01*
X75640Y302500D01*
X75723Y302833D01*
X75640Y303125D01*
X75473Y303333D01*
X75223Y303500D01*
X74932Y303542D01*
X74682Y303500D01*
X74432Y303333D01*
X74223Y303083D01*
X74140Y302792D01*
X74223Y302458D01*
X74473Y302167D01*
X74848Y302000D01*
X75265Y301958D01*
X75807Y302042D01*
X76098Y302167D01*
X76390Y302375D01*
X76598Y302667D01*
X76640Y302958D01*
X76557Y303250D01*
X76348Y303458D01*
G01X74140Y306350D02*
X76640D01*
X74848Y304808D01*
Y306892D01*
G01X68482Y297467D02*
X68607Y297217D01*
X68690Y296925D01*
Y296592D01*
X68565Y296217D01*
X68357Y295925D01*
X68107Y295717D01*
X67690Y295550D01*
X67315Y295508D01*
X66940Y295592D01*
X66690Y295717D01*
X66440Y295967D01*
X66273Y296258D01*
X66190Y296550D01*
Y296842D01*
X66273Y297133D01*
X66398Y297383D01*
X66565Y297592D01*
G01X66190Y299650D02*
X68690D01*
X68190Y299150D01*
G01X66190D02*
Y300150D01*
G01X66565Y301833D02*
X66357Y302083D01*
X66232Y302375D01*
X66190Y302750D01*
X66273Y303125D01*
X66440Y303417D01*
X66732Y303625D01*
X67065Y303667D01*
X67398Y303583D01*
X67607Y303375D01*
X67773Y303083D01*
X67815Y302792D01*
X67773Y302500D01*
X67607Y302125D01*
X68690Y302250D01*
Y303375D01*
G01X66482Y305142D02*
X66273Y305433D01*
X66190Y305767D01*
X66273Y306100D01*
X66523Y306392D01*
X66898Y306600D01*
X67273Y306683D01*
X67732D01*
X68107Y306600D01*
X68440Y306392D01*
X68607Y306142D01*
X68690Y305850D01*
X68607Y305517D01*
X68440Y305267D01*
X68190Y305100D01*
X67857Y305017D01*
X67565Y305100D01*
X67273Y305308D01*
X67107Y305558D01*
X67065Y305850D01*
X67148Y306183D01*
X67357Y306433D01*
X67732Y306683D01*
G01X60292Y284767D02*
X60417Y284517D01*
X60500Y284225D01*
Y283892D01*
X60375Y283517D01*
X60167Y283225D01*
X59917Y283017D01*
X59500Y282850D01*
X59125Y282808D01*
X58750Y282892D01*
X58500Y283017D01*
X58250Y283267D01*
X58083Y283558D01*
X58000Y283850D01*
Y284142D01*
X58083Y284433D01*
X58208Y284683D01*
X58375Y284892D01*
G01X60083Y286158D02*
X60333Y286408D01*
X60458Y286700D01*
X60500Y287033D01*
X60417Y287450D01*
X60208Y287742D01*
X59958Y287825D01*
X59708Y287783D01*
X59500Y287617D01*
X59083Y286783D01*
X58792Y286408D01*
X58375Y286158D01*
X58000Y286075D01*
Y287825D01*
G01X60083Y289258D02*
X60333Y289508D01*
X60458Y289800D01*
X60500Y290133D01*
X60417Y290550D01*
X60208Y290842D01*
X59958Y290925D01*
X59708Y290883D01*
X59500Y290717D01*
X59083Y289883D01*
X58792Y289508D01*
X58375Y289258D01*
X58000Y289175D01*
Y290925D01*
G01Y293150D02*
X60500D01*
X60000Y292650D01*
G01X58000D02*
Y293650D01*
G01X76432Y279996D02*
X76557Y279746D01*
X76640Y279454D01*
Y279121D01*
X76515Y278746D01*
X76307Y278454D01*
X76057Y278246D01*
X75640Y278079D01*
X75265Y278037D01*
X74890Y278121D01*
X74640Y278246D01*
X74390Y278496D01*
X74223Y278787D01*
X74140Y279079D01*
Y279371D01*
X74223Y279662D01*
X74348Y279912D01*
X74515Y280121D01*
G01X76223Y281387D02*
X76473Y281637D01*
X76598Y281929D01*
X76640Y282262D01*
X76557Y282679D01*
X76348Y282971D01*
X76098Y283054D01*
X75848Y283012D01*
X75640Y282846D01*
X75223Y282012D01*
X74932Y281637D01*
X74515Y281387D01*
X74140Y281304D01*
Y283054D01*
G01X76223Y284487D02*
X76473Y284737D01*
X76598Y285029D01*
X76640Y285362D01*
X76557Y285779D01*
X76348Y286071D01*
X76098Y286154D01*
X75848Y286112D01*
X75640Y285946D01*
X75223Y285112D01*
X74932Y284737D01*
X74515Y284487D01*
X74140Y284404D01*
Y286154D01*
G01X74640Y287462D02*
X74348Y287712D01*
X74182Y288046D01*
X74140Y288421D01*
X74182Y288754D01*
X74390Y289087D01*
X74640Y289296D01*
X74890Y289337D01*
X75182Y289254D01*
X75390Y288962D01*
X75473Y288671D01*
Y288296D01*
G01Y288671D02*
X75598Y288921D01*
X75807Y289129D01*
X76057Y289212D01*
X76307Y289129D01*
X76515Y288921D01*
X76640Y288546D01*
X76598Y288171D01*
X76432Y287796D01*
G01X72482Y279996D02*
X72607Y279746D01*
X72690Y279454D01*
Y279121D01*
X72565Y278746D01*
X72357Y278454D01*
X72107Y278246D01*
X71690Y278079D01*
X71315Y278037D01*
X70940Y278121D01*
X70690Y278246D01*
X70440Y278496D01*
X70273Y278787D01*
X70190Y279079D01*
Y279371D01*
X70273Y279662D01*
X70398Y279912D01*
X70565Y280121D01*
G01X72273Y281387D02*
X72523Y281637D01*
X72648Y281929D01*
X72690Y282262D01*
X72607Y282679D01*
X72398Y282971D01*
X72148Y283054D01*
X71898Y283012D01*
X71690Y282846D01*
X71273Y282012D01*
X70982Y281637D01*
X70565Y281387D01*
X70190Y281304D01*
Y283054D01*
G01X72273Y284487D02*
X72523Y284737D01*
X72648Y285029D01*
X72690Y285362D01*
X72607Y285779D01*
X72398Y286071D01*
X72148Y286154D01*
X71898Y286112D01*
X71690Y285946D01*
X71273Y285112D01*
X70982Y284737D01*
X70565Y284487D01*
X70190Y284404D01*
Y286154D01*
G01Y288879D02*
X72690D01*
X70898Y287337D01*
Y289421D01*
G01X68752Y280096D02*
X68877Y279846D01*
X68960Y279554D01*
Y279221D01*
X68835Y278846D01*
X68627Y278554D01*
X68377Y278346D01*
X67960Y278179D01*
X67585Y278137D01*
X67210Y278221D01*
X66960Y278346D01*
X66710Y278596D01*
X66543Y278887D01*
X66460Y279179D01*
Y279471D01*
X66543Y279762D01*
X66668Y280012D01*
X66835Y280221D01*
G01X68543Y281487D02*
X68793Y281737D01*
X68918Y282029D01*
X68960Y282362D01*
X68877Y282779D01*
X68668Y283071D01*
X68418Y283154D01*
X68168Y283112D01*
X67960Y282946D01*
X67543Y282112D01*
X67252Y281737D01*
X66835Y281487D01*
X66460Y281404D01*
Y283154D01*
G01X68543Y284587D02*
X68793Y284837D01*
X68918Y285129D01*
X68960Y285462D01*
X68877Y285879D01*
X68668Y286171D01*
X68418Y286254D01*
X68168Y286212D01*
X67960Y286046D01*
X67543Y285212D01*
X67252Y284837D01*
X66835Y284587D01*
X66460Y284504D01*
Y286254D01*
G01X66835Y287562D02*
X66627Y287812D01*
X66502Y288104D01*
X66460Y288479D01*
X66543Y288854D01*
X66710Y289146D01*
X67002Y289354D01*
X67335Y289396D01*
X67668Y289312D01*
X67877Y289104D01*
X68043Y288812D01*
X68085Y288521D01*
X68043Y288229D01*
X67877Y287854D01*
X68960Y287979D01*
Y289104D01*
G01X18792Y315767D02*
X18917Y315517D01*
X19000Y315225D01*
Y314892D01*
X18875Y314517D01*
X18667Y314225D01*
X18417Y314017D01*
X18000Y313850D01*
X17625Y313808D01*
X17250Y313892D01*
X17000Y314017D01*
X16750Y314267D01*
X16583Y314558D01*
X16500Y314850D01*
Y315142D01*
X16583Y315433D01*
X16708Y315683D01*
X16875Y315892D01*
G01X18583Y317158D02*
X18833Y317408D01*
X18958Y317700D01*
X19000Y318033D01*
X18917Y318450D01*
X18708Y318742D01*
X18458Y318825D01*
X18208Y318783D01*
X18000Y318617D01*
X17583Y317783D01*
X17292Y317408D01*
X16875Y317158D01*
X16500Y317075D01*
Y318825D01*
G01Y321050D02*
X19000D01*
X18500Y320550D01*
G01X16500D02*
Y321550D01*
G01X19000Y324150D02*
X18917Y323817D01*
X18708Y323567D01*
X18458Y323400D01*
X18125Y323275D01*
X17750Y323233D01*
X17375Y323275D01*
X17042Y323400D01*
X16792Y323567D01*
X16583Y323817D01*
X16500Y324150D01*
X16583Y324483D01*
X16792Y324733D01*
X17042Y324900D01*
X17375Y325025D01*
X17750Y325067D01*
X18125Y325025D01*
X18458Y324900D01*
X18708Y324733D01*
X18917Y324483D01*
X19000Y324150D01*
G01X32482Y311117D02*
X32607Y310867D01*
X32690Y310575D01*
Y310242D01*
X32565Y309867D01*
X32357Y309575D01*
X32107Y309367D01*
X31690Y309200D01*
X31315Y309158D01*
X30940Y309242D01*
X30690Y309367D01*
X30440Y309617D01*
X30273Y309908D01*
X30190Y310200D01*
Y310492D01*
X30273Y310783D01*
X30398Y311033D01*
X30565Y311242D01*
G01X32273Y312508D02*
X32523Y312758D01*
X32648Y313050D01*
X32690Y313383D01*
X32607Y313800D01*
X32398Y314092D01*
X32148Y314175D01*
X31898Y314133D01*
X31690Y313967D01*
X31273Y313133D01*
X30982Y312758D01*
X30565Y312508D01*
X30190Y312425D01*
Y314175D01*
G01X32690Y316400D02*
X32607Y316067D01*
X32398Y315817D01*
X32148Y315650D01*
X31815Y315525D01*
X31440Y315483D01*
X31065Y315525D01*
X30732Y315650D01*
X30482Y315817D01*
X30273Y316067D01*
X30190Y316400D01*
X30273Y316733D01*
X30482Y316983D01*
X30732Y317150D01*
X31065Y317275D01*
X31440Y317317D01*
X31815Y317275D01*
X32148Y317150D01*
X32398Y316983D01*
X32607Y316733D01*
X32690Y316400D01*
G01X31232Y318708D02*
X31523Y319000D01*
X31690Y319250D01*
X31773Y319583D01*
X31690Y319875D01*
X31523Y320083D01*
X31273Y320250D01*
X30982Y320292D01*
X30732Y320250D01*
X30482Y320083D01*
X30273Y319833D01*
X30190Y319542D01*
X30273Y319208D01*
X30523Y318917D01*
X30898Y318750D01*
X31315Y318708D01*
X31857Y318792D01*
X32148Y318917D01*
X32440Y319125D01*
X32648Y319417D01*
X32690Y319708D01*
X32607Y320000D01*
X32398Y320208D01*
G01X17792Y302767D02*
X17917Y302517D01*
X18000Y302225D01*
Y301892D01*
X17875Y301517D01*
X17667Y301225D01*
X17417Y301017D01*
X17000Y300850D01*
X16625Y300808D01*
X16250Y300892D01*
X16000Y301017D01*
X15750Y301267D01*
X15583Y301558D01*
X15500Y301850D01*
Y302142D01*
X15583Y302433D01*
X15708Y302683D01*
X15875Y302892D01*
G01X15500Y304950D02*
X18000D01*
X17500Y304450D01*
G01X15500D02*
Y305450D01*
G01X15792Y307342D02*
X15583Y307633D01*
X15500Y307967D01*
X15583Y308300D01*
X15833Y308592D01*
X16208Y308800D01*
X16583Y308883D01*
X17042D01*
X17417Y308800D01*
X17750Y308592D01*
X17917Y308342D01*
X18000Y308050D01*
X17917Y307717D01*
X17750Y307467D01*
X17500Y307300D01*
X17167Y307217D01*
X16875Y307300D01*
X16583Y307508D01*
X16417Y307758D01*
X16375Y308050D01*
X16458Y308383D01*
X16667Y308633D01*
X17042Y308883D01*
G01X15500Y311150D02*
X15542Y311442D01*
X15667Y311775D01*
X15875Y311983D01*
X16167Y312067D01*
X16458Y311983D01*
X16708Y311733D01*
X16833Y311358D01*
Y310942D01*
X16917Y310692D01*
X17125Y310483D01*
X17417Y310400D01*
X17708Y310525D01*
X17917Y310817D01*
X18000Y311150D01*
X17917Y311483D01*
X17708Y311775D01*
X17417Y311900D01*
X17125Y311817D01*
X16917Y311608D01*
X16833Y311358D01*
Y310942D01*
X16708Y310567D01*
X16458Y310317D01*
X16167Y310233D01*
X15875Y310317D01*
X15667Y310525D01*
X15542Y310858D01*
X15500Y311150D01*
G01X57733Y332292D02*
X57983Y332417D01*
X58275Y332500D01*
X58608D01*
X58983Y332375D01*
X59275Y332167D01*
X59483Y331917D01*
X59650Y331500D01*
X59692Y331125D01*
X59608Y330750D01*
X59483Y330500D01*
X59233Y330250D01*
X58942Y330083D01*
X58650Y330000D01*
X58358D01*
X58067Y330083D01*
X57817Y330208D01*
X57608Y330375D01*
G01X55550Y330000D02*
Y332500D01*
X56050Y332000D01*
G01Y330000D02*
X55050D01*
G01X53158Y330292D02*
X52867Y330083D01*
X52533Y330000D01*
X52200Y330083D01*
X51908Y330333D01*
X51700Y330708D01*
X51617Y331083D01*
Y331542D01*
X51700Y331917D01*
X51908Y332250D01*
X52158Y332417D01*
X52450Y332500D01*
X52783Y332417D01*
X53033Y332250D01*
X53200Y332000D01*
X53283Y331667D01*
X53200Y331375D01*
X52992Y331083D01*
X52742Y330917D01*
X52450Y330875D01*
X52117Y330958D01*
X51867Y331167D01*
X51617Y331542D01*
G01X49350Y332500D02*
X49683Y332417D01*
X49933Y332208D01*
X50100Y331958D01*
X50225Y331625D01*
X50267Y331250D01*
X50225Y330875D01*
X50100Y330542D01*
X49933Y330292D01*
X49683Y330083D01*
X49350Y330000D01*
X49017Y330083D01*
X48767Y330292D01*
X48600Y330542D01*
X48475Y330875D01*
X48433Y331250D01*
X48475Y331625D01*
X48600Y331958D01*
X48767Y332208D01*
X49017Y332417D01*
X49350Y332500D01*
G01X45733Y311792D02*
X45983Y311917D01*
X46275Y312000D01*
X46608D01*
X46983Y311875D01*
X47275Y311667D01*
X47483Y311417D01*
X47650Y311000D01*
X47692Y310625D01*
X47608Y310250D01*
X47483Y310000D01*
X47233Y309750D01*
X46942Y309583D01*
X46650Y309500D01*
X46358D01*
X46067Y309583D01*
X45817Y309708D01*
X45608Y309875D01*
G01X43550Y309500D02*
Y312000D01*
X44050Y311500D01*
G01Y309500D02*
X43050D01*
G01X41242Y311583D02*
X40992Y311833D01*
X40700Y311958D01*
X40367Y312000D01*
X39950Y311917D01*
X39658Y311708D01*
X39575Y311458D01*
X39617Y311208D01*
X39783Y311000D01*
X40617Y310583D01*
X40992Y310292D01*
X41242Y309875D01*
X41325Y309500D01*
X39575D01*
G01X38142Y310542D02*
X37850Y310833D01*
X37600Y311000D01*
X37267Y311083D01*
X36975Y311000D01*
X36767Y310833D01*
X36600Y310583D01*
X36558Y310292D01*
X36600Y310042D01*
X36767Y309792D01*
X37017Y309583D01*
X37308Y309500D01*
X37642Y309583D01*
X37933Y309833D01*
X38100Y310208D01*
X38142Y310625D01*
X38058Y311167D01*
X37933Y311458D01*
X37725Y311750D01*
X37433Y311958D01*
X37142Y312000D01*
X36850Y311917D01*
X36642Y311708D01*
G01X22792Y315767D02*
X22917Y315517D01*
X23000Y315225D01*
Y314892D01*
X22875Y314517D01*
X22667Y314225D01*
X22417Y314017D01*
X22000Y313850D01*
X21625Y313808D01*
X21250Y313892D01*
X21000Y314017D01*
X20750Y314267D01*
X20583Y314558D01*
X20500Y314850D01*
Y315142D01*
X20583Y315433D01*
X20708Y315683D01*
X20875Y315892D01*
G01X22583Y317158D02*
X22833Y317408D01*
X22958Y317700D01*
X23000Y318033D01*
X22917Y318450D01*
X22708Y318742D01*
X22458Y318825D01*
X22208Y318783D01*
X22000Y318617D01*
X21583Y317783D01*
X21292Y317408D01*
X20875Y317158D01*
X20500Y317075D01*
Y318825D01*
G01Y321050D02*
X23000D01*
X22500Y320550D01*
G01X20500D02*
Y321550D01*
G01Y324150D02*
X23000D01*
X22500Y323650D01*
G01X20500D02*
Y324650D01*
G01X27982Y311117D02*
X28107Y310867D01*
X28190Y310575D01*
Y310242D01*
X28065Y309867D01*
X27857Y309575D01*
X27607Y309367D01*
X27190Y309200D01*
X26815Y309158D01*
X26440Y309242D01*
X26190Y309367D01*
X25940Y309617D01*
X25773Y309908D01*
X25690Y310200D01*
Y310492D01*
X25773Y310783D01*
X25898Y311033D01*
X26065Y311242D01*
G01X27773Y312508D02*
X28023Y312758D01*
X28148Y313050D01*
X28190Y313383D01*
X28107Y313800D01*
X27898Y314092D01*
X27648Y314175D01*
X27398Y314133D01*
X27190Y313967D01*
X26773Y313133D01*
X26482Y312758D01*
X26065Y312508D01*
X25690Y312425D01*
Y314175D01*
G01X28190Y316400D02*
X28107Y316067D01*
X27898Y315817D01*
X27648Y315650D01*
X27315Y315525D01*
X26940Y315483D01*
X26565Y315525D01*
X26232Y315650D01*
X25982Y315817D01*
X25773Y316067D01*
X25690Y316400D01*
X25773Y316733D01*
X25982Y316983D01*
X26232Y317150D01*
X26565Y317275D01*
X26940Y317317D01*
X27315Y317275D01*
X27648Y317150D01*
X27898Y316983D01*
X28107Y316733D01*
X28190Y316400D01*
G01X25690Y319417D02*
X26232Y319500D01*
X26690Y319625D01*
X27107Y319792D01*
X27565Y320000D01*
X28190Y320333D01*
Y318667D01*
G01X32733Y307292D02*
X32983Y307417D01*
X33275Y307500D01*
X33608D01*
X33983Y307375D01*
X34275Y307167D01*
X34483Y306917D01*
X34650Y306500D01*
X34692Y306125D01*
X34608Y305750D01*
X34483Y305500D01*
X34233Y305250D01*
X33942Y305083D01*
X33650Y305000D01*
X33358D01*
X33067Y305083D01*
X32817Y305208D01*
X32608Y305375D01*
G01X31342Y307083D02*
X31092Y307333D01*
X30800Y307458D01*
X30467Y307500D01*
X30050Y307417D01*
X29758Y307208D01*
X29675Y306958D01*
X29717Y306708D01*
X29883Y306500D01*
X30717Y306083D01*
X31092Y305792D01*
X31342Y305375D01*
X31425Y305000D01*
X29675D01*
G01X27450Y307500D02*
X27783Y307417D01*
X28033Y307208D01*
X28200Y306958D01*
X28325Y306625D01*
X28367Y306250D01*
X28325Y305875D01*
X28200Y305542D01*
X28033Y305292D01*
X27783Y305083D01*
X27450Y305000D01*
X27117Y305083D01*
X26867Y305292D01*
X26700Y305542D01*
X26575Y305875D01*
X26533Y306250D01*
X26575Y306625D01*
X26700Y306958D01*
X26867Y307208D01*
X27117Y307417D01*
X27450Y307500D01*
G01X25267Y305500D02*
X25017Y305208D01*
X24683Y305042D01*
X24308Y305000D01*
X23975Y305042D01*
X23642Y305250D01*
X23433Y305500D01*
X23392Y305750D01*
X23475Y306042D01*
X23767Y306250D01*
X24058Y306333D01*
X24433D01*
G01X24058D02*
X23808Y306458D01*
X23600Y306667D01*
X23517Y306917D01*
X23600Y307167D01*
X23808Y307375D01*
X24183Y307500D01*
X24558Y307458D01*
X24933Y307292D01*
G01X21792Y302767D02*
X21917Y302517D01*
X22000Y302225D01*
Y301892D01*
X21875Y301517D01*
X21667Y301225D01*
X21417Y301017D01*
X21000Y300850D01*
X20625Y300808D01*
X20250Y300892D01*
X20000Y301017D01*
X19750Y301267D01*
X19583Y301558D01*
X19500Y301850D01*
Y302142D01*
X19583Y302433D01*
X19708Y302683D01*
X19875Y302892D01*
G01X19500Y304950D02*
X22000D01*
X21500Y304450D01*
G01X19500D02*
Y305450D01*
G01X19792Y307342D02*
X19583Y307633D01*
X19500Y307967D01*
X19583Y308300D01*
X19833Y308592D01*
X20208Y308800D01*
X20583Y308883D01*
X21042D01*
X21417Y308800D01*
X21750Y308592D01*
X21917Y308342D01*
X22000Y308050D01*
X21917Y307717D01*
X21750Y307467D01*
X21500Y307300D01*
X21167Y307217D01*
X20875Y307300D01*
X20583Y307508D01*
X20417Y307758D01*
X20375Y308050D01*
X20458Y308383D01*
X20667Y308633D01*
X21042Y308883D01*
G01X19792Y310442D02*
X19583Y310733D01*
X19500Y311067D01*
X19583Y311400D01*
X19833Y311692D01*
X20208Y311900D01*
X20583Y311983D01*
X21042D01*
X21417Y311900D01*
X21750Y311692D01*
X21917Y311442D01*
X22000Y311150D01*
X21917Y310817D01*
X21750Y310567D01*
X21500Y310400D01*
X21167Y310317D01*
X20875Y310400D01*
X20583Y310608D01*
X20417Y310858D01*
X20375Y311150D01*
X20458Y311483D01*
X20667Y311733D01*
X21042Y311983D01*
G01X45733Y307292D02*
X45983Y307417D01*
X46275Y307500D01*
X46608D01*
X46983Y307375D01*
X47275Y307167D01*
X47483Y306917D01*
X47650Y306500D01*
X47692Y306125D01*
X47608Y305750D01*
X47483Y305500D01*
X47233Y305250D01*
X46942Y305083D01*
X46650Y305000D01*
X46358D01*
X46067Y305083D01*
X45817Y305208D01*
X45608Y305375D01*
G01X43550Y305000D02*
Y307500D01*
X44050Y307000D01*
G01Y305000D02*
X43050D01*
G01X41367Y305375D02*
X41117Y305167D01*
X40825Y305042D01*
X40450Y305000D01*
X40075Y305083D01*
X39783Y305250D01*
X39575Y305542D01*
X39533Y305875D01*
X39617Y306208D01*
X39825Y306417D01*
X40117Y306583D01*
X40408Y306625D01*
X40700Y306583D01*
X41075Y306417D01*
X40950Y307500D01*
X39825D01*
G01X37433Y305000D02*
X37350Y305542D01*
X37225Y306000D01*
X37058Y306417D01*
X36850Y306875D01*
X36517Y307500D01*
X38183D01*
G01X68382Y310867D02*
X68507Y310617D01*
X68590Y310325D01*
Y309992D01*
X68465Y309617D01*
X68257Y309325D01*
X68007Y309117D01*
X67590Y308950D01*
X67215Y308908D01*
X66840Y308992D01*
X66590Y309117D01*
X66340Y309367D01*
X66173Y309658D01*
X66090Y309950D01*
Y310242D01*
X66173Y310533D01*
X66298Y310783D01*
X66465Y310992D01*
G01X66090Y313050D02*
X68590D01*
X68090Y312550D01*
G01X66090D02*
Y313550D01*
G01Y316150D02*
X66132Y316442D01*
X66257Y316775D01*
X66465Y316983D01*
X66757Y317067D01*
X67048Y316983D01*
X67298Y316733D01*
X67423Y316358D01*
Y315942D01*
X67507Y315692D01*
X67715Y315483D01*
X68007Y315400D01*
X68298Y315525D01*
X68507Y315817D01*
X68590Y316150D01*
X68507Y316483D01*
X68298Y316775D01*
X68007Y316900D01*
X67715Y316817D01*
X67507Y316608D01*
X67423Y316358D01*
Y315942D01*
X67298Y315567D01*
X67048Y315317D01*
X66757Y315233D01*
X66465Y315317D01*
X66257Y315525D01*
X66132Y315858D01*
X66090Y316150D01*
G01X68590Y319250D02*
X68507Y318917D01*
X68298Y318667D01*
X68048Y318500D01*
X67715Y318375D01*
X67340Y318333D01*
X66965Y318375D01*
X66632Y318500D01*
X66382Y318667D01*
X66173Y318917D01*
X66090Y319250D01*
X66173Y319583D01*
X66382Y319833D01*
X66632Y320000D01*
X66965Y320125D01*
X67340Y320167D01*
X67715Y320125D01*
X68048Y320000D01*
X68298Y319833D01*
X68507Y319583D01*
X68590Y319250D01*
G01X64482Y323917D02*
X64607Y323667D01*
X64690Y323375D01*
Y323042D01*
X64565Y322667D01*
X64357Y322375D01*
X64107Y322167D01*
X63690Y322000D01*
X63315Y321958D01*
X62940Y322042D01*
X62690Y322167D01*
X62440Y322417D01*
X62273Y322708D01*
X62190Y323000D01*
Y323292D01*
X62273Y323583D01*
X62398Y323833D01*
X62565Y324042D01*
G01X62190Y326100D02*
X64690D01*
X64190Y325600D01*
G01X62190D02*
Y326600D01*
G01Y329117D02*
X62732Y329200D01*
X63190Y329325D01*
X63607Y329492D01*
X64065Y329700D01*
X64690Y330033D01*
Y328367D01*
G01X62190Y332217D02*
X62732Y332300D01*
X63190Y332425D01*
X63607Y332592D01*
X64065Y332800D01*
X64690Y333133D01*
Y331467D01*
G01X76532Y310867D02*
X76657Y310617D01*
X76740Y310325D01*
Y309992D01*
X76615Y309617D01*
X76407Y309325D01*
X76157Y309117D01*
X75740Y308950D01*
X75365Y308908D01*
X74990Y308992D01*
X74740Y309117D01*
X74490Y309367D01*
X74323Y309658D01*
X74240Y309950D01*
Y310242D01*
X74323Y310533D01*
X74448Y310783D01*
X74615Y310992D01*
G01X74240Y313050D02*
X76740D01*
X76240Y312550D01*
G01X74240D02*
Y313550D01*
G01Y316067D02*
X74782Y316150D01*
X75240Y316275D01*
X75657Y316442D01*
X76115Y316650D01*
X76740Y316983D01*
Y315317D01*
G01X76323Y318458D02*
X76573Y318708D01*
X76698Y319000D01*
X76740Y319333D01*
X76657Y319750D01*
X76448Y320042D01*
X76198Y320125D01*
X75948Y320083D01*
X75740Y319917D01*
X75323Y319083D01*
X75032Y318708D01*
X74615Y318458D01*
X74240Y318375D01*
Y320125D01*
G01X64382Y310867D02*
X64507Y310617D01*
X64590Y310325D01*
Y309992D01*
X64465Y309617D01*
X64257Y309325D01*
X64007Y309117D01*
X63590Y308950D01*
X63215Y308908D01*
X62840Y308992D01*
X62590Y309117D01*
X62340Y309367D01*
X62173Y309658D01*
X62090Y309950D01*
Y310242D01*
X62173Y310533D01*
X62298Y310783D01*
X62465Y310992D01*
G01X62090Y313050D02*
X64590D01*
X64090Y312550D01*
G01X62090D02*
Y313550D01*
G01X63132Y315358D02*
X63423Y315650D01*
X63590Y315900D01*
X63673Y316233D01*
X63590Y316525D01*
X63423Y316733D01*
X63173Y316900D01*
X62882Y316942D01*
X62632Y316900D01*
X62382Y316733D01*
X62173Y316483D01*
X62090Y316192D01*
X62173Y315858D01*
X62423Y315567D01*
X62798Y315400D01*
X63215Y315358D01*
X63757Y315442D01*
X64048Y315567D01*
X64340Y315775D01*
X64548Y316067D01*
X64590Y316358D01*
X64507Y316650D01*
X64298Y316858D01*
G01X62382Y318542D02*
X62173Y318833D01*
X62090Y319167D01*
X62173Y319500D01*
X62423Y319792D01*
X62798Y320000D01*
X63173Y320083D01*
X63632D01*
X64007Y320000D01*
X64340Y319792D01*
X64507Y319542D01*
X64590Y319250D01*
X64507Y318917D01*
X64340Y318667D01*
X64090Y318500D01*
X63757Y318417D01*
X63465Y318500D01*
X63173Y318708D01*
X63007Y318958D01*
X62965Y319250D01*
X63048Y319583D01*
X63257Y319833D01*
X63632Y320083D01*
G01X76482Y323917D02*
X76607Y323667D01*
X76690Y323375D01*
Y323042D01*
X76565Y322667D01*
X76357Y322375D01*
X76107Y322167D01*
X75690Y322000D01*
X75315Y321958D01*
X74940Y322042D01*
X74690Y322167D01*
X74440Y322417D01*
X74273Y322708D01*
X74190Y323000D01*
Y323292D01*
X74273Y323583D01*
X74398Y323833D01*
X74565Y324042D01*
G01X74190Y326100D02*
X76690D01*
X76190Y325600D01*
G01X74190D02*
Y326600D01*
G01X75232Y328408D02*
X75523Y328700D01*
X75690Y328950D01*
X75773Y329283D01*
X75690Y329575D01*
X75523Y329783D01*
X75273Y329950D01*
X74982Y329992D01*
X74732Y329950D01*
X74482Y329783D01*
X74273Y329533D01*
X74190Y329242D01*
X74273Y328908D01*
X74523Y328617D01*
X74898Y328450D01*
X75315Y328408D01*
X75857Y328492D01*
X76148Y328617D01*
X76440Y328825D01*
X76648Y329117D01*
X76690Y329408D01*
X76607Y329700D01*
X76398Y329908D01*
G01X74190Y332300D02*
X74232Y332592D01*
X74357Y332925D01*
X74565Y333133D01*
X74857Y333217D01*
X75148Y333133D01*
X75398Y332883D01*
X75523Y332508D01*
Y332092D01*
X75607Y331842D01*
X75815Y331633D01*
X76107Y331550D01*
X76398Y331675D01*
X76607Y331967D01*
X76690Y332300D01*
X76607Y332633D01*
X76398Y332925D01*
X76107Y333050D01*
X75815Y332967D01*
X75607Y332758D01*
X75523Y332508D01*
Y332092D01*
X75398Y331717D01*
X75148Y331467D01*
X74857Y331383D01*
X74565Y331467D01*
X74357Y331675D01*
X74232Y332008D01*
X74190Y332300D01*
G01X72482Y323917D02*
X72607Y323667D01*
X72690Y323375D01*
Y323042D01*
X72565Y322667D01*
X72357Y322375D01*
X72107Y322167D01*
X71690Y322000D01*
X71315Y321958D01*
X70940Y322042D01*
X70690Y322167D01*
X70440Y322417D01*
X70273Y322708D01*
X70190Y323000D01*
Y323292D01*
X70273Y323583D01*
X70398Y323833D01*
X70565Y324042D01*
G01X70190Y326100D02*
X72690D01*
X72190Y325600D01*
G01X70190D02*
Y326600D01*
G01X71232Y328408D02*
X71523Y328700D01*
X71690Y328950D01*
X71773Y329283D01*
X71690Y329575D01*
X71523Y329783D01*
X71273Y329950D01*
X70982Y329992D01*
X70732Y329950D01*
X70482Y329783D01*
X70273Y329533D01*
X70190Y329242D01*
X70273Y328908D01*
X70523Y328617D01*
X70898Y328450D01*
X71315Y328408D01*
X71857Y328492D01*
X72148Y328617D01*
X72440Y328825D01*
X72648Y329117D01*
X72690Y329408D01*
X72607Y329700D01*
X72398Y329908D01*
G01X71232Y331508D02*
X71523Y331800D01*
X71690Y332050D01*
X71773Y332383D01*
X71690Y332675D01*
X71523Y332883D01*
X71273Y333050D01*
X70982Y333092D01*
X70732Y333050D01*
X70482Y332883D01*
X70273Y332633D01*
X70190Y332342D01*
X70273Y332008D01*
X70523Y331717D01*
X70898Y331550D01*
X71315Y331508D01*
X71857Y331592D01*
X72148Y331717D01*
X72440Y331925D01*
X72648Y332217D01*
X72690Y332508D01*
X72607Y332800D01*
X72398Y333008D01*
G01X68482Y323917D02*
X68607Y323667D01*
X68690Y323375D01*
Y323042D01*
X68565Y322667D01*
X68357Y322375D01*
X68107Y322167D01*
X67690Y322000D01*
X67315Y321958D01*
X66940Y322042D01*
X66690Y322167D01*
X66440Y322417D01*
X66273Y322708D01*
X66190Y323000D01*
Y323292D01*
X66273Y323583D01*
X66398Y323833D01*
X66565Y324042D01*
G01X66190Y326100D02*
X68690D01*
X68190Y325600D01*
G01X66190D02*
Y326600D01*
G01X67232Y328408D02*
X67523Y328700D01*
X67690Y328950D01*
X67773Y329283D01*
X67690Y329575D01*
X67523Y329783D01*
X67273Y329950D01*
X66982Y329992D01*
X66732Y329950D01*
X66482Y329783D01*
X66273Y329533D01*
X66190Y329242D01*
X66273Y328908D01*
X66523Y328617D01*
X66898Y328450D01*
X67315Y328408D01*
X67857Y328492D01*
X68148Y328617D01*
X68440Y328825D01*
X68648Y329117D01*
X68690Y329408D01*
X68607Y329700D01*
X68398Y329908D01*
G01X66565Y331383D02*
X66357Y331633D01*
X66232Y331925D01*
X66190Y332300D01*
X66273Y332675D01*
X66440Y332967D01*
X66732Y333175D01*
X67065Y333217D01*
X67398Y333133D01*
X67607Y332925D01*
X67773Y332633D01*
X67815Y332342D01*
X67773Y332050D01*
X67607Y331675D01*
X68690Y331800D01*
Y332925D01*
G01X72532Y310867D02*
X72657Y310617D01*
X72740Y310325D01*
Y309992D01*
X72615Y309617D01*
X72407Y309325D01*
X72157Y309117D01*
X71740Y308950D01*
X71365Y308908D01*
X70990Y308992D01*
X70740Y309117D01*
X70490Y309367D01*
X70323Y309658D01*
X70240Y309950D01*
Y310242D01*
X70323Y310533D01*
X70448Y310783D01*
X70615Y310992D01*
G01X70240Y313050D02*
X72740D01*
X72240Y312550D01*
G01X70240D02*
Y313550D01*
G01X71282Y315358D02*
X71573Y315650D01*
X71740Y315900D01*
X71823Y316233D01*
X71740Y316525D01*
X71573Y316733D01*
X71323Y316900D01*
X71032Y316942D01*
X70782Y316900D01*
X70532Y316733D01*
X70323Y316483D01*
X70240Y316192D01*
X70323Y315858D01*
X70573Y315567D01*
X70948Y315400D01*
X71365Y315358D01*
X71907Y315442D01*
X72198Y315567D01*
X72490Y315775D01*
X72698Y316067D01*
X72740Y316358D01*
X72657Y316650D01*
X72448Y316858D01*
G01X72323Y318458D02*
X72573Y318708D01*
X72698Y319000D01*
X72740Y319333D01*
X72657Y319750D01*
X72448Y320042D01*
X72198Y320125D01*
X71948Y320083D01*
X71740Y319917D01*
X71323Y319083D01*
X71032Y318708D01*
X70615Y318458D01*
X70240Y318375D01*
Y320125D01*
G01X58233Y311792D02*
X58483Y311917D01*
X58775Y312000D01*
X59108D01*
X59483Y311875D01*
X59775Y311667D01*
X59983Y311417D01*
X60150Y311000D01*
X60192Y310625D01*
X60108Y310250D01*
X59983Y310000D01*
X59733Y309750D01*
X59442Y309583D01*
X59150Y309500D01*
X58858D01*
X58567Y309583D01*
X58317Y309708D01*
X58108Y309875D01*
G01X56050Y309500D02*
Y312000D01*
X56550Y311500D01*
G01Y309500D02*
X55550D01*
G01X53742Y310542D02*
X53450Y310833D01*
X53200Y311000D01*
X52867Y311083D01*
X52575Y311000D01*
X52367Y310833D01*
X52200Y310583D01*
X52158Y310292D01*
X52200Y310042D01*
X52367Y309792D01*
X52617Y309583D01*
X52908Y309500D01*
X53242Y309583D01*
X53533Y309833D01*
X53700Y310208D01*
X53742Y310625D01*
X53658Y311167D01*
X53533Y311458D01*
X53325Y311750D01*
X53033Y311958D01*
X52742Y312000D01*
X52450Y311917D01*
X52242Y311708D01*
G01X49850Y309500D02*
Y312000D01*
X50350Y311500D01*
G01Y309500D02*
X49350D01*
G01X56483Y320000D02*
Y322500D01*
X55442D01*
X55108Y322375D01*
X54900Y322208D01*
X54817Y321875D01*
X54900Y321542D01*
X55150Y321333D01*
X55442Y321208D01*
X56483D01*
G01X55442D02*
X54817Y320000D01*
G01X52050D02*
Y322500D01*
X53592Y320708D01*
X51508D01*
G01X49533Y320000D02*
X49450Y320542D01*
X49325Y321000D01*
X49158Y321417D01*
X48950Y321875D01*
X48617Y322500D01*
X50283D01*
G01X47142Y321042D02*
X46850Y321333D01*
X46600Y321500D01*
X46267Y321583D01*
X45975Y321500D01*
X45767Y321333D01*
X45600Y321083D01*
X45558Y320792D01*
X45600Y320542D01*
X45767Y320292D01*
X46017Y320083D01*
X46308Y320000D01*
X46642Y320083D01*
X46933Y320333D01*
X47100Y320708D01*
X47142Y321125D01*
X47058Y321667D01*
X46933Y321958D01*
X46725Y322250D01*
X46433Y322458D01*
X46142Y322500D01*
X45850Y322417D01*
X45642Y322208D01*
G01X35483Y322000D02*
Y324500D01*
X34442D01*
X34108Y324375D01*
X33900Y324208D01*
X33817Y323875D01*
X33900Y323542D01*
X34150Y323333D01*
X34442Y323208D01*
X35483D01*
G01X34442D02*
X33817Y322000D01*
G01X31050D02*
Y324500D01*
X32592Y322708D01*
X30508D01*
G01X28533Y322000D02*
X28450Y322542D01*
X28325Y323000D01*
X28158Y323417D01*
X27950Y323875D01*
X27617Y324500D01*
X29283D01*
G01X26267Y322375D02*
X26017Y322167D01*
X25725Y322042D01*
X25350Y322000D01*
X24975Y322083D01*
X24683Y322250D01*
X24475Y322542D01*
X24433Y322875D01*
X24517Y323208D01*
X24725Y323417D01*
X25017Y323583D01*
X25308Y323625D01*
X25600Y323583D01*
X25975Y323417D01*
X25850Y324500D01*
X24725D01*
G01X58423Y307142D02*
X58673Y307267D01*
X58965Y307350D01*
X59298D01*
X59673Y307225D01*
X59965Y307017D01*
X60173Y306767D01*
X60340Y306350D01*
X60382Y305975D01*
X60298Y305600D01*
X60173Y305350D01*
X59923Y305100D01*
X59632Y304933D01*
X59340Y304850D01*
X59048D01*
X58757Y304933D01*
X58507Y305058D01*
X58298Y305225D01*
G01X56240Y304850D02*
Y307350D01*
X56740Y306850D01*
G01Y304850D02*
X55740D01*
G01X53140D02*
X52848Y304892D01*
X52515Y305017D01*
X52307Y305225D01*
X52223Y305517D01*
X52307Y305808D01*
X52557Y306058D01*
X52932Y306183D01*
X53348D01*
X53598Y306267D01*
X53807Y306475D01*
X53890Y306767D01*
X53765Y307058D01*
X53473Y307267D01*
X53140Y307350D01*
X52807Y307267D01*
X52515Y307058D01*
X52390Y306767D01*
X52473Y306475D01*
X52682Y306267D01*
X52932Y306183D01*
X53348D01*
X53723Y306058D01*
X53973Y305808D01*
X54057Y305517D01*
X53973Y305225D01*
X53765Y305017D01*
X53432Y304892D01*
X53140Y304850D01*
G01X49540D02*
Y307350D01*
X51082Y305558D01*
X48998D01*
G01X137567Y241417D02*
X138367Y241767D01*
X139300Y242000D01*
X140367D01*
X141567Y241650D01*
X142500Y241067D01*
X143167Y240367D01*
X143700Y239200D01*
X143833Y238150D01*
X143567Y237100D01*
X143167Y236400D01*
X142367Y235700D01*
X141433Y235233D01*
X140500Y235000D01*
X139567D01*
X138633Y235233D01*
X137833Y235583D01*
X137167Y236050D01*
G01X80482Y238667D02*
X80607Y238417D01*
X80690Y238125D01*
Y237792D01*
X80565Y237417D01*
X80357Y237125D01*
X80107Y236917D01*
X79690Y236750D01*
X79315Y236708D01*
X78940Y236792D01*
X78690Y236917D01*
X78440Y237167D01*
X78273Y237458D01*
X78190Y237750D01*
Y238042D01*
X78273Y238333D01*
X78398Y238583D01*
X78565Y238792D01*
G01X78190Y240767D02*
X78732Y240850D01*
X79190Y240975D01*
X79607Y241142D01*
X80065Y241350D01*
X80690Y241683D01*
Y240017D01*
G01X78190Y243950D02*
X80690D01*
X80190Y243450D01*
G01X78190D02*
Y244450D01*
G01X83982Y238767D02*
X84107Y238517D01*
X84190Y238225D01*
Y237892D01*
X84065Y237517D01*
X83857Y237225D01*
X83607Y237017D01*
X83190Y236850D01*
X82815Y236808D01*
X82440Y236892D01*
X82190Y237017D01*
X81940Y237267D01*
X81773Y237558D01*
X81690Y237850D01*
Y238142D01*
X81773Y238433D01*
X81898Y238683D01*
X82065Y238892D01*
G01X81690Y240867D02*
X82232Y240950D01*
X82690Y241075D01*
X83107Y241242D01*
X83565Y241450D01*
X84190Y241783D01*
Y240117D01*
G01Y244050D02*
X84107Y243717D01*
X83898Y243467D01*
X83648Y243300D01*
X83315Y243175D01*
X82940Y243133D01*
X82565Y243175D01*
X82232Y243300D01*
X81982Y243467D01*
X81773Y243717D01*
X81690Y244050D01*
X81773Y244383D01*
X81982Y244633D01*
X82232Y244800D01*
X82565Y244925D01*
X82940Y244967D01*
X83315Y244925D01*
X83648Y244800D01*
X83898Y244633D01*
X84107Y244383D01*
X84190Y244050D01*
G01X87682Y238767D02*
X87807Y238517D01*
X87890Y238225D01*
Y237892D01*
X87765Y237517D01*
X87557Y237225D01*
X87307Y237017D01*
X86890Y236850D01*
X86515Y236808D01*
X86140Y236892D01*
X85890Y237017D01*
X85640Y237267D01*
X85473Y237558D01*
X85390Y237850D01*
Y238142D01*
X85473Y238433D01*
X85598Y238683D01*
X85765Y238892D01*
G01X86432Y240158D02*
X86723Y240450D01*
X86890Y240700D01*
X86973Y241033D01*
X86890Y241325D01*
X86723Y241533D01*
X86473Y241700D01*
X86182Y241742D01*
X85932Y241700D01*
X85682Y241533D01*
X85473Y241283D01*
X85390Y240992D01*
X85473Y240658D01*
X85723Y240367D01*
X86098Y240200D01*
X86515Y240158D01*
X87057Y240242D01*
X87348Y240367D01*
X87640Y240575D01*
X87848Y240867D01*
X87890Y241158D01*
X87807Y241450D01*
X87598Y241658D01*
G01X85682Y243342D02*
X85473Y243633D01*
X85390Y243967D01*
X85473Y244300D01*
X85723Y244592D01*
X86098Y244800D01*
X86473Y244883D01*
X86932D01*
X87307Y244800D01*
X87640Y244592D01*
X87807Y244342D01*
X87890Y244050D01*
X87807Y243717D01*
X87640Y243467D01*
X87390Y243300D01*
X87057Y243217D01*
X86765Y243300D01*
X86473Y243508D01*
X86307Y243758D01*
X86265Y244050D01*
X86348Y244383D01*
X86557Y244633D01*
X86932Y244883D01*
G01X91482Y238767D02*
X91607Y238517D01*
X91690Y238225D01*
Y237892D01*
X91565Y237517D01*
X91357Y237225D01*
X91107Y237017D01*
X90690Y236850D01*
X90315Y236808D01*
X89940Y236892D01*
X89690Y237017D01*
X89440Y237267D01*
X89273Y237558D01*
X89190Y237850D01*
Y238142D01*
X89273Y238433D01*
X89398Y238683D01*
X89565Y238892D01*
G01X90232Y240158D02*
X90523Y240450D01*
X90690Y240700D01*
X90773Y241033D01*
X90690Y241325D01*
X90523Y241533D01*
X90273Y241700D01*
X89982Y241742D01*
X89732Y241700D01*
X89482Y241533D01*
X89273Y241283D01*
X89190Y240992D01*
X89273Y240658D01*
X89523Y240367D01*
X89898Y240200D01*
X90315Y240158D01*
X90857Y240242D01*
X91148Y240367D01*
X91440Y240575D01*
X91648Y240867D01*
X91690Y241158D01*
X91607Y241450D01*
X91398Y241658D01*
G01X89190Y244050D02*
X89232Y244342D01*
X89357Y244675D01*
X89565Y244883D01*
X89857Y244967D01*
X90148Y244883D01*
X90398Y244633D01*
X90523Y244258D01*
Y243842D01*
X90607Y243592D01*
X90815Y243383D01*
X91107Y243300D01*
X91398Y243425D01*
X91607Y243717D01*
X91690Y244050D01*
X91607Y244383D01*
X91398Y244675D01*
X91107Y244800D01*
X90815Y244717D01*
X90607Y244508D01*
X90523Y244258D01*
Y243842D01*
X90398Y243467D01*
X90148Y243217D01*
X89857Y243133D01*
X89565Y243217D01*
X89357Y243425D01*
X89232Y243758D01*
X89190Y244050D01*
G01X95182Y238767D02*
X95307Y238517D01*
X95390Y238225D01*
Y237892D01*
X95265Y237517D01*
X95057Y237225D01*
X94807Y237017D01*
X94390Y236850D01*
X94015Y236808D01*
X93640Y236892D01*
X93390Y237017D01*
X93140Y237267D01*
X92973Y237558D01*
X92890Y237850D01*
Y238142D01*
X92973Y238433D01*
X93098Y238683D01*
X93265Y238892D01*
G01X93932Y240158D02*
X94223Y240450D01*
X94390Y240700D01*
X94473Y241033D01*
X94390Y241325D01*
X94223Y241533D01*
X93973Y241700D01*
X93682Y241742D01*
X93432Y241700D01*
X93182Y241533D01*
X92973Y241283D01*
X92890Y240992D01*
X92973Y240658D01*
X93223Y240367D01*
X93598Y240200D01*
X94015Y240158D01*
X94557Y240242D01*
X94848Y240367D01*
X95140Y240575D01*
X95348Y240867D01*
X95390Y241158D01*
X95307Y241450D01*
X95098Y241658D01*
G01X92890Y243967D02*
X93432Y244050D01*
X93890Y244175D01*
X94307Y244342D01*
X94765Y244550D01*
X95390Y244883D01*
Y243217D01*
G01X99482Y238767D02*
X99607Y238517D01*
X99690Y238225D01*
Y237892D01*
X99565Y237517D01*
X99357Y237225D01*
X99107Y237017D01*
X98690Y236850D01*
X98315Y236808D01*
X97940Y236892D01*
X97690Y237017D01*
X97440Y237267D01*
X97273Y237558D01*
X97190Y237850D01*
Y238142D01*
X97273Y238433D01*
X97398Y238683D01*
X97565Y238892D01*
G01X98232Y240158D02*
X98523Y240450D01*
X98690Y240700D01*
X98773Y241033D01*
X98690Y241325D01*
X98523Y241533D01*
X98273Y241700D01*
X97982Y241742D01*
X97732Y241700D01*
X97482Y241533D01*
X97273Y241283D01*
X97190Y240992D01*
X97273Y240658D01*
X97523Y240367D01*
X97898Y240200D01*
X98315Y240158D01*
X98857Y240242D01*
X99148Y240367D01*
X99440Y240575D01*
X99648Y240867D01*
X99690Y241158D01*
X99607Y241450D01*
X99398Y241658D01*
G01X98232Y243258D02*
X98523Y243550D01*
X98690Y243800D01*
X98773Y244133D01*
X98690Y244425D01*
X98523Y244633D01*
X98273Y244800D01*
X97982Y244842D01*
X97732Y244800D01*
X97482Y244633D01*
X97273Y244383D01*
X97190Y244092D01*
X97273Y243758D01*
X97523Y243467D01*
X97898Y243300D01*
X98315Y243258D01*
X98857Y243342D01*
X99148Y243467D01*
X99440Y243675D01*
X99648Y243967D01*
X99690Y244258D01*
X99607Y244550D01*
X99398Y244758D01*
G01X103182Y238767D02*
X103307Y238517D01*
X103390Y238225D01*
Y237892D01*
X103265Y237517D01*
X103057Y237225D01*
X102807Y237017D01*
X102390Y236850D01*
X102015Y236808D01*
X101640Y236892D01*
X101390Y237017D01*
X101140Y237267D01*
X100973Y237558D01*
X100890Y237850D01*
Y238142D01*
X100973Y238433D01*
X101098Y238683D01*
X101265Y238892D01*
G01X101932Y240158D02*
X102223Y240450D01*
X102390Y240700D01*
X102473Y241033D01*
X102390Y241325D01*
X102223Y241533D01*
X101973Y241700D01*
X101682Y241742D01*
X101432Y241700D01*
X101182Y241533D01*
X100973Y241283D01*
X100890Y240992D01*
X100973Y240658D01*
X101223Y240367D01*
X101598Y240200D01*
X102015Y240158D01*
X102557Y240242D01*
X102848Y240367D01*
X103140Y240575D01*
X103348Y240867D01*
X103390Y241158D01*
X103307Y241450D01*
X103098Y241658D01*
G01X101265Y243133D02*
X101057Y243383D01*
X100932Y243675D01*
X100890Y244050D01*
X100973Y244425D01*
X101140Y244717D01*
X101432Y244925D01*
X101765Y244967D01*
X102098Y244883D01*
X102307Y244675D01*
X102473Y244383D01*
X102515Y244092D01*
X102473Y243800D01*
X102307Y243425D01*
X103390Y243550D01*
Y244675D01*
G01X106982Y238767D02*
X107107Y238517D01*
X107190Y238225D01*
Y237892D01*
X107065Y237517D01*
X106857Y237225D01*
X106607Y237017D01*
X106190Y236850D01*
X105815Y236808D01*
X105440Y236892D01*
X105190Y237017D01*
X104940Y237267D01*
X104773Y237558D01*
X104690Y237850D01*
Y238142D01*
X104773Y238433D01*
X104898Y238683D01*
X105065Y238892D01*
G01X105732Y240158D02*
X106023Y240450D01*
X106190Y240700D01*
X106273Y241033D01*
X106190Y241325D01*
X106023Y241533D01*
X105773Y241700D01*
X105482Y241742D01*
X105232Y241700D01*
X104982Y241533D01*
X104773Y241283D01*
X104690Y240992D01*
X104773Y240658D01*
X105023Y240367D01*
X105398Y240200D01*
X105815Y240158D01*
X106357Y240242D01*
X106648Y240367D01*
X106940Y240575D01*
X107148Y240867D01*
X107190Y241158D01*
X107107Y241450D01*
X106898Y241658D01*
G01X104690Y244550D02*
X107190D01*
X105398Y243008D01*
Y245092D01*
G01X110682Y238767D02*
X110807Y238517D01*
X110890Y238225D01*
Y237892D01*
X110765Y237517D01*
X110557Y237225D01*
X110307Y237017D01*
X109890Y236850D01*
X109515Y236808D01*
X109140Y236892D01*
X108890Y237017D01*
X108640Y237267D01*
X108473Y237558D01*
X108390Y237850D01*
Y238142D01*
X108473Y238433D01*
X108598Y238683D01*
X108765Y238892D01*
G01X109432Y240158D02*
X109723Y240450D01*
X109890Y240700D01*
X109973Y241033D01*
X109890Y241325D01*
X109723Y241533D01*
X109473Y241700D01*
X109182Y241742D01*
X108932Y241700D01*
X108682Y241533D01*
X108473Y241283D01*
X108390Y240992D01*
X108473Y240658D01*
X108723Y240367D01*
X109098Y240200D01*
X109515Y240158D01*
X110057Y240242D01*
X110348Y240367D01*
X110640Y240575D01*
X110848Y240867D01*
X110890Y241158D01*
X110807Y241450D01*
X110598Y241658D01*
G01X108890Y243133D02*
X108598Y243383D01*
X108432Y243717D01*
X108390Y244092D01*
X108432Y244425D01*
X108640Y244758D01*
X108890Y244967D01*
X109140Y245008D01*
X109432Y244925D01*
X109640Y244633D01*
X109723Y244342D01*
Y243967D01*
G01Y244342D02*
X109848Y244592D01*
X110057Y244800D01*
X110307Y244883D01*
X110557Y244800D01*
X110765Y244592D01*
X110890Y244217D01*
X110848Y243842D01*
X110682Y243467D01*
G01X114482Y238767D02*
X114607Y238517D01*
X114690Y238225D01*
Y237892D01*
X114565Y237517D01*
X114357Y237225D01*
X114107Y237017D01*
X113690Y236850D01*
X113315Y236808D01*
X112940Y236892D01*
X112690Y237017D01*
X112440Y237267D01*
X112273Y237558D01*
X112190Y237850D01*
Y238142D01*
X112273Y238433D01*
X112398Y238683D01*
X112565Y238892D01*
G01X113232Y240158D02*
X113523Y240450D01*
X113690Y240700D01*
X113773Y241033D01*
X113690Y241325D01*
X113523Y241533D01*
X113273Y241700D01*
X112982Y241742D01*
X112732Y241700D01*
X112482Y241533D01*
X112273Y241283D01*
X112190Y240992D01*
X112273Y240658D01*
X112523Y240367D01*
X112898Y240200D01*
X113315Y240158D01*
X113857Y240242D01*
X114148Y240367D01*
X114440Y240575D01*
X114648Y240867D01*
X114690Y241158D01*
X114607Y241450D01*
X114398Y241658D01*
G01X114273Y243258D02*
X114523Y243508D01*
X114648Y243800D01*
X114690Y244133D01*
X114607Y244550D01*
X114398Y244842D01*
X114148Y244925D01*
X113898Y244883D01*
X113690Y244717D01*
X113273Y243883D01*
X112982Y243508D01*
X112565Y243258D01*
X112190Y243175D01*
Y244925D01*
G01X118182Y238767D02*
X118307Y238517D01*
X118390Y238225D01*
Y237892D01*
X118265Y237517D01*
X118057Y237225D01*
X117807Y237017D01*
X117390Y236850D01*
X117015Y236808D01*
X116640Y236892D01*
X116390Y237017D01*
X116140Y237267D01*
X115973Y237558D01*
X115890Y237850D01*
Y238142D01*
X115973Y238433D01*
X116098Y238683D01*
X116265Y238892D01*
G01X116932Y240158D02*
X117223Y240450D01*
X117390Y240700D01*
X117473Y241033D01*
X117390Y241325D01*
X117223Y241533D01*
X116973Y241700D01*
X116682Y241742D01*
X116432Y241700D01*
X116182Y241533D01*
X115973Y241283D01*
X115890Y240992D01*
X115973Y240658D01*
X116223Y240367D01*
X116598Y240200D01*
X117015Y240158D01*
X117557Y240242D01*
X117848Y240367D01*
X118140Y240575D01*
X118348Y240867D01*
X118390Y241158D01*
X118307Y241450D01*
X118098Y241658D01*
G01X115890Y244050D02*
X118390D01*
X117890Y243550D01*
G01X115890D02*
Y244550D01*
G01X122142Y238527D02*
X122267Y238277D01*
X122350Y237985D01*
Y237652D01*
X122225Y237277D01*
X122017Y236985D01*
X121767Y236777D01*
X121350Y236610D01*
X120975Y236568D01*
X120600Y236652D01*
X120350Y236777D01*
X120100Y237027D01*
X119933Y237318D01*
X119850Y237610D01*
Y237902D01*
X119933Y238193D01*
X120058Y238443D01*
X120225Y238652D01*
G01X120892Y239918D02*
X121183Y240210D01*
X121350Y240460D01*
X121433Y240793D01*
X121350Y241085D01*
X121183Y241293D01*
X120933Y241460D01*
X120642Y241502D01*
X120392Y241460D01*
X120142Y241293D01*
X119933Y241043D01*
X119850Y240752D01*
X119933Y240418D01*
X120183Y240127D01*
X120558Y239960D01*
X120975Y239918D01*
X121517Y240002D01*
X121808Y240127D01*
X122100Y240335D01*
X122308Y240627D01*
X122350Y240918D01*
X122267Y241210D01*
X122058Y241418D01*
G01X122350Y243810D02*
X122267Y243477D01*
X122058Y243227D01*
X121808Y243060D01*
X121475Y242935D01*
X121100Y242893D01*
X120725Y242935D01*
X120392Y243060D01*
X120142Y243227D01*
X119933Y243477D01*
X119850Y243810D01*
X119933Y244143D01*
X120142Y244393D01*
X120392Y244560D01*
X120725Y244685D01*
X121100Y244727D01*
X121475Y244685D01*
X121808Y244560D01*
X122058Y244393D01*
X122267Y244143D01*
X122350Y243810D01*
G01X125562Y238567D02*
X125687Y238317D01*
X125770Y238025D01*
Y237692D01*
X125645Y237317D01*
X125437Y237025D01*
X125187Y236817D01*
X124770Y236650D01*
X124395Y236608D01*
X124020Y236692D01*
X123770Y236817D01*
X123520Y237067D01*
X123353Y237358D01*
X123270Y237650D01*
Y237942D01*
X123353Y238233D01*
X123478Y238483D01*
X123645Y238692D01*
G01Y239833D02*
X123437Y240083D01*
X123312Y240375D01*
X123270Y240750D01*
X123353Y241125D01*
X123520Y241417D01*
X123812Y241625D01*
X124145Y241667D01*
X124478Y241583D01*
X124687Y241375D01*
X124853Y241083D01*
X124895Y240792D01*
X124853Y240500D01*
X124687Y240125D01*
X125770Y240250D01*
Y241375D01*
G01X123562Y243142D02*
X123353Y243433D01*
X123270Y243767D01*
X123353Y244100D01*
X123603Y244392D01*
X123978Y244600D01*
X124353Y244683D01*
X124812D01*
X125187Y244600D01*
X125520Y244392D01*
X125687Y244142D01*
X125770Y243850D01*
X125687Y243517D01*
X125520Y243267D01*
X125270Y243100D01*
X124937Y243017D01*
X124645Y243100D01*
X124353Y243308D01*
X124187Y243558D01*
X124145Y243850D01*
X124228Y244183D01*
X124437Y244433D01*
X124812Y244683D01*
G01X129652Y238787D02*
X129777Y238537D01*
X129860Y238245D01*
Y237912D01*
X129735Y237537D01*
X129527Y237245D01*
X129277Y237037D01*
X128860Y236870D01*
X128485Y236828D01*
X128110Y236912D01*
X127860Y237037D01*
X127610Y237287D01*
X127443Y237578D01*
X127360Y237870D01*
Y238162D01*
X127443Y238453D01*
X127568Y238703D01*
X127735Y238912D01*
G01Y240053D02*
X127527Y240303D01*
X127402Y240595D01*
X127360Y240970D01*
X127443Y241345D01*
X127610Y241637D01*
X127902Y241845D01*
X128235Y241887D01*
X128568Y241803D01*
X128777Y241595D01*
X128943Y241303D01*
X128985Y241012D01*
X128943Y240720D01*
X128777Y240345D01*
X129860Y240470D01*
Y241595D01*
G01X127360Y244070D02*
X127402Y244362D01*
X127527Y244695D01*
X127735Y244903D01*
X128027Y244987D01*
X128318Y244903D01*
X128568Y244653D01*
X128693Y244278D01*
Y243862D01*
X128777Y243612D01*
X128985Y243403D01*
X129277Y243320D01*
X129568Y243445D01*
X129777Y243737D01*
X129860Y244070D01*
X129777Y244403D01*
X129568Y244695D01*
X129277Y244820D01*
X128985Y244737D01*
X128777Y244528D01*
X128693Y244278D01*
Y243862D01*
X128568Y243487D01*
X128318Y243237D01*
X128027Y243153D01*
X127735Y243237D01*
X127527Y243445D01*
X127402Y243778D01*
X127360Y244070D01*
G01X133132Y238617D02*
X133257Y238367D01*
X133340Y238075D01*
Y237742D01*
X133215Y237367D01*
X133007Y237075D01*
X132757Y236867D01*
X132340Y236700D01*
X131965Y236658D01*
X131590Y236742D01*
X131340Y236867D01*
X131090Y237117D01*
X130923Y237408D01*
X130840Y237700D01*
Y237992D01*
X130923Y238283D01*
X131048Y238533D01*
X131215Y238742D01*
G01Y239883D02*
X131007Y240133D01*
X130882Y240425D01*
X130840Y240800D01*
X130923Y241175D01*
X131090Y241467D01*
X131382Y241675D01*
X131715Y241717D01*
X132048Y241633D01*
X132257Y241425D01*
X132423Y241133D01*
X132465Y240842D01*
X132423Y240550D01*
X132257Y240175D01*
X133340Y240300D01*
Y241425D01*
G01X130840Y243817D02*
X131382Y243900D01*
X131840Y244025D01*
X132257Y244192D01*
X132715Y244400D01*
X133340Y244733D01*
Y243067D01*
G01X237500Y347000D02*
Y369500D01*
X123690D01*
Y276100D01*
G03X123790Y276000I100J0D01*
G01X154000D01*
Y262000D01*
G01X134233Y269792D02*
X134483Y269917D01*
X134775Y270000D01*
X135108D01*
X135483Y269875D01*
X135775Y269667D01*
X135983Y269417D01*
X136150Y269000D01*
X136192Y268625D01*
X136108Y268250D01*
X135983Y268000D01*
X135733Y267750D01*
X135442Y267583D01*
X135150Y267500D01*
X134858D01*
X134567Y267583D01*
X134317Y267708D01*
X134108Y267875D01*
G01X132967Y268000D02*
X132717Y267708D01*
X132383Y267542D01*
X132008Y267500D01*
X131675Y267542D01*
X131342Y267750D01*
X131133Y268000D01*
X131092Y268250D01*
X131175Y268542D01*
X131467Y268750D01*
X131758Y268833D01*
X132133D01*
G01X131758D02*
X131508Y268958D01*
X131300Y269167D01*
X131217Y269417D01*
X131300Y269667D01*
X131508Y269875D01*
X131883Y270000D01*
X132258Y269958D01*
X132633Y269792D01*
G01X128950Y270000D02*
X129283Y269917D01*
X129533Y269708D01*
X129700Y269458D01*
X129825Y269125D01*
X129867Y268750D01*
X129825Y268375D01*
X129700Y268042D01*
X129533Y267792D01*
X129283Y267583D01*
X128950Y267500D01*
X128617Y267583D01*
X128367Y267792D01*
X128200Y268042D01*
X128075Y268375D01*
X128033Y268750D01*
X128075Y269125D01*
X128200Y269458D01*
X128367Y269708D01*
X128617Y269917D01*
X128950Y270000D01*
G01X126558Y267792D02*
X126267Y267583D01*
X125933Y267500D01*
X125600Y267583D01*
X125308Y267833D01*
X125100Y268208D01*
X125017Y268583D01*
Y269042D01*
X125100Y269417D01*
X125308Y269750D01*
X125558Y269917D01*
X125850Y270000D01*
X126183Y269917D01*
X126433Y269750D01*
X126600Y269500D01*
X126683Y269167D01*
X126600Y268875D01*
X126392Y268583D01*
X126142Y268417D01*
X125850Y268375D01*
X125517Y268458D01*
X125267Y268667D01*
X125017Y269042D01*
G01X134355Y257792D02*
X134605Y257917D01*
X134897Y258000D01*
X135230D01*
X135605Y257875D01*
X135897Y257667D01*
X136105Y257417D01*
X136272Y257000D01*
X136314Y256625D01*
X136230Y256250D01*
X136105Y256000D01*
X135855Y255750D01*
X135564Y255583D01*
X135272Y255500D01*
X134980D01*
X134689Y255583D01*
X134439Y255708D01*
X134230Y255875D01*
G01X133089Y256000D02*
X132839Y255708D01*
X132505Y255542D01*
X132130Y255500D01*
X131797Y255542D01*
X131464Y255750D01*
X131255Y256000D01*
X131214Y256250D01*
X131297Y256542D01*
X131589Y256750D01*
X131880Y256833D01*
X132255D01*
G01X131880D02*
X131630Y256958D01*
X131422Y257167D01*
X131339Y257417D01*
X131422Y257667D01*
X131630Y257875D01*
X132005Y258000D01*
X132380Y257958D01*
X132755Y257792D01*
G01X129072Y258000D02*
X129405Y257917D01*
X129655Y257708D01*
X129822Y257458D01*
X129947Y257125D01*
X129989Y256750D01*
X129947Y256375D01*
X129822Y256042D01*
X129655Y255792D01*
X129405Y255583D01*
X129072Y255500D01*
X128739Y255583D01*
X128489Y255792D01*
X128322Y256042D01*
X128197Y256375D01*
X128155Y256750D01*
X128197Y257125D01*
X128322Y257458D01*
X128489Y257708D01*
X128739Y257917D01*
X129072Y258000D01*
G01X126764Y257583D02*
X126514Y257833D01*
X126222Y257958D01*
X125889Y258000D01*
X125472Y257917D01*
X125180Y257708D01*
X125097Y257458D01*
X125139Y257208D01*
X125305Y257000D01*
X126139Y256583D01*
X126514Y256292D01*
X126764Y255875D01*
X126847Y255500D01*
X125097D01*
G01X134455Y265792D02*
X134705Y265917D01*
X134997Y266000D01*
X135330D01*
X135705Y265875D01*
X135997Y265667D01*
X136205Y265417D01*
X136372Y265000D01*
X136414Y264625D01*
X136330Y264250D01*
X136205Y264000D01*
X135955Y263750D01*
X135664Y263583D01*
X135372Y263500D01*
X135080D01*
X134789Y263583D01*
X134539Y263708D01*
X134330Y263875D01*
G01X133064Y265583D02*
X132814Y265833D01*
X132522Y265958D01*
X132189Y266000D01*
X131772Y265917D01*
X131480Y265708D01*
X131397Y265458D01*
X131439Y265208D01*
X131605Y265000D01*
X132439Y264583D01*
X132814Y264292D01*
X133064Y263875D01*
X133147Y263500D01*
X131397D01*
G01X130089Y263875D02*
X129839Y263667D01*
X129547Y263542D01*
X129172Y263500D01*
X128797Y263583D01*
X128505Y263750D01*
X128297Y264042D01*
X128255Y264375D01*
X128339Y264708D01*
X128547Y264917D01*
X128839Y265083D01*
X129130Y265125D01*
X129422Y265083D01*
X129797Y264917D01*
X129672Y266000D01*
X128547D01*
G01X126155Y263500D02*
X126072Y264042D01*
X125947Y264500D01*
X125780Y264917D01*
X125572Y265375D01*
X125239Y266000D01*
X126905D01*
G01X134405Y261792D02*
X134655Y261917D01*
X134947Y262000D01*
X135280D01*
X135655Y261875D01*
X135947Y261667D01*
X136155Y261417D01*
X136322Y261000D01*
X136364Y260625D01*
X136280Y260250D01*
X136155Y260000D01*
X135905Y259750D01*
X135614Y259583D01*
X135322Y259500D01*
X135030D01*
X134739Y259583D01*
X134489Y259708D01*
X134280Y259875D01*
G01X133014Y261583D02*
X132764Y261833D01*
X132472Y261958D01*
X132139Y262000D01*
X131722Y261917D01*
X131430Y261708D01*
X131347Y261458D01*
X131389Y261208D01*
X131555Y261000D01*
X132389Y260583D01*
X132764Y260292D01*
X133014Y259875D01*
X133097Y259500D01*
X131347D01*
G01X129914Y261583D02*
X129664Y261833D01*
X129372Y261958D01*
X129039Y262000D01*
X128622Y261917D01*
X128330Y261708D01*
X128247Y261458D01*
X128289Y261208D01*
X128455Y261000D01*
X129289Y260583D01*
X129664Y260292D01*
X129914Y259875D01*
X129997Y259500D01*
X128247D01*
G01X126730Y259792D02*
X126439Y259583D01*
X126105Y259500D01*
X125772Y259583D01*
X125480Y259833D01*
X125272Y260208D01*
X125189Y260583D01*
Y261042D01*
X125272Y261417D01*
X125480Y261750D01*
X125730Y261917D01*
X126022Y262000D01*
X126355Y261917D01*
X126605Y261750D01*
X126772Y261500D01*
X126855Y261167D01*
X126772Y260875D01*
X126564Y260583D01*
X126314Y260417D01*
X126022Y260375D01*
X125689Y260458D01*
X125439Y260667D01*
X125189Y261042D01*
G01X118773Y290642D02*
X119023Y290767D01*
X119315Y290850D01*
X119648D01*
X120023Y290725D01*
X120315Y290517D01*
X120523Y290267D01*
X120690Y289850D01*
X120732Y289475D01*
X120648Y289100D01*
X120523Y288850D01*
X120273Y288600D01*
X119982Y288433D01*
X119690Y288350D01*
X119398D01*
X119107Y288433D01*
X118857Y288558D01*
X118648Y288725D01*
G01X117507D02*
X117257Y288517D01*
X116965Y288392D01*
X116590Y288350D01*
X116215Y288433D01*
X115923Y288600D01*
X115715Y288892D01*
X115673Y289225D01*
X115757Y289558D01*
X115965Y289767D01*
X116257Y289933D01*
X116548Y289975D01*
X116840Y289933D01*
X117215Y289767D01*
X117090Y290850D01*
X115965D01*
G01X114198Y288642D02*
X113907Y288433D01*
X113573Y288350D01*
X113240Y288433D01*
X112948Y288683D01*
X112740Y289058D01*
X112657Y289433D01*
Y289892D01*
X112740Y290267D01*
X112948Y290600D01*
X113198Y290767D01*
X113490Y290850D01*
X113823Y290767D01*
X114073Y290600D01*
X114240Y290350D01*
X114323Y290017D01*
X114240Y289725D01*
X114032Y289433D01*
X113782Y289267D01*
X113490Y289225D01*
X113157Y289308D01*
X112907Y289517D01*
X112657Y289892D01*
G01X111182Y290433D02*
X110932Y290683D01*
X110640Y290808D01*
X110307Y290850D01*
X109890Y290767D01*
X109598Y290558D01*
X109515Y290308D01*
X109557Y290058D01*
X109723Y289850D01*
X110557Y289433D01*
X110932Y289142D01*
X111182Y288725D01*
X111265Y288350D01*
X109515D01*
G01X116432Y253817D02*
X116557Y253567D01*
X116640Y253275D01*
Y252942D01*
X116515Y252567D01*
X116307Y252275D01*
X116057Y252067D01*
X115640Y251900D01*
X115265Y251858D01*
X114890Y251942D01*
X114640Y252067D01*
X114390Y252317D01*
X114223Y252608D01*
X114140Y252900D01*
Y253192D01*
X114223Y253483D01*
X114348Y253733D01*
X114515Y253942D01*
G01Y255083D02*
X114307Y255333D01*
X114182Y255625D01*
X114140Y256000D01*
X114223Y256375D01*
X114390Y256667D01*
X114682Y256875D01*
X115015Y256917D01*
X115348Y256833D01*
X115557Y256625D01*
X115723Y256333D01*
X115765Y256042D01*
X115723Y255750D01*
X115557Y255375D01*
X116640Y255500D01*
Y256625D01*
G01X114432Y258392D02*
X114223Y258683D01*
X114140Y259017D01*
X114223Y259350D01*
X114473Y259642D01*
X114848Y259850D01*
X115223Y259933D01*
X115682D01*
X116057Y259850D01*
X116390Y259642D01*
X116557Y259392D01*
X116640Y259100D01*
X116557Y258767D01*
X116390Y258517D01*
X116140Y258350D01*
X115807Y258267D01*
X115515Y258350D01*
X115223Y258558D01*
X115057Y258808D01*
X115015Y259100D01*
X115098Y259433D01*
X115307Y259683D01*
X115682Y259933D01*
G01X114140Y262200D02*
X116640D01*
X116140Y261700D01*
G01X114140D02*
Y262700D01*
G01X105823Y286642D02*
X106073Y286767D01*
X106365Y286850D01*
X106698D01*
X107073Y286725D01*
X107365Y286517D01*
X107573Y286267D01*
X107740Y285850D01*
X107782Y285475D01*
X107698Y285100D01*
X107573Y284850D01*
X107323Y284600D01*
X107032Y284433D01*
X106740Y284350D01*
X106448D01*
X106157Y284433D01*
X105907Y284558D01*
X105698Y284725D01*
G01X104557D02*
X104307Y284517D01*
X104015Y284392D01*
X103640Y284350D01*
X103265Y284433D01*
X102973Y284600D01*
X102765Y284892D01*
X102723Y285225D01*
X102807Y285558D01*
X103015Y285767D01*
X103307Y285933D01*
X103598Y285975D01*
X103890Y285933D01*
X104265Y285767D01*
X104140Y286850D01*
X103015D01*
G01X101248Y284642D02*
X100957Y284433D01*
X100623Y284350D01*
X100290Y284433D01*
X99998Y284683D01*
X99790Y285058D01*
X99707Y285433D01*
Y285892D01*
X99790Y286267D01*
X99998Y286600D01*
X100248Y286767D01*
X100540Y286850D01*
X100873Y286767D01*
X101123Y286600D01*
X101290Y286350D01*
X101373Y286017D01*
X101290Y285725D01*
X101082Y285433D01*
X100832Y285267D01*
X100540Y285225D01*
X100207Y285308D01*
X99957Y285517D01*
X99707Y285892D01*
G01X97440Y286850D02*
X97773Y286767D01*
X98023Y286558D01*
X98190Y286308D01*
X98315Y285975D01*
X98357Y285600D01*
X98315Y285225D01*
X98190Y284892D01*
X98023Y284642D01*
X97773Y284433D01*
X97440Y284350D01*
X97107Y284433D01*
X96857Y284642D01*
X96690Y284892D01*
X96565Y285225D01*
X96523Y285600D01*
X96565Y285975D01*
X96690Y286308D01*
X96857Y286558D01*
X97107Y286767D01*
X97440Y286850D01*
G01X88292Y266267D02*
X88417Y266017D01*
X88500Y265725D01*
Y265392D01*
X88375Y265017D01*
X88167Y264725D01*
X87917Y264517D01*
X87500Y264350D01*
X87125Y264308D01*
X86750Y264392D01*
X86500Y264517D01*
X86250Y264767D01*
X86083Y265058D01*
X86000Y265350D01*
Y265642D01*
X86083Y265933D01*
X86208Y266183D01*
X86375Y266392D01*
G01Y267533D02*
X86167Y267783D01*
X86042Y268075D01*
X86000Y268450D01*
X86083Y268825D01*
X86250Y269117D01*
X86542Y269325D01*
X86875Y269367D01*
X87208Y269283D01*
X87417Y269075D01*
X87583Y268783D01*
X87625Y268492D01*
X87583Y268200D01*
X87417Y267825D01*
X88500Y267950D01*
Y269075D01*
G01X86000Y271550D02*
X86042Y271842D01*
X86167Y272175D01*
X86375Y272383D01*
X86667Y272467D01*
X86958Y272383D01*
X87208Y272133D01*
X87333Y271758D01*
Y271342D01*
X87417Y271092D01*
X87625Y270883D01*
X87917Y270800D01*
X88208Y270925D01*
X88417Y271217D01*
X88500Y271550D01*
X88417Y271883D01*
X88208Y272175D01*
X87917Y272300D01*
X87625Y272217D01*
X87417Y272008D01*
X87333Y271758D01*
Y271342D01*
X87208Y270967D01*
X86958Y270717D01*
X86667Y270633D01*
X86375Y270717D01*
X86167Y270925D01*
X86042Y271258D01*
X86000Y271550D01*
G01Y274650D02*
X86042Y274942D01*
X86167Y275275D01*
X86375Y275483D01*
X86667Y275567D01*
X86958Y275483D01*
X87208Y275233D01*
X87333Y274858D01*
Y274442D01*
X87417Y274192D01*
X87625Y273983D01*
X87917Y273900D01*
X88208Y274025D01*
X88417Y274317D01*
X88500Y274650D01*
X88417Y274983D01*
X88208Y275275D01*
X87917Y275400D01*
X87625Y275317D01*
X87417Y275108D01*
X87333Y274858D01*
Y274442D01*
X87208Y274067D01*
X86958Y273817D01*
X86667Y273733D01*
X86375Y273817D01*
X86167Y274025D01*
X86042Y274358D01*
X86000Y274650D01*
G01X92532Y253817D02*
X92657Y253567D01*
X92740Y253275D01*
Y252942D01*
X92615Y252567D01*
X92407Y252275D01*
X92157Y252067D01*
X91740Y251900D01*
X91365Y251858D01*
X90990Y251942D01*
X90740Y252067D01*
X90490Y252317D01*
X90323Y252608D01*
X90240Y252900D01*
Y253192D01*
X90323Y253483D01*
X90448Y253733D01*
X90615Y253942D01*
G01Y255083D02*
X90407Y255333D01*
X90282Y255625D01*
X90240Y256000D01*
X90323Y256375D01*
X90490Y256667D01*
X90782Y256875D01*
X91115Y256917D01*
X91448Y256833D01*
X91657Y256625D01*
X91823Y256333D01*
X91865Y256042D01*
X91823Y255750D01*
X91657Y255375D01*
X92740Y255500D01*
Y256625D01*
G01X90240Y259100D02*
X90282Y259392D01*
X90407Y259725D01*
X90615Y259933D01*
X90907Y260017D01*
X91198Y259933D01*
X91448Y259683D01*
X91573Y259308D01*
Y258892D01*
X91657Y258642D01*
X91865Y258433D01*
X92157Y258350D01*
X92448Y258475D01*
X92657Y258767D01*
X92740Y259100D01*
X92657Y259433D01*
X92448Y259725D01*
X92157Y259850D01*
X91865Y259767D01*
X91657Y259558D01*
X91573Y259308D01*
Y258892D01*
X91448Y258517D01*
X91198Y258267D01*
X90907Y258183D01*
X90615Y258267D01*
X90407Y258475D01*
X90282Y258808D01*
X90240Y259100D01*
G01X90615Y261283D02*
X90407Y261533D01*
X90282Y261825D01*
X90240Y262200D01*
X90323Y262575D01*
X90490Y262867D01*
X90782Y263075D01*
X91115Y263117D01*
X91448Y263033D01*
X91657Y262825D01*
X91823Y262533D01*
X91865Y262242D01*
X91823Y261950D01*
X91657Y261575D01*
X92740Y261700D01*
Y262825D01*
G01X80292Y266267D02*
X80417Y266017D01*
X80500Y265725D01*
Y265392D01*
X80375Y265017D01*
X80167Y264725D01*
X79917Y264517D01*
X79500Y264350D01*
X79125Y264308D01*
X78750Y264392D01*
X78500Y264517D01*
X78250Y264767D01*
X78083Y265058D01*
X78000Y265350D01*
Y265642D01*
X78083Y265933D01*
X78208Y266183D01*
X78375Y266392D01*
G01Y267533D02*
X78167Y267783D01*
X78042Y268075D01*
X78000Y268450D01*
X78083Y268825D01*
X78250Y269117D01*
X78542Y269325D01*
X78875Y269367D01*
X79208Y269283D01*
X79417Y269075D01*
X79583Y268783D01*
X79625Y268492D01*
X79583Y268200D01*
X79417Y267825D01*
X80500Y267950D01*
Y269075D01*
G01X78000Y271550D02*
X78042Y271842D01*
X78167Y272175D01*
X78375Y272383D01*
X78667Y272467D01*
X78958Y272383D01*
X79208Y272133D01*
X79333Y271758D01*
Y271342D01*
X79417Y271092D01*
X79625Y270883D01*
X79917Y270800D01*
X80208Y270925D01*
X80417Y271217D01*
X80500Y271550D01*
X80417Y271883D01*
X80208Y272175D01*
X79917Y272300D01*
X79625Y272217D01*
X79417Y272008D01*
X79333Y271758D01*
Y271342D01*
X79208Y270967D01*
X78958Y270717D01*
X78667Y270633D01*
X78375Y270717D01*
X78167Y270925D01*
X78042Y271258D01*
X78000Y271550D01*
G01Y275150D02*
X80500D01*
X78708Y273608D01*
Y275692D01*
G01X105823Y298642D02*
X106073Y298767D01*
X106365Y298850D01*
X106698D01*
X107073Y298725D01*
X107365Y298517D01*
X107573Y298267D01*
X107740Y297850D01*
X107782Y297475D01*
X107698Y297100D01*
X107573Y296850D01*
X107323Y296600D01*
X107032Y296433D01*
X106740Y296350D01*
X106448D01*
X106157Y296433D01*
X105907Y296558D01*
X105698Y296725D01*
G01X104557D02*
X104307Y296517D01*
X104015Y296392D01*
X103640Y296350D01*
X103265Y296433D01*
X102973Y296600D01*
X102765Y296892D01*
X102723Y297225D01*
X102807Y297558D01*
X103015Y297767D01*
X103307Y297933D01*
X103598Y297975D01*
X103890Y297933D01*
X104265Y297767D01*
X104140Y298850D01*
X103015D01*
G01X101457Y296850D02*
X101207Y296558D01*
X100873Y296392D01*
X100498Y296350D01*
X100165Y296392D01*
X99832Y296600D01*
X99623Y296850D01*
X99582Y297100D01*
X99665Y297392D01*
X99957Y297600D01*
X100248Y297683D01*
X100623D01*
G01X100248D02*
X99998Y297808D01*
X99790Y298017D01*
X99707Y298267D01*
X99790Y298517D01*
X99998Y298725D01*
X100373Y298850D01*
X100748Y298808D01*
X101123Y298642D01*
G01X98232Y297392D02*
X97940Y297683D01*
X97690Y297850D01*
X97357Y297933D01*
X97065Y297850D01*
X96857Y297683D01*
X96690Y297433D01*
X96648Y297142D01*
X96690Y296892D01*
X96857Y296642D01*
X97107Y296433D01*
X97398Y296350D01*
X97732Y296433D01*
X98023Y296683D01*
X98190Y297058D01*
X98232Y297475D01*
X98148Y298017D01*
X98023Y298308D01*
X97815Y298600D01*
X97523Y298808D01*
X97232Y298850D01*
X96940Y298767D01*
X96732Y298558D01*
G01X118823Y294642D02*
X119073Y294767D01*
X119365Y294850D01*
X119698D01*
X120073Y294725D01*
X120365Y294517D01*
X120573Y294267D01*
X120740Y293850D01*
X120782Y293475D01*
X120698Y293100D01*
X120573Y292850D01*
X120323Y292600D01*
X120032Y292433D01*
X119740Y292350D01*
X119448D01*
X119157Y292433D01*
X118907Y292558D01*
X118698Y292725D01*
G01X117557D02*
X117307Y292517D01*
X117015Y292392D01*
X116640Y292350D01*
X116265Y292433D01*
X115973Y292600D01*
X115765Y292892D01*
X115723Y293225D01*
X115807Y293558D01*
X116015Y293767D01*
X116307Y293933D01*
X116598Y293975D01*
X116890Y293933D01*
X117265Y293767D01*
X117140Y294850D01*
X116015D01*
G01X113540Y292350D02*
Y294850D01*
X114040Y294350D01*
G01Y292350D02*
X113040D01*
G01X109940D02*
Y294850D01*
X111482Y293058D01*
X109398D01*
G01X92292Y266267D02*
X92417Y266017D01*
X92500Y265725D01*
Y265392D01*
X92375Y265017D01*
X92167Y264725D01*
X91917Y264517D01*
X91500Y264350D01*
X91125Y264308D01*
X90750Y264392D01*
X90500Y264517D01*
X90250Y264767D01*
X90083Y265058D01*
X90000Y265350D01*
Y265642D01*
X90083Y265933D01*
X90208Y266183D01*
X90375Y266392D01*
G01Y267533D02*
X90167Y267783D01*
X90042Y268075D01*
X90000Y268450D01*
X90083Y268825D01*
X90250Y269117D01*
X90542Y269325D01*
X90875Y269367D01*
X91208Y269283D01*
X91417Y269075D01*
X91583Y268783D01*
X91625Y268492D01*
X91583Y268200D01*
X91417Y267825D01*
X92500Y267950D01*
Y269075D01*
G01X90000Y271550D02*
X92500D01*
X92000Y271050D01*
G01X90000D02*
Y272050D01*
G01X90500Y273733D02*
X90208Y273983D01*
X90042Y274317D01*
X90000Y274692D01*
X90042Y275025D01*
X90250Y275358D01*
X90500Y275567D01*
X90750Y275608D01*
X91042Y275525D01*
X91250Y275233D01*
X91333Y274942D01*
Y274567D01*
G01Y274942D02*
X91458Y275192D01*
X91667Y275400D01*
X91917Y275483D01*
X92167Y275400D01*
X92375Y275192D01*
X92500Y274817D01*
X92458Y274442D01*
X92292Y274067D01*
G01X84292Y266267D02*
X84417Y266017D01*
X84500Y265725D01*
Y265392D01*
X84375Y265017D01*
X84167Y264725D01*
X83917Y264517D01*
X83500Y264350D01*
X83125Y264308D01*
X82750Y264392D01*
X82500Y264517D01*
X82250Y264767D01*
X82083Y265058D01*
X82000Y265350D01*
Y265642D01*
X82083Y265933D01*
X82208Y266183D01*
X82375Y266392D01*
G01Y267533D02*
X82167Y267783D01*
X82042Y268075D01*
X82000Y268450D01*
X82083Y268825D01*
X82250Y269117D01*
X82542Y269325D01*
X82875Y269367D01*
X83208Y269283D01*
X83417Y269075D01*
X83583Y268783D01*
X83625Y268492D01*
X83583Y268200D01*
X83417Y267825D01*
X84500Y267950D01*
Y269075D01*
G01X82000Y271550D02*
X84500D01*
X84000Y271050D01*
G01X82000D02*
Y272050D01*
G01X84083Y273858D02*
X84333Y274108D01*
X84458Y274400D01*
X84500Y274733D01*
X84417Y275150D01*
X84208Y275442D01*
X83958Y275525D01*
X83708Y275483D01*
X83500Y275317D01*
X83083Y274483D01*
X82792Y274108D01*
X82375Y273858D01*
X82000Y273775D01*
Y275525D01*
G01X118823Y302642D02*
X119073Y302767D01*
X119365Y302850D01*
X119698D01*
X120073Y302725D01*
X120365Y302517D01*
X120573Y302267D01*
X120740Y301850D01*
X120782Y301475D01*
X120698Y301100D01*
X120573Y300850D01*
X120323Y300600D01*
X120032Y300433D01*
X119740Y300350D01*
X119448D01*
X119157Y300433D01*
X118907Y300558D01*
X118698Y300725D01*
G01X117557Y300850D02*
X117307Y300558D01*
X116973Y300392D01*
X116598Y300350D01*
X116265Y300392D01*
X115932Y300600D01*
X115723Y300850D01*
X115682Y301100D01*
X115765Y301392D01*
X116057Y301600D01*
X116348Y301683D01*
X116723D01*
G01X116348D02*
X116098Y301808D01*
X115890Y302017D01*
X115807Y302267D01*
X115890Y302517D01*
X116098Y302725D01*
X116473Y302850D01*
X116848Y302808D01*
X117223Y302642D01*
G01X113540Y302850D02*
X113873Y302767D01*
X114123Y302558D01*
X114290Y302308D01*
X114415Y301975D01*
X114457Y301600D01*
X114415Y301225D01*
X114290Y300892D01*
X114123Y300642D01*
X113873Y300433D01*
X113540Y300350D01*
X113207Y300433D01*
X112957Y300642D01*
X112790Y300892D01*
X112665Y301225D01*
X112623Y301600D01*
X112665Y301975D01*
X112790Y302308D01*
X112957Y302558D01*
X113207Y302767D01*
X113540Y302850D01*
G01X109940Y300350D02*
Y302850D01*
X111482Y301058D01*
X109398D01*
G01X105823Y294642D02*
X106073Y294767D01*
X106365Y294850D01*
X106698D01*
X107073Y294725D01*
X107365Y294517D01*
X107573Y294267D01*
X107740Y293850D01*
X107782Y293475D01*
X107698Y293100D01*
X107573Y292850D01*
X107323Y292600D01*
X107032Y292433D01*
X106740Y292350D01*
X106448D01*
X106157Y292433D01*
X105907Y292558D01*
X105698Y292725D01*
G01X104557Y292850D02*
X104307Y292558D01*
X103973Y292392D01*
X103598Y292350D01*
X103265Y292392D01*
X102932Y292600D01*
X102723Y292850D01*
X102682Y293100D01*
X102765Y293392D01*
X103057Y293600D01*
X103348Y293683D01*
X103723D01*
G01X103348D02*
X103098Y293808D01*
X102890Y294017D01*
X102807Y294267D01*
X102890Y294517D01*
X103098Y294725D01*
X103473Y294850D01*
X103848Y294808D01*
X104223Y294642D01*
G01X100540Y294850D02*
X100873Y294767D01*
X101123Y294558D01*
X101290Y294308D01*
X101415Y293975D01*
X101457Y293600D01*
X101415Y293225D01*
X101290Y292892D01*
X101123Y292642D01*
X100873Y292433D01*
X100540Y292350D01*
X100207Y292433D01*
X99957Y292642D01*
X99790Y292892D01*
X99665Y293225D01*
X99623Y293600D01*
X99665Y293975D01*
X99790Y294308D01*
X99957Y294558D01*
X100207Y294767D01*
X100540Y294850D01*
G01X97440Y292350D02*
Y294850D01*
X97940Y294350D01*
G01Y292350D02*
X96940D01*
G01X119406Y278186D02*
X119656Y278311D01*
X119948Y278394D01*
X120281D01*
X120656Y278269D01*
X120948Y278061D01*
X121156Y277811D01*
X121323Y277394D01*
X121365Y277019D01*
X121281Y276644D01*
X121156Y276394D01*
X120906Y276144D01*
X120615Y275977D01*
X120323Y275894D01*
X120031D01*
X119740Y275977D01*
X119490Y276102D01*
X119281Y276269D01*
G01X118015Y277977D02*
X117765Y278227D01*
X117473Y278352D01*
X117140Y278394D01*
X116723Y278311D01*
X116431Y278102D01*
X116348Y277852D01*
X116390Y277602D01*
X116556Y277394D01*
X117390Y276977D01*
X117765Y276686D01*
X118015Y276269D01*
X118098Y275894D01*
X116348D01*
G01X114831Y276186D02*
X114540Y275977D01*
X114206Y275894D01*
X113873Y275977D01*
X113581Y276227D01*
X113373Y276602D01*
X113290Y276977D01*
Y277436D01*
X113373Y277811D01*
X113581Y278144D01*
X113831Y278311D01*
X114123Y278394D01*
X114456Y278311D01*
X114706Y278144D01*
X114873Y277894D01*
X114956Y277561D01*
X114873Y277269D01*
X114665Y276977D01*
X114415Y276811D01*
X114123Y276769D01*
X113790Y276852D01*
X113540Y277061D01*
X113290Y277436D01*
G01X111940Y276394D02*
X111690Y276102D01*
X111356Y275936D01*
X110981Y275894D01*
X110648Y275936D01*
X110315Y276144D01*
X110106Y276394D01*
X110065Y276644D01*
X110148Y276936D01*
X110440Y277144D01*
X110731Y277227D01*
X111106D01*
G01X110731D02*
X110481Y277352D01*
X110273Y277561D01*
X110190Y277811D01*
X110273Y278061D01*
X110481Y278269D01*
X110856Y278394D01*
X111231Y278352D01*
X111606Y278186D01*
G01X96292Y266267D02*
X96417Y266017D01*
X96500Y265725D01*
Y265392D01*
X96375Y265017D01*
X96167Y264725D01*
X95917Y264517D01*
X95500Y264350D01*
X95125Y264308D01*
X94750Y264392D01*
X94500Y264517D01*
X94250Y264767D01*
X94083Y265058D01*
X94000Y265350D01*
Y265642D01*
X94083Y265933D01*
X94208Y266183D01*
X94375Y266392D01*
G01X96083Y267658D02*
X96333Y267908D01*
X96458Y268200D01*
X96500Y268533D01*
X96417Y268950D01*
X96208Y269242D01*
X95958Y269325D01*
X95708Y269283D01*
X95500Y269117D01*
X95083Y268283D01*
X94792Y267908D01*
X94375Y267658D01*
X94000Y267575D01*
Y269325D01*
G01X94292Y270842D02*
X94083Y271133D01*
X94000Y271467D01*
X94083Y271800D01*
X94333Y272092D01*
X94708Y272300D01*
X95083Y272383D01*
X95542D01*
X95917Y272300D01*
X96250Y272092D01*
X96417Y271842D01*
X96500Y271550D01*
X96417Y271217D01*
X96250Y270967D01*
X96000Y270800D01*
X95667Y270717D01*
X95375Y270800D01*
X95083Y271008D01*
X94917Y271258D01*
X94875Y271550D01*
X94958Y271883D01*
X95167Y272133D01*
X95542Y272383D01*
G01X94000Y274650D02*
X96500D01*
X96000Y274150D01*
G01X94000D02*
Y275150D01*
G01X119423Y282642D02*
X119673Y282767D01*
X119965Y282850D01*
X120298D01*
X120673Y282725D01*
X120965Y282517D01*
X121173Y282267D01*
X121340Y281850D01*
X121382Y281475D01*
X121298Y281100D01*
X121173Y280850D01*
X120923Y280600D01*
X120632Y280433D01*
X120340Y280350D01*
X120048D01*
X119757Y280433D01*
X119507Y280558D01*
X119298Y280725D01*
G01X118032Y282433D02*
X117782Y282683D01*
X117490Y282808D01*
X117157Y282850D01*
X116740Y282767D01*
X116448Y282558D01*
X116365Y282308D01*
X116407Y282058D01*
X116573Y281850D01*
X117407Y281433D01*
X117782Y281142D01*
X118032Y280725D01*
X118115Y280350D01*
X116365D01*
G01X114140D02*
X113848Y280392D01*
X113515Y280517D01*
X113307Y280725D01*
X113223Y281017D01*
X113307Y281308D01*
X113557Y281558D01*
X113932Y281683D01*
X114348D01*
X114598Y281767D01*
X114807Y281975D01*
X114890Y282267D01*
X114765Y282558D01*
X114473Y282767D01*
X114140Y282850D01*
X113807Y282767D01*
X113515Y282558D01*
X113390Y282267D01*
X113473Y281975D01*
X113682Y281767D01*
X113932Y281683D01*
X114348D01*
X114723Y281558D01*
X114973Y281308D01*
X115057Y281017D01*
X114973Y280725D01*
X114765Y280517D01*
X114432Y280392D01*
X114140Y280350D01*
G01X111832Y281392D02*
X111540Y281683D01*
X111290Y281850D01*
X110957Y281933D01*
X110665Y281850D01*
X110457Y281683D01*
X110290Y281433D01*
X110248Y281142D01*
X110290Y280892D01*
X110457Y280642D01*
X110707Y280433D01*
X110998Y280350D01*
X111332Y280433D01*
X111623Y280683D01*
X111790Y281058D01*
X111832Y281475D01*
X111748Y282017D01*
X111623Y282308D01*
X111415Y282600D01*
X111123Y282808D01*
X110832Y282850D01*
X110540Y282767D01*
X110332Y282558D01*
G01X108292Y266267D02*
X108417Y266017D01*
X108500Y265725D01*
Y265392D01*
X108375Y265017D01*
X108167Y264725D01*
X107917Y264517D01*
X107500Y264350D01*
X107125Y264308D01*
X106750Y264392D01*
X106500Y264517D01*
X106250Y264767D01*
X106083Y265058D01*
X106000Y265350D01*
Y265642D01*
X106083Y265933D01*
X106208Y266183D01*
X106375Y266392D01*
G01X108083Y267658D02*
X108333Y267908D01*
X108458Y268200D01*
X108500Y268533D01*
X108417Y268950D01*
X108208Y269242D01*
X107958Y269325D01*
X107708Y269283D01*
X107500Y269117D01*
X107083Y268283D01*
X106792Y267908D01*
X106375Y267658D01*
X106000Y267575D01*
Y269325D01*
G01Y271550D02*
X106042Y271842D01*
X106167Y272175D01*
X106375Y272383D01*
X106667Y272467D01*
X106958Y272383D01*
X107208Y272133D01*
X107333Y271758D01*
Y271342D01*
X107417Y271092D01*
X107625Y270883D01*
X107917Y270800D01*
X108208Y270925D01*
X108417Y271217D01*
X108500Y271550D01*
X108417Y271883D01*
X108208Y272175D01*
X107917Y272300D01*
X107625Y272217D01*
X107417Y272008D01*
X107333Y271758D01*
Y271342D01*
X107208Y270967D01*
X106958Y270717D01*
X106667Y270633D01*
X106375Y270717D01*
X106167Y270925D01*
X106042Y271258D01*
X106000Y271550D01*
G01X108083Y273858D02*
X108333Y274108D01*
X108458Y274400D01*
X108500Y274733D01*
X108417Y275150D01*
X108208Y275442D01*
X107958Y275525D01*
X107708Y275483D01*
X107500Y275317D01*
X107083Y274483D01*
X106792Y274108D01*
X106375Y273858D01*
X106000Y273775D01*
Y275525D01*
G01X119233Y274292D02*
X119483Y274417D01*
X119775Y274500D01*
X120108D01*
X120483Y274375D01*
X120775Y274167D01*
X120983Y273917D01*
X121150Y273500D01*
X121192Y273125D01*
X121108Y272750D01*
X120983Y272500D01*
X120733Y272250D01*
X120442Y272083D01*
X120150Y272000D01*
X119858D01*
X119567Y272083D01*
X119317Y272208D01*
X119108Y272375D01*
G01X117842Y274083D02*
X117592Y274333D01*
X117300Y274458D01*
X116967Y274500D01*
X116550Y274417D01*
X116258Y274208D01*
X116175Y273958D01*
X116217Y273708D01*
X116383Y273500D01*
X117217Y273083D01*
X117592Y272792D01*
X117842Y272375D01*
X117925Y272000D01*
X116175D01*
G01X114033D02*
X113950Y272542D01*
X113825Y273000D01*
X113658Y273417D01*
X113450Y273875D01*
X113117Y274500D01*
X114783D01*
G01X110850Y272000D02*
X110558Y272042D01*
X110225Y272167D01*
X110017Y272375D01*
X109933Y272667D01*
X110017Y272958D01*
X110267Y273208D01*
X110642Y273333D01*
X111058D01*
X111308Y273417D01*
X111517Y273625D01*
X111600Y273917D01*
X111475Y274208D01*
X111183Y274417D01*
X110850Y274500D01*
X110517Y274417D01*
X110225Y274208D01*
X110100Y273917D01*
X110183Y273625D01*
X110392Y273417D01*
X110642Y273333D01*
X111058D01*
X111433Y273208D01*
X111683Y272958D01*
X111767Y272667D01*
X111683Y272375D01*
X111475Y272167D01*
X111142Y272042D01*
X110850Y272000D01*
G01X100292Y266267D02*
X100417Y266017D01*
X100500Y265725D01*
Y265392D01*
X100375Y265017D01*
X100167Y264725D01*
X99917Y264517D01*
X99500Y264350D01*
X99125Y264308D01*
X98750Y264392D01*
X98500Y264517D01*
X98250Y264767D01*
X98083Y265058D01*
X98000Y265350D01*
Y265642D01*
X98083Y265933D01*
X98208Y266183D01*
X98375Y266392D01*
G01X100083Y267658D02*
X100333Y267908D01*
X100458Y268200D01*
X100500Y268533D01*
X100417Y268950D01*
X100208Y269242D01*
X99958Y269325D01*
X99708Y269283D01*
X99500Y269117D01*
X99083Y268283D01*
X98792Y267908D01*
X98375Y267658D01*
X98000Y267575D01*
Y269325D01*
G01Y271467D02*
X98542Y271550D01*
X99000Y271675D01*
X99417Y271842D01*
X99875Y272050D01*
X100500Y272383D01*
Y270717D01*
G01X99042Y273858D02*
X99333Y274150D01*
X99500Y274400D01*
X99583Y274733D01*
X99500Y275025D01*
X99333Y275233D01*
X99083Y275400D01*
X98792Y275442D01*
X98542Y275400D01*
X98292Y275233D01*
X98083Y274983D01*
X98000Y274692D01*
X98083Y274358D01*
X98333Y274067D01*
X98708Y273900D01*
X99125Y273858D01*
X99667Y273942D01*
X99958Y274067D01*
X100250Y274275D01*
X100458Y274567D01*
X100500Y274858D01*
X100417Y275150D01*
X100208Y275358D01*
G01X134233Y253292D02*
X134483Y253417D01*
X134775Y253500D01*
X135108D01*
X135483Y253375D01*
X135775Y253167D01*
X135983Y252917D01*
X136150Y252500D01*
X136192Y252125D01*
X136108Y251750D01*
X135983Y251500D01*
X135733Y251250D01*
X135442Y251083D01*
X135150Y251000D01*
X134858D01*
X134567Y251083D01*
X134317Y251208D01*
X134108Y251375D01*
G01X132842Y253083D02*
X132592Y253333D01*
X132300Y253458D01*
X131967Y253500D01*
X131550Y253417D01*
X131258Y253208D01*
X131175Y252958D01*
X131217Y252708D01*
X131383Y252500D01*
X132217Y252083D01*
X132592Y251792D01*
X132842Y251375D01*
X132925Y251000D01*
X131175D01*
G01X129033D02*
X128950Y251542D01*
X128825Y252000D01*
X128658Y252417D01*
X128450Y252875D01*
X128117Y253500D01*
X129783D01*
G01X126767Y251500D02*
X126517Y251208D01*
X126183Y251042D01*
X125808Y251000D01*
X125475Y251042D01*
X125142Y251250D01*
X124933Y251500D01*
X124892Y251750D01*
X124975Y252042D01*
X125267Y252250D01*
X125558Y252333D01*
X125933D01*
G01X125558D02*
X125308Y252458D01*
X125100Y252667D01*
X125017Y252917D01*
X125100Y253167D01*
X125308Y253375D01*
X125683Y253500D01*
X126058Y253458D01*
X126433Y253292D01*
G01X134405Y273411D02*
X134655Y273536D01*
X134947Y273619D01*
X135280D01*
X135655Y273494D01*
X135947Y273286D01*
X136155Y273036D01*
X136322Y272619D01*
X136364Y272244D01*
X136280Y271869D01*
X136155Y271619D01*
X135905Y271369D01*
X135614Y271202D01*
X135322Y271119D01*
X135030D01*
X134739Y271202D01*
X134489Y271327D01*
X134280Y271494D01*
G01X133014Y273202D02*
X132764Y273452D01*
X132472Y273577D01*
X132139Y273619D01*
X131722Y273536D01*
X131430Y273327D01*
X131347Y273077D01*
X131389Y272827D01*
X131555Y272619D01*
X132389Y272202D01*
X132764Y271911D01*
X133014Y271494D01*
X133097Y271119D01*
X131347D01*
G01X129205D02*
X129122Y271661D01*
X128997Y272119D01*
X128830Y272536D01*
X128622Y272994D01*
X128289Y273619D01*
X129955D01*
G01X126814Y273202D02*
X126564Y273452D01*
X126272Y273577D01*
X125939Y273619D01*
X125522Y273536D01*
X125230Y273327D01*
X125147Y273077D01*
X125189Y272827D01*
X125355Y272619D01*
X126189Y272202D01*
X126564Y271911D01*
X126814Y271494D01*
X126897Y271119D01*
X125147D01*
G01X105823Y290642D02*
X106073Y290767D01*
X106365Y290850D01*
X106698D01*
X107073Y290725D01*
X107365Y290517D01*
X107573Y290267D01*
X107740Y289850D01*
X107782Y289475D01*
X107698Y289100D01*
X107573Y288850D01*
X107323Y288600D01*
X107032Y288433D01*
X106740Y288350D01*
X106448D01*
X106157Y288433D01*
X105907Y288558D01*
X105698Y288725D01*
G01X104432Y290433D02*
X104182Y290683D01*
X103890Y290808D01*
X103557Y290850D01*
X103140Y290767D01*
X102848Y290558D01*
X102765Y290308D01*
X102807Y290058D01*
X102973Y289850D01*
X103807Y289433D01*
X104182Y289142D01*
X104432Y288725D01*
X104515Y288350D01*
X102765D01*
G01X101332Y289392D02*
X101040Y289683D01*
X100790Y289850D01*
X100457Y289933D01*
X100165Y289850D01*
X99957Y289683D01*
X99790Y289433D01*
X99748Y289142D01*
X99790Y288892D01*
X99957Y288642D01*
X100207Y288433D01*
X100498Y288350D01*
X100832Y288433D01*
X101123Y288683D01*
X101290Y289058D01*
X101332Y289475D01*
X101248Y290017D01*
X101123Y290308D01*
X100915Y290600D01*
X100623Y290808D01*
X100332Y290850D01*
X100040Y290767D01*
X99832Y290558D01*
G01X98148Y288642D02*
X97857Y288433D01*
X97523Y288350D01*
X97190Y288433D01*
X96898Y288683D01*
X96690Y289058D01*
X96607Y289433D01*
Y289892D01*
X96690Y290267D01*
X96898Y290600D01*
X97148Y290767D01*
X97440Y290850D01*
X97773Y290767D01*
X98023Y290600D01*
X98190Y290350D01*
X98273Y290017D01*
X98190Y289725D01*
X97982Y289433D01*
X97732Y289267D01*
X97440Y289225D01*
X97107Y289308D01*
X96857Y289517D01*
X96607Y289892D01*
G01X102032Y253817D02*
X102157Y253567D01*
X102240Y253275D01*
Y252942D01*
X102115Y252567D01*
X101907Y252275D01*
X101657Y252067D01*
X101240Y251900D01*
X100865Y251858D01*
X100490Y251942D01*
X100240Y252067D01*
X99990Y252317D01*
X99823Y252608D01*
X99740Y252900D01*
Y253192D01*
X99823Y253483D01*
X99948Y253733D01*
X100115Y253942D01*
G01X101823Y255208D02*
X102073Y255458D01*
X102198Y255750D01*
X102240Y256083D01*
X102157Y256500D01*
X101948Y256792D01*
X101698Y256875D01*
X101448Y256833D01*
X101240Y256667D01*
X100823Y255833D01*
X100532Y255458D01*
X100115Y255208D01*
X99740Y255125D01*
Y256875D01*
G01X100782Y258308D02*
X101073Y258600D01*
X101240Y258850D01*
X101323Y259183D01*
X101240Y259475D01*
X101073Y259683D01*
X100823Y259850D01*
X100532Y259892D01*
X100282Y259850D01*
X100032Y259683D01*
X99823Y259433D01*
X99740Y259142D01*
X99823Y258808D01*
X100073Y258517D01*
X100448Y258350D01*
X100865Y258308D01*
X101407Y258392D01*
X101698Y258517D01*
X101990Y258725D01*
X102198Y259017D01*
X102240Y259308D01*
X102157Y259600D01*
X101948Y259808D01*
G01X99740Y262200D02*
X99782Y262492D01*
X99907Y262825D01*
X100115Y263033D01*
X100407Y263117D01*
X100698Y263033D01*
X100948Y262783D01*
X101073Y262408D01*
Y261992D01*
X101157Y261742D01*
X101365Y261533D01*
X101657Y261450D01*
X101948Y261575D01*
X102157Y261867D01*
X102240Y262200D01*
X102157Y262533D01*
X101948Y262825D01*
X101657Y262950D01*
X101365Y262867D01*
X101157Y262658D01*
X101073Y262408D01*
Y261992D01*
X100948Y261617D01*
X100698Y261367D01*
X100407Y261283D01*
X100115Y261367D01*
X99907Y261575D01*
X99782Y261908D01*
X99740Y262200D01*
G01X107482Y253817D02*
X107607Y253567D01*
X107690Y253275D01*
Y252942D01*
X107565Y252567D01*
X107357Y252275D01*
X107107Y252067D01*
X106690Y251900D01*
X106315Y251858D01*
X105940Y251942D01*
X105690Y252067D01*
X105440Y252317D01*
X105273Y252608D01*
X105190Y252900D01*
Y253192D01*
X105273Y253483D01*
X105398Y253733D01*
X105565Y253942D01*
G01X107273Y255208D02*
X107523Y255458D01*
X107648Y255750D01*
X107690Y256083D01*
X107607Y256500D01*
X107398Y256792D01*
X107148Y256875D01*
X106898Y256833D01*
X106690Y256667D01*
X106273Y255833D01*
X105982Y255458D01*
X105565Y255208D01*
X105190Y255125D01*
Y256875D01*
G01X106232Y258308D02*
X106523Y258600D01*
X106690Y258850D01*
X106773Y259183D01*
X106690Y259475D01*
X106523Y259683D01*
X106273Y259850D01*
X105982Y259892D01*
X105732Y259850D01*
X105482Y259683D01*
X105273Y259433D01*
X105190Y259142D01*
X105273Y258808D01*
X105523Y258517D01*
X105898Y258350D01*
X106315Y258308D01*
X106857Y258392D01*
X107148Y258517D01*
X107440Y258725D01*
X107648Y259017D01*
X107690Y259308D01*
X107607Y259600D01*
X107398Y259808D01*
G01X105190Y262117D02*
X105732Y262200D01*
X106190Y262325D01*
X106607Y262492D01*
X107065Y262700D01*
X107690Y263033D01*
Y261367D01*
G01X83932Y253817D02*
X84057Y253567D01*
X84140Y253275D01*
Y252942D01*
X84015Y252567D01*
X83807Y252275D01*
X83557Y252067D01*
X83140Y251900D01*
X82765Y251858D01*
X82390Y251942D01*
X82140Y252067D01*
X81890Y252317D01*
X81723Y252608D01*
X81640Y252900D01*
Y253192D01*
X81723Y253483D01*
X81848Y253733D01*
X82015Y253942D01*
G01X83723Y255208D02*
X83973Y255458D01*
X84098Y255750D01*
X84140Y256083D01*
X84057Y256500D01*
X83848Y256792D01*
X83598Y256875D01*
X83348Y256833D01*
X83140Y256667D01*
X82723Y255833D01*
X82432Y255458D01*
X82015Y255208D01*
X81640Y255125D01*
Y256875D01*
G01X82682Y258308D02*
X82973Y258600D01*
X83140Y258850D01*
X83223Y259183D01*
X83140Y259475D01*
X82973Y259683D01*
X82723Y259850D01*
X82432Y259892D01*
X82182Y259850D01*
X81932Y259683D01*
X81723Y259433D01*
X81640Y259142D01*
X81723Y258808D01*
X81973Y258517D01*
X82348Y258350D01*
X82765Y258308D01*
X83307Y258392D01*
X83598Y258517D01*
X83890Y258725D01*
X84098Y259017D01*
X84140Y259308D01*
X84057Y259600D01*
X83848Y259808D01*
G01X82682Y261408D02*
X82973Y261700D01*
X83140Y261950D01*
X83223Y262283D01*
X83140Y262575D01*
X82973Y262783D01*
X82723Y262950D01*
X82432Y262992D01*
X82182Y262950D01*
X81932Y262783D01*
X81723Y262533D01*
X81640Y262242D01*
X81723Y261908D01*
X81973Y261617D01*
X82348Y261450D01*
X82765Y261408D01*
X83307Y261492D01*
X83598Y261617D01*
X83890Y261825D01*
X84098Y262117D01*
X84140Y262408D01*
X84057Y262700D01*
X83848Y262908D01*
G01X89032Y253817D02*
X89157Y253567D01*
X89240Y253275D01*
Y252942D01*
X89115Y252567D01*
X88907Y252275D01*
X88657Y252067D01*
X88240Y251900D01*
X87865Y251858D01*
X87490Y251942D01*
X87240Y252067D01*
X86990Y252317D01*
X86823Y252608D01*
X86740Y252900D01*
Y253192D01*
X86823Y253483D01*
X86948Y253733D01*
X87115Y253942D01*
G01X88823Y255208D02*
X89073Y255458D01*
X89198Y255750D01*
X89240Y256083D01*
X89157Y256500D01*
X88948Y256792D01*
X88698Y256875D01*
X88448Y256833D01*
X88240Y256667D01*
X87823Y255833D01*
X87532Y255458D01*
X87115Y255208D01*
X86740Y255125D01*
Y256875D01*
G01X87782Y258308D02*
X88073Y258600D01*
X88240Y258850D01*
X88323Y259183D01*
X88240Y259475D01*
X88073Y259683D01*
X87823Y259850D01*
X87532Y259892D01*
X87282Y259850D01*
X87032Y259683D01*
X86823Y259433D01*
X86740Y259142D01*
X86823Y258808D01*
X87073Y258517D01*
X87448Y258350D01*
X87865Y258308D01*
X88407Y258392D01*
X88698Y258517D01*
X88990Y258725D01*
X89198Y259017D01*
X89240Y259308D01*
X89157Y259600D01*
X88948Y259808D01*
G01X87115Y261283D02*
X86907Y261533D01*
X86782Y261825D01*
X86740Y262200D01*
X86823Y262575D01*
X86990Y262867D01*
X87282Y263075D01*
X87615Y263117D01*
X87948Y263033D01*
X88157Y262825D01*
X88323Y262533D01*
X88365Y262242D01*
X88323Y261950D01*
X88157Y261575D01*
X89240Y261700D01*
Y262825D01*
G01X119982Y253817D02*
X120107Y253567D01*
X120190Y253275D01*
Y252942D01*
X120065Y252567D01*
X119857Y252275D01*
X119607Y252067D01*
X119190Y251900D01*
X118815Y251858D01*
X118440Y251942D01*
X118190Y252067D01*
X117940Y252317D01*
X117773Y252608D01*
X117690Y252900D01*
Y253192D01*
X117773Y253483D01*
X117898Y253733D01*
X118065Y253942D01*
G01X119773Y255208D02*
X120023Y255458D01*
X120148Y255750D01*
X120190Y256083D01*
X120107Y256500D01*
X119898Y256792D01*
X119648Y256875D01*
X119398Y256833D01*
X119190Y256667D01*
X118773Y255833D01*
X118482Y255458D01*
X118065Y255208D01*
X117690Y255125D01*
Y256875D01*
G01X118732Y258308D02*
X119023Y258600D01*
X119190Y258850D01*
X119273Y259183D01*
X119190Y259475D01*
X119023Y259683D01*
X118773Y259850D01*
X118482Y259892D01*
X118232Y259850D01*
X117982Y259683D01*
X117773Y259433D01*
X117690Y259142D01*
X117773Y258808D01*
X118023Y258517D01*
X118398Y258350D01*
X118815Y258308D01*
X119357Y258392D01*
X119648Y258517D01*
X119940Y258725D01*
X120148Y259017D01*
X120190Y259308D01*
X120107Y259600D01*
X119898Y259808D01*
G01X120190Y262200D02*
X120107Y261867D01*
X119898Y261617D01*
X119648Y261450D01*
X119315Y261325D01*
X118940Y261283D01*
X118565Y261325D01*
X118232Y261450D01*
X117982Y261617D01*
X117773Y261867D01*
X117690Y262200D01*
X117773Y262533D01*
X117982Y262783D01*
X118232Y262950D01*
X118565Y263075D01*
X118940Y263117D01*
X119315Y263075D01*
X119648Y262950D01*
X119898Y262783D01*
X120107Y262533D01*
X120190Y262200D01*
G01X110982Y253817D02*
X111107Y253567D01*
X111190Y253275D01*
Y252942D01*
X111065Y252567D01*
X110857Y252275D01*
X110607Y252067D01*
X110190Y251900D01*
X109815Y251858D01*
X109440Y251942D01*
X109190Y252067D01*
X108940Y252317D01*
X108773Y252608D01*
X108690Y252900D01*
Y253192D01*
X108773Y253483D01*
X108898Y253733D01*
X109065Y253942D01*
G01X110773Y255208D02*
X111023Y255458D01*
X111148Y255750D01*
X111190Y256083D01*
X111107Y256500D01*
X110898Y256792D01*
X110648Y256875D01*
X110398Y256833D01*
X110190Y256667D01*
X109773Y255833D01*
X109482Y255458D01*
X109065Y255208D01*
X108690Y255125D01*
Y256875D01*
G01X109065Y258183D02*
X108857Y258433D01*
X108732Y258725D01*
X108690Y259100D01*
X108773Y259475D01*
X108940Y259767D01*
X109232Y259975D01*
X109565Y260017D01*
X109898Y259933D01*
X110107Y259725D01*
X110273Y259433D01*
X110315Y259142D01*
X110273Y258850D01*
X110107Y258475D01*
X111190Y258600D01*
Y259725D01*
G01X108982Y261492D02*
X108773Y261783D01*
X108690Y262117D01*
X108773Y262450D01*
X109023Y262742D01*
X109398Y262950D01*
X109773Y263033D01*
X110232D01*
X110607Y262950D01*
X110940Y262742D01*
X111107Y262492D01*
X111190Y262200D01*
X111107Y261867D01*
X110940Y261617D01*
X110690Y261450D01*
X110357Y261367D01*
X110065Y261450D01*
X109773Y261658D01*
X109607Y261908D01*
X109565Y262200D01*
X109648Y262533D01*
X109857Y262783D01*
X110232Y263033D01*
G01X118823Y298642D02*
X119073Y298767D01*
X119365Y298850D01*
X119698D01*
X120073Y298725D01*
X120365Y298517D01*
X120573Y298267D01*
X120740Y297850D01*
X120782Y297475D01*
X120698Y297100D01*
X120573Y296850D01*
X120323Y296600D01*
X120032Y296433D01*
X119740Y296350D01*
X119448D01*
X119157Y296433D01*
X118907Y296558D01*
X118698Y296725D01*
G01X117432Y298433D02*
X117182Y298683D01*
X116890Y298808D01*
X116557Y298850D01*
X116140Y298767D01*
X115848Y298558D01*
X115765Y298308D01*
X115807Y298058D01*
X115973Y297850D01*
X116807Y297433D01*
X117182Y297142D01*
X117432Y296725D01*
X117515Y296350D01*
X115765D01*
G01X114457Y296725D02*
X114207Y296517D01*
X113915Y296392D01*
X113540Y296350D01*
X113165Y296433D01*
X112873Y296600D01*
X112665Y296892D01*
X112623Y297225D01*
X112707Y297558D01*
X112915Y297767D01*
X113207Y297933D01*
X113498Y297975D01*
X113790Y297933D01*
X114165Y297767D01*
X114040Y298850D01*
X112915D01*
G01X110440Y296350D02*
X110148Y296392D01*
X109815Y296517D01*
X109607Y296725D01*
X109523Y297017D01*
X109607Y297308D01*
X109857Y297558D01*
X110232Y297683D01*
X110648D01*
X110898Y297767D01*
X111107Y297975D01*
X111190Y298267D01*
X111065Y298558D01*
X110773Y298767D01*
X110440Y298850D01*
X110107Y298767D01*
X109815Y298558D01*
X109690Y298267D01*
X109773Y297975D01*
X109982Y297767D01*
X110232Y297683D01*
X110648D01*
X111023Y297558D01*
X111273Y297308D01*
X111357Y297017D01*
X111273Y296725D01*
X111065Y296517D01*
X110732Y296392D01*
X110440Y296350D01*
G01X79832Y253817D02*
X79957Y253567D01*
X80040Y253275D01*
Y252942D01*
X79915Y252567D01*
X79707Y252275D01*
X79457Y252067D01*
X79040Y251900D01*
X78665Y251858D01*
X78290Y251942D01*
X78040Y252067D01*
X77790Y252317D01*
X77623Y252608D01*
X77540Y252900D01*
Y253192D01*
X77623Y253483D01*
X77748Y253733D01*
X77915Y253942D01*
G01X79623Y255208D02*
X79873Y255458D01*
X79998Y255750D01*
X80040Y256083D01*
X79957Y256500D01*
X79748Y256792D01*
X79498Y256875D01*
X79248Y256833D01*
X79040Y256667D01*
X78623Y255833D01*
X78332Y255458D01*
X77915Y255208D01*
X77540Y255125D01*
Y256875D01*
G01X77915Y258183D02*
X77707Y258433D01*
X77582Y258725D01*
X77540Y259100D01*
X77623Y259475D01*
X77790Y259767D01*
X78082Y259975D01*
X78415Y260017D01*
X78748Y259933D01*
X78957Y259725D01*
X79123Y259433D01*
X79165Y259142D01*
X79123Y258850D01*
X78957Y258475D01*
X80040Y258600D01*
Y259725D01*
G01X77540Y262700D02*
X80040D01*
X78248Y261158D01*
Y263242D01*
G01X119673Y286642D02*
X119923Y286767D01*
X120215Y286850D01*
X120548D01*
X120923Y286725D01*
X121215Y286517D01*
X121423Y286267D01*
X121590Y285850D01*
X121632Y285475D01*
X121548Y285100D01*
X121423Y284850D01*
X121173Y284600D01*
X120882Y284433D01*
X120590Y284350D01*
X120298D01*
X120007Y284433D01*
X119757Y284558D01*
X119548Y284725D01*
G01X118282Y286433D02*
X118032Y286683D01*
X117740Y286808D01*
X117407Y286850D01*
X116990Y286767D01*
X116698Y286558D01*
X116615Y286308D01*
X116657Y286058D01*
X116823Y285850D01*
X117657Y285433D01*
X118032Y285142D01*
X118282Y284725D01*
X118365Y284350D01*
X116615D01*
G01X115307Y284725D02*
X115057Y284517D01*
X114765Y284392D01*
X114390Y284350D01*
X114015Y284433D01*
X113723Y284600D01*
X113515Y284892D01*
X113473Y285225D01*
X113557Y285558D01*
X113765Y285767D01*
X114057Y285933D01*
X114348Y285975D01*
X114640Y285933D01*
X115015Y285767D01*
X114890Y286850D01*
X113765D01*
G01X112082Y286433D02*
X111832Y286683D01*
X111540Y286808D01*
X111207Y286850D01*
X110790Y286767D01*
X110498Y286558D01*
X110415Y286308D01*
X110457Y286058D01*
X110623Y285850D01*
X111457Y285433D01*
X111832Y285142D01*
X112082Y284725D01*
X112165Y284350D01*
X110415D01*
G01X104292Y266267D02*
X104417Y266017D01*
X104500Y265725D01*
Y265392D01*
X104375Y265017D01*
X104167Y264725D01*
X103917Y264517D01*
X103500Y264350D01*
X103125Y264308D01*
X102750Y264392D01*
X102500Y264517D01*
X102250Y264767D01*
X102083Y265058D01*
X102000Y265350D01*
Y265642D01*
X102083Y265933D01*
X102208Y266183D01*
X102375Y266392D01*
G01X104083Y267658D02*
X104333Y267908D01*
X104458Y268200D01*
X104500Y268533D01*
X104417Y268950D01*
X104208Y269242D01*
X103958Y269325D01*
X103708Y269283D01*
X103500Y269117D01*
X103083Y268283D01*
X102792Y267908D01*
X102375Y267658D01*
X102000Y267575D01*
Y269325D01*
G01X102375Y270633D02*
X102167Y270883D01*
X102042Y271175D01*
X102000Y271550D01*
X102083Y271925D01*
X102250Y272217D01*
X102542Y272425D01*
X102875Y272467D01*
X103208Y272383D01*
X103417Y272175D01*
X103583Y271883D01*
X103625Y271592D01*
X103583Y271300D01*
X103417Y270925D01*
X104500Y271050D01*
Y272175D01*
G01X102000Y274650D02*
X104500D01*
X104000Y274150D01*
G01X102000D02*
Y275150D01*
G01X105923Y302642D02*
X106173Y302767D01*
X106465Y302850D01*
X106798D01*
X107173Y302725D01*
X107465Y302517D01*
X107673Y302267D01*
X107840Y301850D01*
X107882Y301475D01*
X107798Y301100D01*
X107673Y300850D01*
X107423Y300600D01*
X107132Y300433D01*
X106840Y300350D01*
X106548D01*
X106257Y300433D01*
X106007Y300558D01*
X105798Y300725D01*
G01X104532Y302433D02*
X104282Y302683D01*
X103990Y302808D01*
X103657Y302850D01*
X103240Y302767D01*
X102948Y302558D01*
X102865Y302308D01*
X102907Y302058D01*
X103073Y301850D01*
X103907Y301433D01*
X104282Y301142D01*
X104532Y300725D01*
X104615Y300350D01*
X102865D01*
G01X100140D02*
Y302850D01*
X101682Y301058D01*
X99598D01*
G01X98332Y301392D02*
X98040Y301683D01*
X97790Y301850D01*
X97457Y301933D01*
X97165Y301850D01*
X96957Y301683D01*
X96790Y301433D01*
X96748Y301142D01*
X96790Y300892D01*
X96957Y300642D01*
X97207Y300433D01*
X97498Y300350D01*
X97832Y300433D01*
X98123Y300683D01*
X98290Y301058D01*
X98332Y301475D01*
X98248Y302017D01*
X98123Y302308D01*
X97915Y302600D01*
X97623Y302808D01*
X97332Y302850D01*
X97040Y302767D01*
X96832Y302558D01*
G01X98032Y253817D02*
X98157Y253567D01*
X98240Y253275D01*
Y252942D01*
X98115Y252567D01*
X97907Y252275D01*
X97657Y252067D01*
X97240Y251900D01*
X96865Y251858D01*
X96490Y251942D01*
X96240Y252067D01*
X95990Y252317D01*
X95823Y252608D01*
X95740Y252900D01*
Y253192D01*
X95823Y253483D01*
X95948Y253733D01*
X96115Y253942D01*
G01X97823Y255208D02*
X98073Y255458D01*
X98198Y255750D01*
X98240Y256083D01*
X98157Y256500D01*
X97948Y256792D01*
X97698Y256875D01*
X97448Y256833D01*
X97240Y256667D01*
X96823Y255833D01*
X96532Y255458D01*
X96115Y255208D01*
X95740Y255125D01*
Y256875D01*
G01X96240Y258183D02*
X95948Y258433D01*
X95782Y258767D01*
X95740Y259142D01*
X95782Y259475D01*
X95990Y259808D01*
X96240Y260017D01*
X96490Y260058D01*
X96782Y259975D01*
X96990Y259683D01*
X97073Y259392D01*
Y259017D01*
G01Y259392D02*
X97198Y259642D01*
X97407Y259850D01*
X97657Y259933D01*
X97907Y259850D01*
X98115Y259642D01*
X98240Y259267D01*
X98198Y258892D01*
X98032Y258517D01*
G01X95740Y262200D02*
X95782Y262492D01*
X95907Y262825D01*
X96115Y263033D01*
X96407Y263117D01*
X96698Y263033D01*
X96948Y262783D01*
X97073Y262408D01*
Y261992D01*
X97157Y261742D01*
X97365Y261533D01*
X97657Y261450D01*
X97948Y261575D01*
X98157Y261867D01*
X98240Y262200D01*
X98157Y262533D01*
X97948Y262825D01*
X97657Y262950D01*
X97365Y262867D01*
X97157Y262658D01*
X97073Y262408D01*
Y261992D01*
X96948Y261617D01*
X96698Y261367D01*
X96407Y261283D01*
X96115Y261367D01*
X95907Y261575D01*
X95782Y261908D01*
X95740Y262200D01*
G01X80432Y297467D02*
X80557Y297217D01*
X80640Y296925D01*
Y296592D01*
X80515Y296217D01*
X80307Y295925D01*
X80057Y295717D01*
X79640Y295550D01*
X79265Y295508D01*
X78890Y295592D01*
X78640Y295717D01*
X78390Y295967D01*
X78223Y296258D01*
X78140Y296550D01*
Y296842D01*
X78223Y297133D01*
X78348Y297383D01*
X78515Y297592D01*
G01X78140Y299650D02*
X80640D01*
X80140Y299150D01*
G01X78140D02*
Y300150D01*
G01Y302667D02*
X78682Y302750D01*
X79140Y302875D01*
X79557Y303042D01*
X80015Y303250D01*
X80640Y303583D01*
Y301917D01*
G01X78140Y306350D02*
X80640D01*
X78848Y304808D01*
Y306892D01*
G01X84432Y297467D02*
X84557Y297217D01*
X84640Y296925D01*
Y296592D01*
X84515Y296217D01*
X84307Y295925D01*
X84057Y295717D01*
X83640Y295550D01*
X83265Y295508D01*
X82890Y295592D01*
X82640Y295717D01*
X82390Y295967D01*
X82223Y296258D01*
X82140Y296550D01*
Y296842D01*
X82223Y297133D01*
X82348Y297383D01*
X82515Y297592D01*
G01X82140Y299650D02*
X84640D01*
X84140Y299150D01*
G01X82140D02*
Y300150D01*
G01X83182Y301958D02*
X83473Y302250D01*
X83640Y302500D01*
X83723Y302833D01*
X83640Y303125D01*
X83473Y303333D01*
X83223Y303500D01*
X82932Y303542D01*
X82682Y303500D01*
X82432Y303333D01*
X82223Y303083D01*
X82140Y302792D01*
X82223Y302458D01*
X82473Y302167D01*
X82848Y302000D01*
X83265Y301958D01*
X83807Y302042D01*
X84098Y302167D01*
X84390Y302375D01*
X84598Y302667D01*
X84640Y302958D01*
X84557Y303250D01*
X84348Y303458D01*
G01X84640Y305850D02*
X84557Y305517D01*
X84348Y305267D01*
X84098Y305100D01*
X83765Y304975D01*
X83390Y304933D01*
X83015Y304975D01*
X82682Y305100D01*
X82432Y305267D01*
X82223Y305517D01*
X82140Y305850D01*
X82223Y306183D01*
X82432Y306433D01*
X82682Y306600D01*
X83015Y306725D01*
X83390Y306767D01*
X83765Y306725D01*
X84098Y306600D01*
X84348Y306433D01*
X84557Y306183D01*
X84640Y305850D01*
G01X90423Y294142D02*
X90673Y294267D01*
X90965Y294350D01*
X91298D01*
X91673Y294225D01*
X91965Y294017D01*
X92173Y293767D01*
X92340Y293350D01*
X92382Y292975D01*
X92298Y292600D01*
X92173Y292350D01*
X91923Y292100D01*
X91632Y291933D01*
X91340Y291850D01*
X91048D01*
X90757Y291933D01*
X90507Y292058D01*
X90298Y292225D01*
G01X89032Y293933D02*
X88782Y294183D01*
X88490Y294308D01*
X88157Y294350D01*
X87740Y294267D01*
X87448Y294058D01*
X87365Y293808D01*
X87407Y293558D01*
X87573Y293350D01*
X88407Y292933D01*
X88782Y292642D01*
X89032Y292225D01*
X89115Y291850D01*
X87365D01*
G01X85140D02*
Y294350D01*
X85640Y293850D01*
G01Y291850D02*
X84640D01*
G01X82123D02*
X82040Y292392D01*
X81915Y292850D01*
X81748Y293267D01*
X81540Y293725D01*
X81207Y294350D01*
X82873D01*
G01X92482Y297617D02*
X92607Y297367D01*
X92690Y297075D01*
Y296742D01*
X92565Y296367D01*
X92357Y296075D01*
X92107Y295867D01*
X91690Y295700D01*
X91315Y295658D01*
X90940Y295742D01*
X90690Y295867D01*
X90440Y296117D01*
X90273Y296408D01*
X90190Y296700D01*
Y296992D01*
X90273Y297283D01*
X90398Y297533D01*
X90565Y297742D01*
G01X92273Y299008D02*
X92523Y299258D01*
X92648Y299550D01*
X92690Y299883D01*
X92607Y300300D01*
X92398Y300592D01*
X92148Y300675D01*
X91898Y300633D01*
X91690Y300467D01*
X91273Y299633D01*
X90982Y299258D01*
X90565Y299008D01*
X90190Y298925D01*
Y300675D01*
G01Y302900D02*
X92690D01*
X92190Y302400D01*
G01X90190D02*
Y303400D01*
G01Y306000D02*
X90232Y306292D01*
X90357Y306625D01*
X90565Y306833D01*
X90857Y306917D01*
X91148Y306833D01*
X91398Y306583D01*
X91523Y306208D01*
Y305792D01*
X91607Y305542D01*
X91815Y305333D01*
X92107Y305250D01*
X92398Y305375D01*
X92607Y305667D01*
X92690Y306000D01*
X92607Y306333D01*
X92398Y306625D01*
X92107Y306750D01*
X91815Y306667D01*
X91607Y306458D01*
X91523Y306208D01*
Y305792D01*
X91398Y305417D01*
X91148Y305167D01*
X90857Y305083D01*
X90565Y305167D01*
X90357Y305375D01*
X90232Y305708D01*
X90190Y306000D01*
G01X92482Y280617D02*
X92607Y280367D01*
X92690Y280075D01*
Y279742D01*
X92565Y279367D01*
X92357Y279075D01*
X92107Y278867D01*
X91690Y278700D01*
X91315Y278658D01*
X90940Y278742D01*
X90690Y278867D01*
X90440Y279117D01*
X90273Y279408D01*
X90190Y279700D01*
Y279992D01*
X90273Y280283D01*
X90398Y280533D01*
X90565Y280742D01*
G01X92273Y282008D02*
X92523Y282258D01*
X92648Y282550D01*
X92690Y282883D01*
X92607Y283300D01*
X92398Y283592D01*
X92148Y283675D01*
X91898Y283633D01*
X91690Y283467D01*
X91273Y282633D01*
X90982Y282258D01*
X90565Y282008D01*
X90190Y281925D01*
Y283675D01*
G01Y285900D02*
X92690D01*
X92190Y285400D01*
G01X90190D02*
Y286400D01*
G01X90482Y288292D02*
X90273Y288583D01*
X90190Y288917D01*
X90273Y289250D01*
X90523Y289542D01*
X90898Y289750D01*
X91273Y289833D01*
X91732D01*
X92107Y289750D01*
X92440Y289542D01*
X92607Y289292D01*
X92690Y289000D01*
X92607Y288667D01*
X92440Y288417D01*
X92190Y288250D01*
X91857Y288167D01*
X91565Y288250D01*
X91273Y288458D01*
X91107Y288708D01*
X91065Y289000D01*
X91148Y289333D01*
X91357Y289583D01*
X91732Y289833D01*
G01X84482Y280617D02*
X84607Y280367D01*
X84690Y280075D01*
Y279742D01*
X84565Y279367D01*
X84357Y279075D01*
X84107Y278867D01*
X83690Y278700D01*
X83315Y278658D01*
X82940Y278742D01*
X82690Y278867D01*
X82440Y279117D01*
X82273Y279408D01*
X82190Y279700D01*
Y279992D01*
X82273Y280283D01*
X82398Y280533D01*
X82565Y280742D01*
G01X84273Y282008D02*
X84523Y282258D01*
X84648Y282550D01*
X84690Y282883D01*
X84607Y283300D01*
X84398Y283592D01*
X84148Y283675D01*
X83898Y283633D01*
X83690Y283467D01*
X83273Y282633D01*
X82982Y282258D01*
X82565Y282008D01*
X82190Y281925D01*
Y283675D01*
G01X84273Y285108D02*
X84523Y285358D01*
X84648Y285650D01*
X84690Y285983D01*
X84607Y286400D01*
X84398Y286692D01*
X84148Y286775D01*
X83898Y286733D01*
X83690Y286567D01*
X83273Y285733D01*
X82982Y285358D01*
X82565Y285108D01*
X82190Y285025D01*
Y286775D01*
G01X84690Y289000D02*
X84607Y288667D01*
X84398Y288417D01*
X84148Y288250D01*
X83815Y288125D01*
X83440Y288083D01*
X83065Y288125D01*
X82732Y288250D01*
X82482Y288417D01*
X82273Y288667D01*
X82190Y289000D01*
X82273Y289333D01*
X82482Y289583D01*
X82732Y289750D01*
X83065Y289875D01*
X83440Y289917D01*
X83815Y289875D01*
X84148Y289750D01*
X84398Y289583D01*
X84607Y289333D01*
X84690Y289000D01*
G01X80482Y280617D02*
X80607Y280367D01*
X80690Y280075D01*
Y279742D01*
X80565Y279367D01*
X80357Y279075D01*
X80107Y278867D01*
X79690Y278700D01*
X79315Y278658D01*
X78940Y278742D01*
X78690Y278867D01*
X78440Y279117D01*
X78273Y279408D01*
X78190Y279700D01*
Y279992D01*
X78273Y280283D01*
X78398Y280533D01*
X78565Y280742D01*
G01X80273Y282008D02*
X80523Y282258D01*
X80648Y282550D01*
X80690Y282883D01*
X80607Y283300D01*
X80398Y283592D01*
X80148Y283675D01*
X79898Y283633D01*
X79690Y283467D01*
X79273Y282633D01*
X78982Y282258D01*
X78565Y282008D01*
X78190Y281925D01*
Y283675D01*
G01X80273Y285108D02*
X80523Y285358D01*
X80648Y285650D01*
X80690Y285983D01*
X80607Y286400D01*
X80398Y286692D01*
X80148Y286775D01*
X79898Y286733D01*
X79690Y286567D01*
X79273Y285733D01*
X78982Y285358D01*
X78565Y285108D01*
X78190Y285025D01*
Y286775D01*
G01X80273Y288208D02*
X80523Y288458D01*
X80648Y288750D01*
X80690Y289083D01*
X80607Y289500D01*
X80398Y289792D01*
X80148Y289875D01*
X79898Y289833D01*
X79690Y289667D01*
X79273Y288833D01*
X78982Y288458D01*
X78565Y288208D01*
X78190Y288125D01*
Y289875D01*
G01X88482Y280617D02*
X88607Y280367D01*
X88690Y280075D01*
Y279742D01*
X88565Y279367D01*
X88357Y279075D01*
X88107Y278867D01*
X87690Y278700D01*
X87315Y278658D01*
X86940Y278742D01*
X86690Y278867D01*
X86440Y279117D01*
X86273Y279408D01*
X86190Y279700D01*
Y279992D01*
X86273Y280283D01*
X86398Y280533D01*
X86565Y280742D01*
G01X88273Y282008D02*
X88523Y282258D01*
X88648Y282550D01*
X88690Y282883D01*
X88607Y283300D01*
X88398Y283592D01*
X88148Y283675D01*
X87898Y283633D01*
X87690Y283467D01*
X87273Y282633D01*
X86982Y282258D01*
X86565Y282008D01*
X86190Y281925D01*
Y283675D01*
G01X88273Y285108D02*
X88523Y285358D01*
X88648Y285650D01*
X88690Y285983D01*
X88607Y286400D01*
X88398Y286692D01*
X88148Y286775D01*
X87898Y286733D01*
X87690Y286567D01*
X87273Y285733D01*
X86982Y285358D01*
X86565Y285108D01*
X86190Y285025D01*
Y286775D01*
G01X87232Y288208D02*
X87523Y288500D01*
X87690Y288750D01*
X87773Y289083D01*
X87690Y289375D01*
X87523Y289583D01*
X87273Y289750D01*
X86982Y289792D01*
X86732Y289750D01*
X86482Y289583D01*
X86273Y289333D01*
X86190Y289042D01*
X86273Y288708D01*
X86523Y288417D01*
X86898Y288250D01*
X87315Y288208D01*
X87857Y288292D01*
X88148Y288417D01*
X88440Y288625D01*
X88648Y288917D01*
X88690Y289208D01*
X88607Y289500D01*
X88398Y289708D01*
G01X139333Y293192D02*
X139583Y293317D01*
X139875Y293400D01*
X140208D01*
X140583Y293275D01*
X140875Y293067D01*
X141083Y292817D01*
X141250Y292400D01*
X141292Y292025D01*
X141208Y291650D01*
X141083Y291400D01*
X140833Y291150D01*
X140542Y290983D01*
X140250Y290900D01*
X139958D01*
X139667Y290983D01*
X139417Y291108D01*
X139208Y291275D01*
G01X136650Y290900D02*
Y293400D01*
X138192Y291608D01*
X136108D01*
G01X134050Y293400D02*
X134383Y293317D01*
X134633Y293108D01*
X134800Y292858D01*
X134925Y292525D01*
X134967Y292150D01*
X134925Y291775D01*
X134800Y291442D01*
X134633Y291192D01*
X134383Y290983D01*
X134050Y290900D01*
X133717Y290983D01*
X133467Y291192D01*
X133300Y291442D01*
X133175Y291775D01*
X133133Y292150D01*
X133175Y292525D01*
X133300Y292858D01*
X133467Y293108D01*
X133717Y293317D01*
X134050Y293400D01*
G01X131742Y292983D02*
X131492Y293233D01*
X131200Y293358D01*
X130867Y293400D01*
X130450Y293317D01*
X130158Y293108D01*
X130075Y292858D01*
X130117Y292608D01*
X130283Y292400D01*
X131117Y291983D01*
X131492Y291692D01*
X131742Y291275D01*
X131825Y290900D01*
X130075D01*
G01X139333Y298192D02*
X139583Y298317D01*
X139875Y298400D01*
X140208D01*
X140583Y298275D01*
X140875Y298067D01*
X141083Y297817D01*
X141250Y297400D01*
X141292Y297025D01*
X141208Y296650D01*
X141083Y296400D01*
X140833Y296150D01*
X140542Y295983D01*
X140250Y295900D01*
X139958D01*
X139667Y295983D01*
X139417Y296108D01*
X139208Y296275D01*
G01X136650Y295900D02*
Y298400D01*
X138192Y296608D01*
X136108D01*
G01X134050Y298400D02*
X134383Y298317D01*
X134633Y298108D01*
X134800Y297858D01*
X134925Y297525D01*
X134967Y297150D01*
X134925Y296775D01*
X134800Y296442D01*
X134633Y296192D01*
X134383Y295983D01*
X134050Y295900D01*
X133717Y295983D01*
X133467Y296192D01*
X133300Y296442D01*
X133175Y296775D01*
X133133Y297150D01*
X133175Y297525D01*
X133300Y297858D01*
X133467Y298108D01*
X133717Y298317D01*
X134050Y298400D01*
G01X131867Y296400D02*
X131617Y296108D01*
X131283Y295942D01*
X130908Y295900D01*
X130575Y295942D01*
X130242Y296150D01*
X130033Y296400D01*
X129992Y296650D01*
X130075Y296942D01*
X130367Y297150D01*
X130658Y297233D01*
X131033D01*
G01X130658D02*
X130408Y297358D01*
X130200Y297567D01*
X130117Y297817D01*
X130200Y298067D01*
X130408Y298275D01*
X130783Y298400D01*
X131158Y298358D01*
X131533Y298192D01*
G01X128392Y290667D02*
X128517Y290417D01*
X128600Y290125D01*
Y289792D01*
X128475Y289417D01*
X128267Y289125D01*
X128017Y288917D01*
X127600Y288750D01*
X127225Y288708D01*
X126850Y288792D01*
X126600Y288917D01*
X126350Y289167D01*
X126183Y289458D01*
X126100Y289750D01*
Y290042D01*
X126183Y290333D01*
X126308Y290583D01*
X126475Y290792D01*
G01X126100Y293350D02*
X128600D01*
X126808Y291808D01*
Y293892D01*
G01X128600Y295950D02*
X128517Y295617D01*
X128308Y295367D01*
X128058Y295200D01*
X127725Y295075D01*
X127350Y295033D01*
X126975Y295075D01*
X126642Y295200D01*
X126392Y295367D01*
X126183Y295617D01*
X126100Y295950D01*
X126183Y296283D01*
X126392Y296533D01*
X126642Y296700D01*
X126975Y296825D01*
X127350Y296867D01*
X127725Y296825D01*
X128058Y296700D01*
X128308Y296533D01*
X128517Y296283D01*
X128600Y295950D01*
G01X126100Y299550D02*
X128600D01*
X126808Y298008D01*
Y300092D01*
G01X135333Y285192D02*
X135583Y285317D01*
X135875Y285400D01*
X136208D01*
X136583Y285275D01*
X136875Y285067D01*
X137083Y284817D01*
X137250Y284400D01*
X137292Y284025D01*
X137208Y283650D01*
X137083Y283400D01*
X136833Y283150D01*
X136542Y282983D01*
X136250Y282900D01*
X135958D01*
X135667Y282983D01*
X135417Y283108D01*
X135208Y283275D01*
G01X134067Y283400D02*
X133817Y283108D01*
X133483Y282942D01*
X133108Y282900D01*
X132775Y282942D01*
X132442Y283150D01*
X132233Y283400D01*
X132192Y283650D01*
X132275Y283942D01*
X132567Y284150D01*
X132858Y284233D01*
X133233D01*
G01X132858D02*
X132608Y284358D01*
X132400Y284567D01*
X132317Y284817D01*
X132400Y285067D01*
X132608Y285275D01*
X132983Y285400D01*
X133358Y285358D01*
X133733Y285192D01*
G01X130050Y282900D02*
X129758Y282942D01*
X129425Y283067D01*
X129217Y283275D01*
X129133Y283567D01*
X129217Y283858D01*
X129467Y284108D01*
X129842Y284233D01*
X130258D01*
X130508Y284317D01*
X130717Y284525D01*
X130800Y284817D01*
X130675Y285108D01*
X130383Y285317D01*
X130050Y285400D01*
X129717Y285317D01*
X129425Y285108D01*
X129300Y284817D01*
X129383Y284525D01*
X129592Y284317D01*
X129842Y284233D01*
X130258D01*
X130633Y284108D01*
X130883Y283858D01*
X130967Y283567D01*
X130883Y283275D01*
X130675Y283067D01*
X130342Y282942D01*
X130050Y282900D01*
G01X126950D02*
Y285400D01*
X127450Y284900D01*
G01Y282900D02*
X126450D01*
G01X88482Y297617D02*
X88607Y297367D01*
X88690Y297075D01*
Y296742D01*
X88565Y296367D01*
X88357Y296075D01*
X88107Y295867D01*
X87690Y295700D01*
X87315Y295658D01*
X86940Y295742D01*
X86690Y295867D01*
X86440Y296117D01*
X86273Y296408D01*
X86190Y296700D01*
Y296992D01*
X86273Y297283D01*
X86398Y297533D01*
X86565Y297742D01*
G01X86190Y299800D02*
X88690D01*
X88190Y299300D01*
G01X86190D02*
Y300300D01*
G01Y302900D02*
X86232Y303192D01*
X86357Y303525D01*
X86565Y303733D01*
X86857Y303817D01*
X87148Y303733D01*
X87398Y303483D01*
X87523Y303108D01*
Y302692D01*
X87607Y302442D01*
X87815Y302233D01*
X88107Y302150D01*
X88398Y302275D01*
X88607Y302567D01*
X88690Y302900D01*
X88607Y303233D01*
X88398Y303525D01*
X88107Y303650D01*
X87815Y303567D01*
X87607Y303358D01*
X87523Y303108D01*
Y302692D01*
X87398Y302317D01*
X87148Y302067D01*
X86857Y301983D01*
X86565Y302067D01*
X86357Y302275D01*
X86232Y302608D01*
X86190Y302900D01*
G01X87232Y305208D02*
X87523Y305500D01*
X87690Y305750D01*
X87773Y306083D01*
X87690Y306375D01*
X87523Y306583D01*
X87273Y306750D01*
X86982Y306792D01*
X86732Y306750D01*
X86482Y306583D01*
X86273Y306333D01*
X86190Y306042D01*
X86273Y305708D01*
X86523Y305417D01*
X86898Y305250D01*
X87315Y305208D01*
X87857Y305292D01*
X88148Y305417D01*
X88440Y305625D01*
X88648Y305917D01*
X88690Y306208D01*
X88607Y306500D01*
X88398Y306708D01*
G01X108553Y342242D02*
X108803Y342367D01*
X109095Y342450D01*
X109428D01*
X109803Y342325D01*
X110095Y342117D01*
X110303Y341867D01*
X110470Y341450D01*
X110512Y341075D01*
X110428Y340700D01*
X110303Y340450D01*
X110053Y340200D01*
X109762Y340033D01*
X109470Y339950D01*
X109178D01*
X108887Y340033D01*
X108637Y340158D01*
X108428Y340325D01*
G01X107162Y342033D02*
X106912Y342283D01*
X106620Y342408D01*
X106287Y342450D01*
X105870Y342367D01*
X105578Y342158D01*
X105495Y341908D01*
X105537Y341658D01*
X105703Y341450D01*
X106537Y341033D01*
X106912Y340742D01*
X107162Y340325D01*
X107245Y339950D01*
X105495D01*
G01X103270D02*
X102978Y339992D01*
X102645Y340117D01*
X102437Y340325D01*
X102353Y340617D01*
X102437Y340908D01*
X102687Y341158D01*
X103062Y341283D01*
X103478D01*
X103728Y341367D01*
X103937Y341575D01*
X104020Y341867D01*
X103895Y342158D01*
X103603Y342367D01*
X103270Y342450D01*
X102937Y342367D01*
X102645Y342158D01*
X102520Y341867D01*
X102603Y341575D01*
X102812Y341367D01*
X103062Y341283D01*
X103478D01*
X103853Y341158D01*
X104103Y340908D01*
X104187Y340617D01*
X104103Y340325D01*
X103895Y340117D01*
X103562Y339992D01*
X103270Y339950D01*
G01X100253D02*
X100170Y340492D01*
X100045Y340950D01*
X99878Y341367D01*
X99670Y341825D01*
X99337Y342450D01*
X101003D01*
G01X118792Y352267D02*
X118917Y352017D01*
X119000Y351725D01*
Y351392D01*
X118875Y351017D01*
X118667Y350725D01*
X118417Y350517D01*
X118000Y350350D01*
X117625Y350308D01*
X117250Y350392D01*
X117000Y350517D01*
X116750Y350767D01*
X116583Y351058D01*
X116500Y351350D01*
Y351642D01*
X116583Y351933D01*
X116708Y352183D01*
X116875Y352392D01*
G01X118583Y353658D02*
X118833Y353908D01*
X118958Y354200D01*
X119000Y354533D01*
X118917Y354950D01*
X118708Y355242D01*
X118458Y355325D01*
X118208Y355283D01*
X118000Y355117D01*
X117583Y354283D01*
X117292Y353908D01*
X116875Y353658D01*
X116500Y353575D01*
Y355325D01*
G01Y357467D02*
X117042Y357550D01*
X117500Y357675D01*
X117917Y357842D01*
X118375Y358050D01*
X119000Y358383D01*
Y356717D01*
G01X116500Y361150D02*
X119000D01*
X117208Y359608D01*
Y361692D01*
G01X111292Y352267D02*
X111417Y352017D01*
X111500Y351725D01*
Y351392D01*
X111375Y351017D01*
X111167Y350725D01*
X110917Y350517D01*
X110500Y350350D01*
X110125Y350308D01*
X109750Y350392D01*
X109500Y350517D01*
X109250Y350767D01*
X109083Y351058D01*
X109000Y351350D01*
Y351642D01*
X109083Y351933D01*
X109208Y352183D01*
X109375Y352392D01*
G01X111083Y353658D02*
X111333Y353908D01*
X111458Y354200D01*
X111500Y354533D01*
X111417Y354950D01*
X111208Y355242D01*
X110958Y355325D01*
X110708Y355283D01*
X110500Y355117D01*
X110083Y354283D01*
X109792Y353908D01*
X109375Y353658D01*
X109000Y353575D01*
Y355325D01*
G01Y358050D02*
X111500D01*
X109708Y356508D01*
Y358592D01*
G01X109500Y359733D02*
X109208Y359983D01*
X109042Y360317D01*
X109000Y360692D01*
X109042Y361025D01*
X109250Y361358D01*
X109500Y361567D01*
X109750Y361608D01*
X110042Y361525D01*
X110250Y361233D01*
X110333Y360942D01*
Y360567D01*
G01Y360942D02*
X110458Y361192D01*
X110667Y361400D01*
X110917Y361483D01*
X111167Y361400D01*
X111375Y361192D01*
X111500Y360817D01*
X111458Y360442D01*
X111292Y360067D01*
G01X137892Y336667D02*
X138017Y336417D01*
X138100Y336125D01*
Y335792D01*
X137975Y335417D01*
X137767Y335125D01*
X137517Y334917D01*
X137100Y334750D01*
X136725Y334708D01*
X136350Y334792D01*
X136100Y334917D01*
X135850Y335167D01*
X135683Y335458D01*
X135600Y335750D01*
Y336042D01*
X135683Y336333D01*
X135808Y336583D01*
X135975Y336792D01*
G01X135600Y339350D02*
X138100D01*
X136308Y337808D01*
Y339892D01*
G01X135892Y341242D02*
X135683Y341533D01*
X135600Y341867D01*
X135683Y342200D01*
X135933Y342492D01*
X136308Y342700D01*
X136683Y342783D01*
X137142D01*
X137517Y342700D01*
X137850Y342492D01*
X138017Y342242D01*
X138100Y341950D01*
X138017Y341617D01*
X137850Y341367D01*
X137600Y341200D01*
X137267Y341117D01*
X136975Y341200D01*
X136683Y341408D01*
X136517Y341658D01*
X136475Y341950D01*
X136558Y342283D01*
X136767Y342533D01*
X137142Y342783D01*
G01X136100Y344133D02*
X135808Y344383D01*
X135642Y344717D01*
X135600Y345092D01*
X135642Y345425D01*
X135850Y345758D01*
X136100Y345967D01*
X136350Y346008D01*
X136642Y345925D01*
X136850Y345633D01*
X136933Y345342D01*
Y344967D01*
G01Y345342D02*
X137058Y345592D01*
X137267Y345800D01*
X137517Y345883D01*
X137767Y345800D01*
X137975Y345592D01*
X138100Y345217D01*
X138058Y344842D01*
X137892Y344467D01*
G01X97292Y337267D02*
X97417Y337017D01*
X97500Y336725D01*
Y336392D01*
X97375Y336017D01*
X97167Y335725D01*
X96917Y335517D01*
X96500Y335350D01*
X96125Y335308D01*
X95750Y335392D01*
X95500Y335517D01*
X95250Y335767D01*
X95083Y336058D01*
X95000Y336350D01*
Y336642D01*
X95083Y336933D01*
X95208Y337183D01*
X95375Y337392D01*
G01X95000Y339450D02*
X97500D01*
X97000Y338950D01*
G01X95000D02*
Y339950D01*
G01X97083Y341758D02*
X97333Y342008D01*
X97458Y342300D01*
X97500Y342633D01*
X97417Y343050D01*
X97208Y343342D01*
X96958Y343425D01*
X96708Y343383D01*
X96500Y343217D01*
X96083Y342383D01*
X95792Y342008D01*
X95375Y341758D01*
X95000Y341675D01*
Y343425D01*
G01X95375Y344733D02*
X95167Y344983D01*
X95042Y345275D01*
X95000Y345650D01*
X95083Y346025D01*
X95250Y346317D01*
X95542Y346525D01*
X95875Y346567D01*
X96208Y346483D01*
X96417Y346275D01*
X96583Y345983D01*
X96625Y345692D01*
X96583Y345400D01*
X96417Y345025D01*
X97500Y345150D01*
Y346275D01*
G01X105323Y322642D02*
X105573Y322767D01*
X105865Y322850D01*
X106198D01*
X106573Y322725D01*
X106865Y322517D01*
X107073Y322267D01*
X107240Y321850D01*
X107282Y321475D01*
X107198Y321100D01*
X107073Y320850D01*
X106823Y320600D01*
X106532Y320433D01*
X106240Y320350D01*
X105948D01*
X105657Y320433D01*
X105407Y320558D01*
X105198Y320725D01*
G01X104057D02*
X103807Y320517D01*
X103515Y320392D01*
X103140Y320350D01*
X102765Y320433D01*
X102473Y320600D01*
X102265Y320892D01*
X102223Y321225D01*
X102307Y321558D01*
X102515Y321767D01*
X102807Y321933D01*
X103098Y321975D01*
X103390Y321933D01*
X103765Y321767D01*
X103640Y322850D01*
X102515D01*
G01X100040Y320350D02*
X99748Y320392D01*
X99415Y320517D01*
X99207Y320725D01*
X99123Y321017D01*
X99207Y321308D01*
X99457Y321558D01*
X99832Y321683D01*
X100248D01*
X100498Y321767D01*
X100707Y321975D01*
X100790Y322267D01*
X100665Y322558D01*
X100373Y322767D01*
X100040Y322850D01*
X99707Y322767D01*
X99415Y322558D01*
X99290Y322267D01*
X99373Y321975D01*
X99582Y321767D01*
X99832Y321683D01*
X100248D01*
X100623Y321558D01*
X100873Y321308D01*
X100957Y321017D01*
X100873Y320725D01*
X100665Y320517D01*
X100332Y320392D01*
X100040Y320350D01*
G01X97648Y320642D02*
X97357Y320433D01*
X97023Y320350D01*
X96690Y320433D01*
X96398Y320683D01*
X96190Y321058D01*
X96107Y321433D01*
Y321892D01*
X96190Y322267D01*
X96398Y322600D01*
X96648Y322767D01*
X96940Y322850D01*
X97273Y322767D01*
X97523Y322600D01*
X97690Y322350D01*
X97773Y322017D01*
X97690Y321725D01*
X97482Y321433D01*
X97232Y321267D01*
X96940Y321225D01*
X96607Y321308D01*
X96357Y321517D01*
X96107Y321892D01*
G01X105523Y314642D02*
X105773Y314767D01*
X106065Y314850D01*
X106398D01*
X106773Y314725D01*
X107065Y314517D01*
X107273Y314267D01*
X107440Y313850D01*
X107482Y313475D01*
X107398Y313100D01*
X107273Y312850D01*
X107023Y312600D01*
X106732Y312433D01*
X106440Y312350D01*
X106148D01*
X105857Y312433D01*
X105607Y312558D01*
X105398Y312725D01*
G01X104257D02*
X104007Y312517D01*
X103715Y312392D01*
X103340Y312350D01*
X102965Y312433D01*
X102673Y312600D01*
X102465Y312892D01*
X102423Y313225D01*
X102507Y313558D01*
X102715Y313767D01*
X103007Y313933D01*
X103298Y313975D01*
X103590Y313933D01*
X103965Y313767D01*
X103840Y314850D01*
X102715D01*
G01X100240Y312350D02*
X99948Y312392D01*
X99615Y312517D01*
X99407Y312725D01*
X99323Y313017D01*
X99407Y313308D01*
X99657Y313558D01*
X100032Y313683D01*
X100448D01*
X100698Y313767D01*
X100907Y313975D01*
X100990Y314267D01*
X100865Y314558D01*
X100573Y314767D01*
X100240Y314850D01*
X99907Y314767D01*
X99615Y314558D01*
X99490Y314267D01*
X99573Y313975D01*
X99782Y313767D01*
X100032Y313683D01*
X100448D01*
X100823Y313558D01*
X101073Y313308D01*
X101157Y313017D01*
X101073Y312725D01*
X100865Y312517D01*
X100532Y312392D01*
X100240Y312350D01*
G01X97223D02*
X97140Y312892D01*
X97015Y313350D01*
X96848Y313767D01*
X96640Y314225D01*
X96307Y314850D01*
X97973D01*
G01X105323Y318642D02*
X105573Y318767D01*
X105865Y318850D01*
X106198D01*
X106573Y318725D01*
X106865Y318517D01*
X107073Y318267D01*
X107240Y317850D01*
X107282Y317475D01*
X107198Y317100D01*
X107073Y316850D01*
X106823Y316600D01*
X106532Y316433D01*
X106240Y316350D01*
X105948D01*
X105657Y316433D01*
X105407Y316558D01*
X105198Y316725D01*
G01X104057D02*
X103807Y316517D01*
X103515Y316392D01*
X103140Y316350D01*
X102765Y316433D01*
X102473Y316600D01*
X102265Y316892D01*
X102223Y317225D01*
X102307Y317558D01*
X102515Y317767D01*
X102807Y317933D01*
X103098Y317975D01*
X103390Y317933D01*
X103765Y317767D01*
X103640Y318850D01*
X102515D01*
G01X100040Y316350D02*
X99748Y316392D01*
X99415Y316517D01*
X99207Y316725D01*
X99123Y317017D01*
X99207Y317308D01*
X99457Y317558D01*
X99832Y317683D01*
X100248D01*
X100498Y317767D01*
X100707Y317975D01*
X100790Y318267D01*
X100665Y318558D01*
X100373Y318767D01*
X100040Y318850D01*
X99707Y318767D01*
X99415Y318558D01*
X99290Y318267D01*
X99373Y317975D01*
X99582Y317767D01*
X99832Y317683D01*
X100248D01*
X100623Y317558D01*
X100873Y317308D01*
X100957Y317017D01*
X100873Y316725D01*
X100665Y316517D01*
X100332Y316392D01*
X100040Y316350D01*
G01X97732Y317392D02*
X97440Y317683D01*
X97190Y317850D01*
X96857Y317933D01*
X96565Y317850D01*
X96357Y317683D01*
X96190Y317433D01*
X96148Y317142D01*
X96190Y316892D01*
X96357Y316642D01*
X96607Y316433D01*
X96898Y316350D01*
X97232Y316433D01*
X97523Y316683D01*
X97690Y317058D01*
X97732Y317475D01*
X97648Y318017D01*
X97523Y318308D01*
X97315Y318600D01*
X97023Y318808D01*
X96732Y318850D01*
X96440Y318767D01*
X96232Y318558D01*
G01X120733Y337292D02*
X120983Y337417D01*
X121275Y337500D01*
X121608D01*
X121983Y337375D01*
X122275Y337167D01*
X122483Y336917D01*
X122650Y336500D01*
X122692Y336125D01*
X122608Y335750D01*
X122483Y335500D01*
X122233Y335250D01*
X121942Y335083D01*
X121650Y335000D01*
X121358D01*
X121067Y335083D01*
X120817Y335208D01*
X120608Y335375D01*
G01X119467D02*
X119217Y335167D01*
X118925Y335042D01*
X118550Y335000D01*
X118175Y335083D01*
X117883Y335250D01*
X117675Y335542D01*
X117633Y335875D01*
X117717Y336208D01*
X117925Y336417D01*
X118217Y336583D01*
X118508Y336625D01*
X118800Y336583D01*
X119175Y336417D01*
X119050Y337500D01*
X117925D01*
G01X115450Y335000D02*
X115158Y335042D01*
X114825Y335167D01*
X114617Y335375D01*
X114533Y335667D01*
X114617Y335958D01*
X114867Y336208D01*
X115242Y336333D01*
X115658D01*
X115908Y336417D01*
X116117Y336625D01*
X116200Y336917D01*
X116075Y337208D01*
X115783Y337417D01*
X115450Y337500D01*
X115117Y337417D01*
X114825Y337208D01*
X114700Y336917D01*
X114783Y336625D01*
X114992Y336417D01*
X115242Y336333D01*
X115658D01*
X116033Y336208D01*
X116283Y335958D01*
X116367Y335667D01*
X116283Y335375D01*
X116075Y335167D01*
X115742Y335042D01*
X115450Y335000D01*
G01X113267Y335500D02*
X113017Y335208D01*
X112683Y335042D01*
X112308Y335000D01*
X111975Y335042D01*
X111642Y335250D01*
X111433Y335500D01*
X111392Y335750D01*
X111475Y336042D01*
X111767Y336250D01*
X112058Y336333D01*
X112433D01*
G01X112058D02*
X111808Y336458D01*
X111600Y336667D01*
X111517Y336917D01*
X111600Y337167D01*
X111808Y337375D01*
X112183Y337500D01*
X112558Y337458D01*
X112933Y337292D01*
G01X120733Y342292D02*
X120983Y342417D01*
X121275Y342500D01*
X121608D01*
X121983Y342375D01*
X122275Y342167D01*
X122483Y341917D01*
X122650Y341500D01*
X122692Y341125D01*
X122608Y340750D01*
X122483Y340500D01*
X122233Y340250D01*
X121942Y340083D01*
X121650Y340000D01*
X121358D01*
X121067Y340083D01*
X120817Y340208D01*
X120608Y340375D01*
G01X119467D02*
X119217Y340167D01*
X118925Y340042D01*
X118550Y340000D01*
X118175Y340083D01*
X117883Y340250D01*
X117675Y340542D01*
X117633Y340875D01*
X117717Y341208D01*
X117925Y341417D01*
X118217Y341583D01*
X118508Y341625D01*
X118800Y341583D01*
X119175Y341417D01*
X119050Y342500D01*
X117925D01*
G01X115450Y340000D02*
X115158Y340042D01*
X114825Y340167D01*
X114617Y340375D01*
X114533Y340667D01*
X114617Y340958D01*
X114867Y341208D01*
X115242Y341333D01*
X115658D01*
X115908Y341417D01*
X116117Y341625D01*
X116200Y341917D01*
X116075Y342208D01*
X115783Y342417D01*
X115450Y342500D01*
X115117Y342417D01*
X114825Y342208D01*
X114700Y341917D01*
X114783Y341625D01*
X114992Y341417D01*
X115242Y341333D01*
X115658D01*
X116033Y341208D01*
X116283Y340958D01*
X116367Y340667D01*
X116283Y340375D01*
X116075Y340167D01*
X115742Y340042D01*
X115450Y340000D01*
G01X113142Y342083D02*
X112892Y342333D01*
X112600Y342458D01*
X112267Y342500D01*
X111850Y342417D01*
X111558Y342208D01*
X111475Y341958D01*
X111517Y341708D01*
X111683Y341500D01*
X112517Y341083D01*
X112892Y340792D01*
X113142Y340375D01*
X113225Y340000D01*
X111475D01*
G01X118823Y306642D02*
X119073Y306767D01*
X119365Y306850D01*
X119698D01*
X120073Y306725D01*
X120365Y306517D01*
X120573Y306267D01*
X120740Y305850D01*
X120782Y305475D01*
X120698Y305100D01*
X120573Y304850D01*
X120323Y304600D01*
X120032Y304433D01*
X119740Y304350D01*
X119448D01*
X119157Y304433D01*
X118907Y304558D01*
X118698Y304725D01*
G01X117557D02*
X117307Y304517D01*
X117015Y304392D01*
X116640Y304350D01*
X116265Y304433D01*
X115973Y304600D01*
X115765Y304892D01*
X115723Y305225D01*
X115807Y305558D01*
X116015Y305767D01*
X116307Y305933D01*
X116598Y305975D01*
X116890Y305933D01*
X117265Y305767D01*
X117140Y306850D01*
X116015D01*
G01X113623Y304350D02*
X113540Y304892D01*
X113415Y305350D01*
X113248Y305767D01*
X113040Y306225D01*
X112707Y306850D01*
X114373D01*
G01X110440Y304350D02*
X110148Y304392D01*
X109815Y304517D01*
X109607Y304725D01*
X109523Y305017D01*
X109607Y305308D01*
X109857Y305558D01*
X110232Y305683D01*
X110648D01*
X110898Y305767D01*
X111107Y305975D01*
X111190Y306267D01*
X111065Y306558D01*
X110773Y306767D01*
X110440Y306850D01*
X110107Y306767D01*
X109815Y306558D01*
X109690Y306267D01*
X109773Y305975D01*
X109982Y305767D01*
X110232Y305683D01*
X110648D01*
X111023Y305558D01*
X111273Y305308D01*
X111357Y305017D01*
X111273Y304725D01*
X111065Y304517D01*
X110732Y304392D01*
X110440Y304350D01*
G01X108153Y337592D02*
X108403Y337717D01*
X108695Y337800D01*
X109028D01*
X109403Y337675D01*
X109695Y337467D01*
X109903Y337217D01*
X110070Y336800D01*
X110112Y336425D01*
X110028Y336050D01*
X109903Y335800D01*
X109653Y335550D01*
X109362Y335383D01*
X109070Y335300D01*
X108778D01*
X108487Y335383D01*
X108237Y335508D01*
X108028Y335675D01*
G01X106887D02*
X106637Y335467D01*
X106345Y335342D01*
X105970Y335300D01*
X105595Y335383D01*
X105303Y335550D01*
X105095Y335842D01*
X105053Y336175D01*
X105137Y336508D01*
X105345Y336717D01*
X105637Y336883D01*
X105928Y336925D01*
X106220Y336883D01*
X106595Y336717D01*
X106470Y337800D01*
X105345D01*
G01X103787Y335800D02*
X103537Y335508D01*
X103203Y335342D01*
X102828Y335300D01*
X102495Y335342D01*
X102162Y335550D01*
X101953Y335800D01*
X101912Y336050D01*
X101995Y336342D01*
X102287Y336550D01*
X102578Y336633D01*
X102953D01*
G01X102578D02*
X102328Y336758D01*
X102120Y336967D01*
X102037Y337217D01*
X102120Y337467D01*
X102328Y337675D01*
X102703Y337800D01*
X103078Y337758D01*
X103453Y337592D01*
G01X99770Y335300D02*
Y337800D01*
X100270Y337300D01*
G01Y335300D02*
X99270D01*
G01X118823Y310592D02*
X119073Y310717D01*
X119365Y310800D01*
X119698D01*
X120073Y310675D01*
X120365Y310467D01*
X120573Y310217D01*
X120740Y309800D01*
X120782Y309425D01*
X120698Y309050D01*
X120573Y308800D01*
X120323Y308550D01*
X120032Y308383D01*
X119740Y308300D01*
X119448D01*
X119157Y308383D01*
X118907Y308508D01*
X118698Y308675D01*
G01X117557Y308800D02*
X117307Y308508D01*
X116973Y308342D01*
X116598Y308300D01*
X116265Y308342D01*
X115932Y308550D01*
X115723Y308800D01*
X115682Y309050D01*
X115765Y309342D01*
X116057Y309550D01*
X116348Y309633D01*
X116723D01*
G01X116348D02*
X116098Y309758D01*
X115890Y309967D01*
X115807Y310217D01*
X115890Y310467D01*
X116098Y310675D01*
X116473Y310800D01*
X116848Y310758D01*
X117223Y310592D01*
G01X113540Y310800D02*
X113873Y310717D01*
X114123Y310508D01*
X114290Y310258D01*
X114415Y309925D01*
X114457Y309550D01*
X114415Y309175D01*
X114290Y308842D01*
X114123Y308592D01*
X113873Y308383D01*
X113540Y308300D01*
X113207Y308383D01*
X112957Y308592D01*
X112790Y308842D01*
X112665Y309175D01*
X112623Y309550D01*
X112665Y309925D01*
X112790Y310258D01*
X112957Y310508D01*
X113207Y310717D01*
X113540Y310800D01*
G01X110523Y308300D02*
X110440Y308842D01*
X110315Y309300D01*
X110148Y309717D01*
X109940Y310175D01*
X109607Y310800D01*
X111273D01*
G01X119523Y322692D02*
X119773Y322817D01*
X120065Y322900D01*
X120398D01*
X120773Y322775D01*
X121065Y322567D01*
X121273Y322317D01*
X121440Y321900D01*
X121482Y321525D01*
X121398Y321150D01*
X121273Y320900D01*
X121023Y320650D01*
X120732Y320483D01*
X120440Y320400D01*
X120148D01*
X119857Y320483D01*
X119607Y320608D01*
X119398Y320775D01*
G01X118257Y320900D02*
X118007Y320608D01*
X117673Y320442D01*
X117298Y320400D01*
X116965Y320442D01*
X116632Y320650D01*
X116423Y320900D01*
X116382Y321150D01*
X116465Y321442D01*
X116757Y321650D01*
X117048Y321733D01*
X117423D01*
G01X117048D02*
X116798Y321858D01*
X116590Y322067D01*
X116507Y322317D01*
X116590Y322567D01*
X116798Y322775D01*
X117173Y322900D01*
X117548Y322858D01*
X117923Y322692D01*
G01X114240Y322900D02*
X114573Y322817D01*
X114823Y322608D01*
X114990Y322358D01*
X115115Y322025D01*
X115157Y321650D01*
X115115Y321275D01*
X114990Y320942D01*
X114823Y320692D01*
X114573Y320483D01*
X114240Y320400D01*
X113907Y320483D01*
X113657Y320692D01*
X113490Y320942D01*
X113365Y321275D01*
X113323Y321650D01*
X113365Y322025D01*
X113490Y322358D01*
X113657Y322608D01*
X113907Y322817D01*
X114240Y322900D01*
G01X111932Y321442D02*
X111640Y321733D01*
X111390Y321900D01*
X111057Y321983D01*
X110765Y321900D01*
X110557Y321733D01*
X110390Y321483D01*
X110348Y321192D01*
X110390Y320942D01*
X110557Y320692D01*
X110807Y320483D01*
X111098Y320400D01*
X111432Y320483D01*
X111723Y320733D01*
X111890Y321108D01*
X111932Y321525D01*
X111848Y322067D01*
X111723Y322358D01*
X111515Y322650D01*
X111223Y322858D01*
X110932Y322900D01*
X110640Y322817D01*
X110432Y322608D01*
G01X119523Y314642D02*
X119773Y314767D01*
X120065Y314850D01*
X120398D01*
X120773Y314725D01*
X121065Y314517D01*
X121273Y314267D01*
X121440Y313850D01*
X121482Y313475D01*
X121398Y313100D01*
X121273Y312850D01*
X121023Y312600D01*
X120732Y312433D01*
X120440Y312350D01*
X120148D01*
X119857Y312433D01*
X119607Y312558D01*
X119398Y312725D01*
G01X118257Y312850D02*
X118007Y312558D01*
X117673Y312392D01*
X117298Y312350D01*
X116965Y312392D01*
X116632Y312600D01*
X116423Y312850D01*
X116382Y313100D01*
X116465Y313392D01*
X116757Y313600D01*
X117048Y313683D01*
X117423D01*
G01X117048D02*
X116798Y313808D01*
X116590Y314017D01*
X116507Y314267D01*
X116590Y314517D01*
X116798Y314725D01*
X117173Y314850D01*
X117548Y314808D01*
X117923Y314642D01*
G01X114240Y314850D02*
X114573Y314767D01*
X114823Y314558D01*
X114990Y314308D01*
X115115Y313975D01*
X115157Y313600D01*
X115115Y313225D01*
X114990Y312892D01*
X114823Y312642D01*
X114573Y312433D01*
X114240Y312350D01*
X113907Y312433D01*
X113657Y312642D01*
X113490Y312892D01*
X113365Y313225D01*
X113323Y313600D01*
X113365Y313975D01*
X113490Y314308D01*
X113657Y314558D01*
X113907Y314767D01*
X114240Y314850D01*
G01X111140D02*
X111473Y314767D01*
X111723Y314558D01*
X111890Y314308D01*
X112015Y313975D01*
X112057Y313600D01*
X112015Y313225D01*
X111890Y312892D01*
X111723Y312642D01*
X111473Y312433D01*
X111140Y312350D01*
X110807Y312433D01*
X110557Y312642D01*
X110390Y312892D01*
X110265Y313225D01*
X110223Y313600D01*
X110265Y313975D01*
X110390Y314308D01*
X110557Y314558D01*
X110807Y314767D01*
X111140Y314850D01*
G01X105923Y306642D02*
X106173Y306767D01*
X106465Y306850D01*
X106798D01*
X107173Y306725D01*
X107465Y306517D01*
X107673Y306267D01*
X107840Y305850D01*
X107882Y305475D01*
X107798Y305100D01*
X107673Y304850D01*
X107423Y304600D01*
X107132Y304433D01*
X106840Y304350D01*
X106548D01*
X106257Y304433D01*
X106007Y304558D01*
X105798Y304725D01*
G01X104532Y306433D02*
X104282Y306683D01*
X103990Y306808D01*
X103657Y306850D01*
X103240Y306767D01*
X102948Y306558D01*
X102865Y306308D01*
X102907Y306058D01*
X103073Y305850D01*
X103907Y305433D01*
X104282Y305142D01*
X104532Y304725D01*
X104615Y304350D01*
X102865D01*
G01X100640D02*
X100348Y304392D01*
X100015Y304517D01*
X99807Y304725D01*
X99723Y305017D01*
X99807Y305308D01*
X100057Y305558D01*
X100432Y305683D01*
X100848D01*
X101098Y305767D01*
X101307Y305975D01*
X101390Y306267D01*
X101265Y306558D01*
X100973Y306767D01*
X100640Y306850D01*
X100307Y306767D01*
X100015Y306558D01*
X99890Y306267D01*
X99973Y305975D01*
X100182Y305767D01*
X100432Y305683D01*
X100848D01*
X101223Y305558D01*
X101473Y305308D01*
X101557Y305017D01*
X101473Y304725D01*
X101265Y304517D01*
X100932Y304392D01*
X100640Y304350D01*
G01X98457Y304725D02*
X98207Y304517D01*
X97915Y304392D01*
X97540Y304350D01*
X97165Y304433D01*
X96873Y304600D01*
X96665Y304892D01*
X96623Y305225D01*
X96707Y305558D01*
X96915Y305767D01*
X97207Y305933D01*
X97498Y305975D01*
X97790Y305933D01*
X98165Y305767D01*
X98040Y306850D01*
X96915D01*
G01X105323Y326642D02*
X105573Y326767D01*
X105865Y326850D01*
X106198D01*
X106573Y326725D01*
X106865Y326517D01*
X107073Y326267D01*
X107240Y325850D01*
X107282Y325475D01*
X107198Y325100D01*
X107073Y324850D01*
X106823Y324600D01*
X106532Y324433D01*
X106240Y324350D01*
X105948D01*
X105657Y324433D01*
X105407Y324558D01*
X105198Y324725D01*
G01X103932Y326433D02*
X103682Y326683D01*
X103390Y326808D01*
X103057Y326850D01*
X102640Y326767D01*
X102348Y326558D01*
X102265Y326308D01*
X102307Y326058D01*
X102473Y325850D01*
X103307Y325433D01*
X103682Y325142D01*
X103932Y324725D01*
X104015Y324350D01*
X102265D01*
G01X100040D02*
X99748Y324392D01*
X99415Y324517D01*
X99207Y324725D01*
X99123Y325017D01*
X99207Y325308D01*
X99457Y325558D01*
X99832Y325683D01*
X100248D01*
X100498Y325767D01*
X100707Y325975D01*
X100790Y326267D01*
X100665Y326558D01*
X100373Y326767D01*
X100040Y326850D01*
X99707Y326767D01*
X99415Y326558D01*
X99290Y326267D01*
X99373Y325975D01*
X99582Y325767D01*
X99832Y325683D01*
X100248D01*
X100623Y325558D01*
X100873Y325308D01*
X100957Y325017D01*
X100873Y324725D01*
X100665Y324517D01*
X100332Y324392D01*
X100040Y324350D01*
G01X96940Y326850D02*
X97273Y326767D01*
X97523Y326558D01*
X97690Y326308D01*
X97815Y325975D01*
X97857Y325600D01*
X97815Y325225D01*
X97690Y324892D01*
X97523Y324642D01*
X97273Y324433D01*
X96940Y324350D01*
X96607Y324433D01*
X96357Y324642D01*
X96190Y324892D01*
X96065Y325225D01*
X96023Y325600D01*
X96065Y325975D01*
X96190Y326308D01*
X96357Y326558D01*
X96607Y326767D01*
X96940Y326850D01*
G01X119573Y326642D02*
X119823Y326767D01*
X120115Y326850D01*
X120448D01*
X120823Y326725D01*
X121115Y326517D01*
X121323Y326267D01*
X121490Y325850D01*
X121532Y325475D01*
X121448Y325100D01*
X121323Y324850D01*
X121073Y324600D01*
X120782Y324433D01*
X120490Y324350D01*
X120198D01*
X119907Y324433D01*
X119657Y324558D01*
X119448Y324725D01*
G01X118182Y326433D02*
X117932Y326683D01*
X117640Y326808D01*
X117307Y326850D01*
X116890Y326767D01*
X116598Y326558D01*
X116515Y326308D01*
X116557Y326058D01*
X116723Y325850D01*
X117557Y325433D01*
X117932Y325142D01*
X118182Y324725D01*
X118265Y324350D01*
X116515D01*
G01X114373D02*
X114290Y324892D01*
X114165Y325350D01*
X113998Y325767D01*
X113790Y326225D01*
X113457Y326850D01*
X115123D01*
G01X111898Y324642D02*
X111607Y324433D01*
X111273Y324350D01*
X110940Y324433D01*
X110648Y324683D01*
X110440Y325058D01*
X110357Y325433D01*
Y325892D01*
X110440Y326267D01*
X110648Y326600D01*
X110898Y326767D01*
X111190Y326850D01*
X111523Y326767D01*
X111773Y326600D01*
X111940Y326350D01*
X112023Y326017D01*
X111940Y325725D01*
X111732Y325433D01*
X111482Y325267D01*
X111190Y325225D01*
X110857Y325308D01*
X110607Y325517D01*
X110357Y325892D01*
G01X119233Y318792D02*
X119483Y318917D01*
X119775Y319000D01*
X120108D01*
X120483Y318875D01*
X120775Y318667D01*
X120983Y318417D01*
X121150Y318000D01*
X121192Y317625D01*
X121108Y317250D01*
X120983Y317000D01*
X120733Y316750D01*
X120442Y316583D01*
X120150Y316500D01*
X119858D01*
X119567Y316583D01*
X119317Y316708D01*
X119108Y316875D01*
G01X117842Y318583D02*
X117592Y318833D01*
X117300Y318958D01*
X116967Y319000D01*
X116550Y318917D01*
X116258Y318708D01*
X116175Y318458D01*
X116217Y318208D01*
X116383Y318000D01*
X117217Y317583D01*
X117592Y317292D01*
X117842Y316875D01*
X117925Y316500D01*
X116175D01*
G01X113450D02*
Y319000D01*
X114992Y317208D01*
X112908D01*
G01X111767Y316875D02*
X111517Y316667D01*
X111225Y316542D01*
X110850Y316500D01*
X110475Y316583D01*
X110183Y316750D01*
X109975Y317042D01*
X109933Y317375D01*
X110017Y317708D01*
X110225Y317917D01*
X110517Y318083D01*
X110808Y318125D01*
X111100Y318083D01*
X111475Y317917D01*
X111350Y319000D01*
X110225D01*
G01X120683Y346852D02*
X120933Y346977D01*
X121225Y347060D01*
X121558D01*
X121933Y346935D01*
X122225Y346727D01*
X122433Y346477D01*
X122600Y346060D01*
X122642Y345685D01*
X122558Y345310D01*
X122433Y345060D01*
X122183Y344810D01*
X121892Y344643D01*
X121600Y344560D01*
X121308D01*
X121017Y344643D01*
X120767Y344768D01*
X120558Y344935D01*
G01X119292Y346643D02*
X119042Y346893D01*
X118750Y347018D01*
X118417Y347060D01*
X118000Y346977D01*
X117708Y346768D01*
X117625Y346518D01*
X117667Y346268D01*
X117833Y346060D01*
X118667Y345643D01*
X119042Y345352D01*
X119292Y344935D01*
X119375Y344560D01*
X117625D01*
G01X114900D02*
Y347060D01*
X116442Y345268D01*
X114358D01*
G01X111800Y344560D02*
Y347060D01*
X113342Y345268D01*
X111258D01*
G01X106023Y310642D02*
X106273Y310767D01*
X106565Y310850D01*
X106898D01*
X107273Y310725D01*
X107565Y310517D01*
X107773Y310267D01*
X107940Y309850D01*
X107982Y309475D01*
X107898Y309100D01*
X107773Y308850D01*
X107523Y308600D01*
X107232Y308433D01*
X106940Y308350D01*
X106648D01*
X106357Y308433D01*
X106107Y308558D01*
X105898Y308725D01*
G01X104632Y310433D02*
X104382Y310683D01*
X104090Y310808D01*
X103757Y310850D01*
X103340Y310767D01*
X103048Y310558D01*
X102965Y310308D01*
X103007Y310058D01*
X103173Y309850D01*
X104007Y309433D01*
X104382Y309142D01*
X104632Y308725D01*
X104715Y308350D01*
X102965D01*
G01X101657Y308850D02*
X101407Y308558D01*
X101073Y308392D01*
X100698Y308350D01*
X100365Y308392D01*
X100032Y308600D01*
X99823Y308850D01*
X99782Y309100D01*
X99865Y309392D01*
X100157Y309600D01*
X100448Y309683D01*
X100823D01*
G01X100448D02*
X100198Y309808D01*
X99990Y310017D01*
X99907Y310267D01*
X99990Y310517D01*
X100198Y310725D01*
X100573Y310850D01*
X100948Y310808D01*
X101323Y310642D01*
G01X97640Y310850D02*
X97973Y310767D01*
X98223Y310558D01*
X98390Y310308D01*
X98515Y309975D01*
X98557Y309600D01*
X98515Y309225D01*
X98390Y308892D01*
X98223Y308642D01*
X97973Y308433D01*
X97640Y308350D01*
X97307Y308433D01*
X97057Y308642D01*
X96890Y308892D01*
X96765Y309225D01*
X96723Y309600D01*
X96765Y309975D01*
X96890Y310308D01*
X97057Y310558D01*
X97307Y310767D01*
X97640Y310850D01*
G01X80482Y323917D02*
X80607Y323667D01*
X80690Y323375D01*
Y323042D01*
X80565Y322667D01*
X80357Y322375D01*
X80107Y322167D01*
X79690Y322000D01*
X79315Y321958D01*
X78940Y322042D01*
X78690Y322167D01*
X78440Y322417D01*
X78273Y322708D01*
X78190Y323000D01*
Y323292D01*
X78273Y323583D01*
X78398Y323833D01*
X78565Y324042D01*
G01X78190Y326100D02*
X80690D01*
X80190Y325600D01*
G01X78190D02*
Y326600D01*
G01Y329117D02*
X78732Y329200D01*
X79190Y329325D01*
X79607Y329492D01*
X80065Y329700D01*
X80690Y330033D01*
Y328367D01*
G01X78482Y331592D02*
X78273Y331883D01*
X78190Y332217D01*
X78273Y332550D01*
X78523Y332842D01*
X78898Y333050D01*
X79273Y333133D01*
X79732D01*
X80107Y333050D01*
X80440Y332842D01*
X80607Y332592D01*
X80690Y332300D01*
X80607Y331967D01*
X80440Y331717D01*
X80190Y331550D01*
X79857Y331467D01*
X79565Y331550D01*
X79273Y331758D01*
X79107Y332008D01*
X79065Y332300D01*
X79148Y332633D01*
X79357Y332883D01*
X79732Y333133D01*
G01X84482Y323917D02*
X84607Y323667D01*
X84690Y323375D01*
Y323042D01*
X84565Y322667D01*
X84357Y322375D01*
X84107Y322167D01*
X83690Y322000D01*
X83315Y321958D01*
X82940Y322042D01*
X82690Y322167D01*
X82440Y322417D01*
X82273Y322708D01*
X82190Y323000D01*
Y323292D01*
X82273Y323583D01*
X82398Y323833D01*
X82565Y324042D01*
G01X82190Y326100D02*
X84690D01*
X84190Y325600D01*
G01X82190D02*
Y326600D01*
G01Y329117D02*
X82732Y329200D01*
X83190Y329325D01*
X83607Y329492D01*
X84065Y329700D01*
X84690Y330033D01*
Y328367D01*
G01X82190Y332300D02*
X82232Y332592D01*
X82357Y332925D01*
X82565Y333133D01*
X82857Y333217D01*
X83148Y333133D01*
X83398Y332883D01*
X83523Y332508D01*
Y332092D01*
X83607Y331842D01*
X83815Y331633D01*
X84107Y331550D01*
X84398Y331675D01*
X84607Y331967D01*
X84690Y332300D01*
X84607Y332633D01*
X84398Y332925D01*
X84107Y333050D01*
X83815Y332967D01*
X83607Y332758D01*
X83523Y332508D01*
Y332092D01*
X83398Y331717D01*
X83148Y331467D01*
X82857Y331383D01*
X82565Y331467D01*
X82357Y331675D01*
X82232Y332008D01*
X82190Y332300D01*
G01X80482Y310867D02*
X80607Y310617D01*
X80690Y310325D01*
Y309992D01*
X80565Y309617D01*
X80357Y309325D01*
X80107Y309117D01*
X79690Y308950D01*
X79315Y308908D01*
X78940Y308992D01*
X78690Y309117D01*
X78440Y309367D01*
X78273Y309658D01*
X78190Y309950D01*
Y310242D01*
X78273Y310533D01*
X78398Y310783D01*
X78565Y310992D01*
G01X78190Y313050D02*
X80690D01*
X80190Y312550D01*
G01X78190D02*
Y313550D01*
G01X79232Y315358D02*
X79523Y315650D01*
X79690Y315900D01*
X79773Y316233D01*
X79690Y316525D01*
X79523Y316733D01*
X79273Y316900D01*
X78982Y316942D01*
X78732Y316900D01*
X78482Y316733D01*
X78273Y316483D01*
X78190Y316192D01*
X78273Y315858D01*
X78523Y315567D01*
X78898Y315400D01*
X79315Y315358D01*
X79857Y315442D01*
X80148Y315567D01*
X80440Y315775D01*
X80648Y316067D01*
X80690Y316358D01*
X80607Y316650D01*
X80398Y316858D01*
G01X78190Y319167D02*
X78732Y319250D01*
X79190Y319375D01*
X79607Y319542D01*
X80065Y319750D01*
X80690Y320083D01*
Y318417D01*
G01X84482Y310867D02*
X84607Y310617D01*
X84690Y310325D01*
Y309992D01*
X84565Y309617D01*
X84357Y309325D01*
X84107Y309117D01*
X83690Y308950D01*
X83315Y308908D01*
X82940Y308992D01*
X82690Y309117D01*
X82440Y309367D01*
X82273Y309658D01*
X82190Y309950D01*
Y310242D01*
X82273Y310533D01*
X82398Y310783D01*
X82565Y310992D01*
G01X82190Y313050D02*
X84690D01*
X84190Y312550D01*
G01X82190D02*
Y313550D01*
G01X82565Y315233D02*
X82357Y315483D01*
X82232Y315775D01*
X82190Y316150D01*
X82273Y316525D01*
X82440Y316817D01*
X82732Y317025D01*
X83065Y317067D01*
X83398Y316983D01*
X83607Y316775D01*
X83773Y316483D01*
X83815Y316192D01*
X83773Y315900D01*
X83607Y315525D01*
X84690Y315650D01*
Y316775D01*
G01X82190Y319250D02*
X82232Y319542D01*
X82357Y319875D01*
X82565Y320083D01*
X82857Y320167D01*
X83148Y320083D01*
X83398Y319833D01*
X83523Y319458D01*
Y319042D01*
X83607Y318792D01*
X83815Y318583D01*
X84107Y318500D01*
X84398Y318625D01*
X84607Y318917D01*
X84690Y319250D01*
X84607Y319583D01*
X84398Y319875D01*
X84107Y320000D01*
X83815Y319917D01*
X83607Y319708D01*
X83523Y319458D01*
Y319042D01*
X83398Y318667D01*
X83148Y318417D01*
X82857Y318333D01*
X82565Y318417D01*
X82357Y318625D01*
X82232Y318958D01*
X82190Y319250D01*
G01X92482Y324117D02*
X92607Y323867D01*
X92690Y323575D01*
Y323242D01*
X92565Y322867D01*
X92357Y322575D01*
X92107Y322367D01*
X91690Y322200D01*
X91315Y322158D01*
X90940Y322242D01*
X90690Y322367D01*
X90440Y322617D01*
X90273Y322908D01*
X90190Y323200D01*
Y323492D01*
X90273Y323783D01*
X90398Y324033D01*
X90565Y324242D01*
G01X92273Y325508D02*
X92523Y325758D01*
X92648Y326050D01*
X92690Y326383D01*
X92607Y326800D01*
X92398Y327092D01*
X92148Y327175D01*
X91898Y327133D01*
X91690Y326967D01*
X91273Y326133D01*
X90982Y325758D01*
X90565Y325508D01*
X90190Y325425D01*
Y327175D01*
G01Y329400D02*
X92690D01*
X92190Y328900D01*
G01X90190D02*
Y329900D01*
G01X90565Y331583D02*
X90357Y331833D01*
X90232Y332125D01*
X90190Y332500D01*
X90273Y332875D01*
X90440Y333167D01*
X90732Y333375D01*
X91065Y333417D01*
X91398Y333333D01*
X91607Y333125D01*
X91773Y332833D01*
X91815Y332542D01*
X91773Y332250D01*
X91607Y331875D01*
X92690Y332000D01*
Y333125D01*
G01X92482Y311117D02*
X92607Y310867D01*
X92690Y310575D01*
Y310242D01*
X92565Y309867D01*
X92357Y309575D01*
X92107Y309367D01*
X91690Y309200D01*
X91315Y309158D01*
X90940Y309242D01*
X90690Y309367D01*
X90440Y309617D01*
X90273Y309908D01*
X90190Y310200D01*
Y310492D01*
X90273Y310783D01*
X90398Y311033D01*
X90565Y311242D01*
G01X92273Y312508D02*
X92523Y312758D01*
X92648Y313050D01*
X92690Y313383D01*
X92607Y313800D01*
X92398Y314092D01*
X92148Y314175D01*
X91898Y314133D01*
X91690Y313967D01*
X91273Y313133D01*
X90982Y312758D01*
X90565Y312508D01*
X90190Y312425D01*
Y314175D01*
G01Y316400D02*
X92690D01*
X92190Y315900D01*
G01X90190D02*
Y316900D01*
G01X91232Y318708D02*
X91523Y319000D01*
X91690Y319250D01*
X91773Y319583D01*
X91690Y319875D01*
X91523Y320083D01*
X91273Y320250D01*
X90982Y320292D01*
X90732Y320250D01*
X90482Y320083D01*
X90273Y319833D01*
X90190Y319542D01*
X90273Y319208D01*
X90523Y318917D01*
X90898Y318750D01*
X91315Y318708D01*
X91857Y318792D01*
X92148Y318917D01*
X92440Y319125D01*
X92648Y319417D01*
X92690Y319708D01*
X92607Y320000D01*
X92398Y320208D01*
G01X133892Y318167D02*
X134017Y317917D01*
X134100Y317625D01*
Y317292D01*
X133975Y316917D01*
X133767Y316625D01*
X133517Y316417D01*
X133100Y316250D01*
X132725Y316208D01*
X132350Y316292D01*
X132100Y316417D01*
X131850Y316667D01*
X131683Y316958D01*
X131600Y317250D01*
Y317542D01*
X131683Y317833D01*
X131808Y318083D01*
X131975Y318292D01*
G01X131600Y320850D02*
X134100D01*
X132308Y319308D01*
Y321392D01*
G01X134100Y323450D02*
X134017Y323117D01*
X133808Y322867D01*
X133558Y322700D01*
X133225Y322575D01*
X132850Y322533D01*
X132475Y322575D01*
X132142Y322700D01*
X131892Y322867D01*
X131683Y323117D01*
X131600Y323450D01*
X131683Y323783D01*
X131892Y324033D01*
X132142Y324200D01*
X132475Y324325D01*
X132850Y324367D01*
X133225Y324325D01*
X133558Y324200D01*
X133808Y324033D01*
X134017Y323783D01*
X134100Y323450D01*
G01Y326550D02*
X134017Y326217D01*
X133808Y325967D01*
X133558Y325800D01*
X133225Y325675D01*
X132850Y325633D01*
X132475Y325675D01*
X132142Y325800D01*
X131892Y325967D01*
X131683Y326217D01*
X131600Y326550D01*
X131683Y326883D01*
X131892Y327133D01*
X132142Y327300D01*
X132475Y327425D01*
X132850Y327467D01*
X133225Y327425D01*
X133558Y327300D01*
X133808Y327133D01*
X134017Y326883D01*
X134100Y326550D01*
G01X137892Y318667D02*
X138017Y318417D01*
X138100Y318125D01*
Y317792D01*
X137975Y317417D01*
X137767Y317125D01*
X137517Y316917D01*
X137100Y316750D01*
X136725Y316708D01*
X136350Y316792D01*
X136100Y316917D01*
X135850Y317167D01*
X135683Y317458D01*
X135600Y317750D01*
Y318042D01*
X135683Y318333D01*
X135808Y318583D01*
X135975Y318792D01*
G01X135600Y321350D02*
X138100D01*
X136308Y319808D01*
Y321892D01*
G01X138100Y323950D02*
X138017Y323617D01*
X137808Y323367D01*
X137558Y323200D01*
X137225Y323075D01*
X136850Y323033D01*
X136475Y323075D01*
X136142Y323200D01*
X135892Y323367D01*
X135683Y323617D01*
X135600Y323950D01*
X135683Y324283D01*
X135892Y324533D01*
X136142Y324700D01*
X136475Y324825D01*
X136850Y324867D01*
X137225Y324825D01*
X137558Y324700D01*
X137808Y324533D01*
X138017Y324283D01*
X138100Y323950D01*
G01X135600Y327050D02*
X138100D01*
X137600Y326550D01*
G01X135600D02*
Y327550D01*
G01X88382Y310867D02*
X88507Y310617D01*
X88590Y310325D01*
Y309992D01*
X88465Y309617D01*
X88257Y309325D01*
X88007Y309117D01*
X87590Y308950D01*
X87215Y308908D01*
X86840Y308992D01*
X86590Y309117D01*
X86340Y309367D01*
X86173Y309658D01*
X86090Y309950D01*
Y310242D01*
X86173Y310533D01*
X86298Y310783D01*
X86465Y310992D01*
G01X86090Y313050D02*
X88590D01*
X88090Y312550D01*
G01X86090D02*
Y313550D01*
G01Y316150D02*
X86132Y316442D01*
X86257Y316775D01*
X86465Y316983D01*
X86757Y317067D01*
X87048Y316983D01*
X87298Y316733D01*
X87423Y316358D01*
Y315942D01*
X87507Y315692D01*
X87715Y315483D01*
X88007Y315400D01*
X88298Y315525D01*
X88507Y315817D01*
X88590Y316150D01*
X88507Y316483D01*
X88298Y316775D01*
X88007Y316900D01*
X87715Y316817D01*
X87507Y316608D01*
X87423Y316358D01*
Y315942D01*
X87298Y315567D01*
X87048Y315317D01*
X86757Y315233D01*
X86465Y315317D01*
X86257Y315525D01*
X86132Y315858D01*
X86090Y316150D01*
G01X86465Y318333D02*
X86257Y318583D01*
X86132Y318875D01*
X86090Y319250D01*
X86173Y319625D01*
X86340Y319917D01*
X86632Y320125D01*
X86965Y320167D01*
X87298Y320083D01*
X87507Y319875D01*
X87673Y319583D01*
X87715Y319292D01*
X87673Y319000D01*
X87507Y318625D01*
X88590Y318750D01*
Y319875D01*
G01X88792Y324267D02*
X88917Y324017D01*
X89000Y323725D01*
Y323392D01*
X88875Y323017D01*
X88667Y322725D01*
X88417Y322517D01*
X88000Y322350D01*
X87625Y322308D01*
X87250Y322392D01*
X87000Y322517D01*
X86750Y322767D01*
X86583Y323058D01*
X86500Y323350D01*
Y323642D01*
X86583Y323933D01*
X86708Y324183D01*
X86875Y324392D01*
G01X86500Y326450D02*
X89000D01*
X88500Y325950D01*
G01X86500D02*
Y326950D01*
G01Y329550D02*
X86542Y329842D01*
X86667Y330175D01*
X86875Y330383D01*
X87167Y330467D01*
X87458Y330383D01*
X87708Y330133D01*
X87833Y329758D01*
Y329342D01*
X87917Y329092D01*
X88125Y328883D01*
X88417Y328800D01*
X88708Y328925D01*
X88917Y329217D01*
X89000Y329550D01*
X88917Y329883D01*
X88708Y330175D01*
X88417Y330300D01*
X88125Y330217D01*
X87917Y330008D01*
X87833Y329758D01*
Y329342D01*
X87708Y328967D01*
X87458Y328717D01*
X87167Y328633D01*
X86875Y328717D01*
X86667Y328925D01*
X86542Y329258D01*
X86500Y329550D01*
G01X87000Y331733D02*
X86708Y331983D01*
X86542Y332317D01*
X86500Y332692D01*
X86542Y333025D01*
X86750Y333358D01*
X87000Y333567D01*
X87250Y333608D01*
X87542Y333525D01*
X87750Y333233D01*
X87833Y332942D01*
Y332567D01*
G01Y332942D02*
X87958Y333192D01*
X88167Y333400D01*
X88417Y333483D01*
X88667Y333400D01*
X88875Y333192D01*
X89000Y332817D01*
X88958Y332442D01*
X88792Y332067D01*
G01X144833Y331692D02*
X145083Y331817D01*
X145375Y331900D01*
X145708D01*
X146083Y331775D01*
X146375Y331567D01*
X146583Y331317D01*
X146750Y330900D01*
X146792Y330525D01*
X146708Y330150D01*
X146583Y329900D01*
X146333Y329650D01*
X146042Y329483D01*
X145750Y329400D01*
X145458D01*
X145167Y329483D01*
X144917Y329608D01*
X144708Y329775D01*
G01X142150Y329400D02*
Y331900D01*
X143692Y330108D01*
X141608D01*
G01X139550Y331900D02*
X139883Y331817D01*
X140133Y331608D01*
X140300Y331358D01*
X140425Y331025D01*
X140467Y330650D01*
X140425Y330275D01*
X140300Y329942D01*
X140133Y329692D01*
X139883Y329483D01*
X139550Y329400D01*
X139217Y329483D01*
X138967Y329692D01*
X138800Y329942D01*
X138675Y330275D01*
X138633Y330650D01*
X138675Y331025D01*
X138800Y331358D01*
X138967Y331608D01*
X139217Y331817D01*
X139550Y331900D01*
G01X137158Y329692D02*
X136867Y329483D01*
X136533Y329400D01*
X136200Y329483D01*
X135908Y329733D01*
X135700Y330108D01*
X135617Y330483D01*
Y330942D01*
X135700Y331317D01*
X135908Y331650D01*
X136158Y331817D01*
X136450Y331900D01*
X136783Y331817D01*
X137033Y331650D01*
X137200Y331400D01*
X137283Y331067D01*
X137200Y330775D01*
X136992Y330483D01*
X136742Y330317D01*
X136450Y330275D01*
X136117Y330358D01*
X135867Y330567D01*
X135617Y330942D01*
G01X134233Y420792D02*
X134483Y420917D01*
X134775Y421000D01*
X135108D01*
X135483Y420875D01*
X135775Y420667D01*
X135983Y420417D01*
X136150Y420000D01*
X136192Y419625D01*
X136108Y419250D01*
X135983Y419000D01*
X135733Y418750D01*
X135442Y418583D01*
X135150Y418500D01*
X134858D01*
X134567Y418583D01*
X134317Y418708D01*
X134108Y418875D01*
G01X132967D02*
X132717Y418667D01*
X132425Y418542D01*
X132050Y418500D01*
X131675Y418583D01*
X131383Y418750D01*
X131175Y419042D01*
X131133Y419375D01*
X131217Y419708D01*
X131425Y419917D01*
X131717Y420083D01*
X132008Y420125D01*
X132300Y420083D01*
X132675Y419917D01*
X132550Y421000D01*
X131425D01*
G01X129658Y418792D02*
X129367Y418583D01*
X129033Y418500D01*
X128700Y418583D01*
X128408Y418833D01*
X128200Y419208D01*
X128117Y419583D01*
Y420042D01*
X128200Y420417D01*
X128408Y420750D01*
X128658Y420917D01*
X128950Y421000D01*
X129283Y420917D01*
X129533Y420750D01*
X129700Y420500D01*
X129783Y420167D01*
X129700Y419875D01*
X129492Y419583D01*
X129242Y419417D01*
X128950Y419375D01*
X128617Y419458D01*
X128367Y419667D01*
X128117Y420042D01*
G01X125350Y418500D02*
Y421000D01*
X126892Y419208D01*
X124808D01*
G01X134903Y426422D02*
X135153Y426547D01*
X135445Y426630D01*
X135778D01*
X136153Y426505D01*
X136445Y426297D01*
X136653Y426047D01*
X136820Y425630D01*
X136862Y425255D01*
X136778Y424880D01*
X136653Y424630D01*
X136403Y424380D01*
X136112Y424213D01*
X135820Y424130D01*
X135528D01*
X135237Y424213D01*
X134987Y424338D01*
X134778Y424505D01*
G01X133637D02*
X133387Y424297D01*
X133095Y424172D01*
X132720Y424130D01*
X132345Y424213D01*
X132053Y424380D01*
X131845Y424672D01*
X131803Y425005D01*
X131887Y425338D01*
X132095Y425547D01*
X132387Y425713D01*
X132678Y425755D01*
X132970Y425713D01*
X133345Y425547D01*
X133220Y426630D01*
X132095D01*
G01X129620Y424130D02*
Y426630D01*
X130120Y426130D01*
G01Y424130D02*
X129120D01*
G01X126520D02*
Y426630D01*
X127020Y426130D01*
G01Y424130D02*
X126020D01*
G01X148400Y404400D02*
Y376600D01*
X120600D01*
Y404400D01*
X148400D01*
G01X135233Y431792D02*
X135483Y431917D01*
X135775Y432000D01*
X136108D01*
X136483Y431875D01*
X136775Y431667D01*
X136983Y431417D01*
X137150Y431000D01*
X137192Y430625D01*
X137108Y430250D01*
X136983Y430000D01*
X136733Y429750D01*
X136442Y429583D01*
X136150Y429500D01*
X135858D01*
X135567Y429583D01*
X135317Y429708D01*
X135108Y429875D01*
G01X133967D02*
X133717Y429667D01*
X133425Y429542D01*
X133050Y429500D01*
X132675Y429583D01*
X132383Y429750D01*
X132175Y430042D01*
X132133Y430375D01*
X132217Y430708D01*
X132425Y430917D01*
X132717Y431083D01*
X133008Y431125D01*
X133300Y431083D01*
X133675Y430917D01*
X133550Y432000D01*
X132425D01*
G01X130742Y430542D02*
X130450Y430833D01*
X130200Y431000D01*
X129867Y431083D01*
X129575Y431000D01*
X129367Y430833D01*
X129200Y430583D01*
X129158Y430292D01*
X129200Y430042D01*
X129367Y429792D01*
X129617Y429583D01*
X129908Y429500D01*
X130242Y429583D01*
X130533Y429833D01*
X130700Y430208D01*
X130742Y430625D01*
X130658Y431167D01*
X130533Y431458D01*
X130325Y431750D01*
X130033Y431958D01*
X129742Y432000D01*
X129450Y431917D01*
X129242Y431708D01*
G01X127767Y430000D02*
X127517Y429708D01*
X127183Y429542D01*
X126808Y429500D01*
X126475Y429542D01*
X126142Y429750D01*
X125933Y430000D01*
X125892Y430250D01*
X125975Y430542D01*
X126267Y430750D01*
X126558Y430833D01*
X126933D01*
G01X126558D02*
X126308Y430958D01*
X126100Y431167D01*
X126017Y431417D01*
X126100Y431667D01*
X126308Y431875D01*
X126683Y432000D01*
X127058Y431958D01*
X127433Y431792D01*
G01X154000Y243000D02*
Y262000D01*
X290000D01*
Y282500D01*
G01X179392Y296667D02*
X179517Y296417D01*
X179600Y296125D01*
Y295792D01*
X179475Y295417D01*
X179267Y295125D01*
X179017Y294917D01*
X178600Y294750D01*
X178225Y294708D01*
X177850Y294792D01*
X177600Y294917D01*
X177350Y295167D01*
X177183Y295458D01*
X177100Y295750D01*
Y296042D01*
X177183Y296333D01*
X177308Y296583D01*
X177475Y296792D01*
G01X177100Y299350D02*
X179600D01*
X177808Y297808D01*
Y299892D01*
G01X177100Y301950D02*
X179600D01*
X179100Y301450D01*
G01X177100D02*
Y302450D01*
G01Y305550D02*
X179600D01*
X177808Y304008D01*
Y306092D01*
G01X150733Y273292D02*
X150983Y273417D01*
X151275Y273500D01*
X151608D01*
X151983Y273375D01*
X152275Y273167D01*
X152483Y272917D01*
X152650Y272500D01*
X152692Y272125D01*
X152608Y271750D01*
X152483Y271500D01*
X152233Y271250D01*
X151942Y271083D01*
X151650Y271000D01*
X151358D01*
X151067Y271083D01*
X150817Y271208D01*
X150608Y271375D01*
G01X149342Y273083D02*
X149092Y273333D01*
X148800Y273458D01*
X148467Y273500D01*
X148050Y273417D01*
X147758Y273208D01*
X147675Y272958D01*
X147717Y272708D01*
X147883Y272500D01*
X148717Y272083D01*
X149092Y271792D01*
X149342Y271375D01*
X149425Y271000D01*
X147675D01*
G01X146242Y272042D02*
X145950Y272333D01*
X145700Y272500D01*
X145367Y272583D01*
X145075Y272500D01*
X144867Y272333D01*
X144700Y272083D01*
X144658Y271792D01*
X144700Y271542D01*
X144867Y271292D01*
X145117Y271083D01*
X145408Y271000D01*
X145742Y271083D01*
X146033Y271333D01*
X146200Y271708D01*
X146242Y272125D01*
X146158Y272667D01*
X146033Y272958D01*
X145825Y273250D01*
X145533Y273458D01*
X145242Y273500D01*
X144950Y273417D01*
X144742Y273208D01*
G01X141850Y271000D02*
Y273500D01*
X143392Y271708D01*
X141308D01*
G01X150733Y253292D02*
X150983Y253417D01*
X151275Y253500D01*
X151608D01*
X151983Y253375D01*
X152275Y253167D01*
X152483Y252917D01*
X152650Y252500D01*
X152692Y252125D01*
X152608Y251750D01*
X152483Y251500D01*
X152233Y251250D01*
X151942Y251083D01*
X151650Y251000D01*
X151358D01*
X151067Y251083D01*
X150817Y251208D01*
X150608Y251375D01*
G01X149342Y253083D02*
X149092Y253333D01*
X148800Y253458D01*
X148467Y253500D01*
X148050Y253417D01*
X147758Y253208D01*
X147675Y252958D01*
X147717Y252708D01*
X147883Y252500D01*
X148717Y252083D01*
X149092Y251792D01*
X149342Y251375D01*
X149425Y251000D01*
X147675D01*
G01X146367Y251500D02*
X146117Y251208D01*
X145783Y251042D01*
X145408Y251000D01*
X145075Y251042D01*
X144742Y251250D01*
X144533Y251500D01*
X144492Y251750D01*
X144575Y252042D01*
X144867Y252250D01*
X145158Y252333D01*
X145533D01*
G01X145158D02*
X144908Y252458D01*
X144700Y252667D01*
X144617Y252917D01*
X144700Y253167D01*
X144908Y253375D01*
X145283Y253500D01*
X145658Y253458D01*
X146033Y253292D01*
G01X143142Y252042D02*
X142850Y252333D01*
X142600Y252500D01*
X142267Y252583D01*
X141975Y252500D01*
X141767Y252333D01*
X141600Y252083D01*
X141558Y251792D01*
X141600Y251542D01*
X141767Y251292D01*
X142017Y251083D01*
X142308Y251000D01*
X142642Y251083D01*
X142933Y251333D01*
X143100Y251708D01*
X143142Y252125D01*
X143058Y252667D01*
X142933Y252958D01*
X142725Y253250D01*
X142433Y253458D01*
X142142Y253500D01*
X141850Y253417D01*
X141642Y253208D01*
G01X182823Y288042D02*
X183073Y288167D01*
X183365Y288250D01*
X183698D01*
X184073Y288125D01*
X184365Y287917D01*
X184573Y287667D01*
X184740Y287250D01*
X184782Y286875D01*
X184698Y286500D01*
X184573Y286250D01*
X184323Y286000D01*
X184032Y285833D01*
X183740Y285750D01*
X183448D01*
X183157Y285833D01*
X182907Y285958D01*
X182698Y286125D01*
G01X180140Y285750D02*
Y288250D01*
X181682Y286458D01*
X179598D01*
G01X177623Y285750D02*
X177540Y286292D01*
X177415Y286750D01*
X177248Y287167D01*
X177040Y287625D01*
X176707Y288250D01*
X178373D01*
G01X174440Y285750D02*
Y288250D01*
X174940Y287750D01*
G01Y285750D02*
X173940D01*
G01X195023Y288042D02*
X195273Y288167D01*
X195565Y288250D01*
X195898D01*
X196273Y288125D01*
X196565Y287917D01*
X196773Y287667D01*
X196940Y287250D01*
X196982Y286875D01*
X196898Y286500D01*
X196773Y286250D01*
X196523Y286000D01*
X196232Y285833D01*
X195940Y285750D01*
X195648D01*
X195357Y285833D01*
X195107Y285958D01*
X194898Y286125D01*
G01X192340Y285750D02*
Y288250D01*
X193882Y286458D01*
X191798D01*
G01X189823Y285750D02*
X189740Y286292D01*
X189615Y286750D01*
X189448Y287167D01*
X189240Y287625D01*
X188907Y288250D01*
X190573D01*
G01X186640D02*
X186973Y288167D01*
X187223Y287958D01*
X187390Y287708D01*
X187515Y287375D01*
X187557Y287000D01*
X187515Y286625D01*
X187390Y286292D01*
X187223Y286042D01*
X186973Y285833D01*
X186640Y285750D01*
X186307Y285833D01*
X186057Y286042D01*
X185890Y286292D01*
X185765Y286625D01*
X185723Y287000D01*
X185765Y287375D01*
X185890Y287708D01*
X186057Y287958D01*
X186307Y288167D01*
X186640Y288250D01*
G01X208023Y288042D02*
X208273Y288167D01*
X208565Y288250D01*
X208898D01*
X209273Y288125D01*
X209565Y287917D01*
X209773Y287667D01*
X209940Y287250D01*
X209982Y286875D01*
X209898Y286500D01*
X209773Y286250D01*
X209523Y286000D01*
X209232Y285833D01*
X208940Y285750D01*
X208648D01*
X208357Y285833D01*
X208107Y285958D01*
X207898Y286125D01*
G01X205340Y285750D02*
Y288250D01*
X206882Y286458D01*
X204798D01*
G01X203532Y286792D02*
X203240Y287083D01*
X202990Y287250D01*
X202657Y287333D01*
X202365Y287250D01*
X202157Y287083D01*
X201990Y286833D01*
X201948Y286542D01*
X201990Y286292D01*
X202157Y286042D01*
X202407Y285833D01*
X202698Y285750D01*
X203032Y285833D01*
X203323Y286083D01*
X203490Y286458D01*
X203532Y286875D01*
X203448Y287417D01*
X203323Y287708D01*
X203115Y288000D01*
X202823Y288208D01*
X202532Y288250D01*
X202240Y288167D01*
X202032Y287958D01*
G01X200348Y286042D02*
X200057Y285833D01*
X199723Y285750D01*
X199390Y285833D01*
X199098Y286083D01*
X198890Y286458D01*
X198807Y286833D01*
Y287292D01*
X198890Y287667D01*
X199098Y288000D01*
X199348Y288167D01*
X199640Y288250D01*
X199973Y288167D01*
X200223Y288000D01*
X200390Y287750D01*
X200473Y287417D01*
X200390Y287125D01*
X200182Y286833D01*
X199932Y286667D01*
X199640Y286625D01*
X199307Y286708D01*
X199057Y286917D01*
X198807Y287292D01*
G01X160392Y296667D02*
X160517Y296417D01*
X160600Y296125D01*
Y295792D01*
X160475Y295417D01*
X160267Y295125D01*
X160017Y294917D01*
X159600Y294750D01*
X159225Y294708D01*
X158850Y294792D01*
X158600Y294917D01*
X158350Y295167D01*
X158183Y295458D01*
X158100Y295750D01*
Y296042D01*
X158183Y296333D01*
X158308Y296583D01*
X158475Y296792D01*
G01X158100Y299350D02*
X160600D01*
X158808Y297808D01*
Y299892D01*
G01X158600Y301033D02*
X158308Y301283D01*
X158142Y301617D01*
X158100Y301992D01*
X158142Y302325D01*
X158350Y302658D01*
X158600Y302867D01*
X158850Y302908D01*
X159142Y302825D01*
X159350Y302533D01*
X159433Y302242D01*
Y301867D01*
G01Y302242D02*
X159558Y302492D01*
X159767Y302700D01*
X160017Y302783D01*
X160267Y302700D01*
X160475Y302492D01*
X160600Y302117D01*
X160558Y301742D01*
X160392Y301367D01*
G01X158100Y305050D02*
X158142Y305342D01*
X158267Y305675D01*
X158475Y305883D01*
X158767Y305967D01*
X159058Y305883D01*
X159308Y305633D01*
X159433Y305258D01*
Y304842D01*
X159517Y304592D01*
X159725Y304383D01*
X160017Y304300D01*
X160308Y304425D01*
X160517Y304717D01*
X160600Y305050D01*
X160517Y305383D01*
X160308Y305675D01*
X160017Y305800D01*
X159725Y305717D01*
X159517Y305508D01*
X159433Y305258D01*
Y304842D01*
X159308Y304467D01*
X159058Y304217D01*
X158767Y304133D01*
X158475Y304217D01*
X158267Y304425D01*
X158142Y304758D01*
X158100Y305050D01*
G01X174392Y296667D02*
X174517Y296417D01*
X174600Y296125D01*
Y295792D01*
X174475Y295417D01*
X174267Y295125D01*
X174017Y294917D01*
X173600Y294750D01*
X173225Y294708D01*
X172850Y294792D01*
X172600Y294917D01*
X172350Y295167D01*
X172183Y295458D01*
X172100Y295750D01*
Y296042D01*
X172183Y296333D01*
X172308Y296583D01*
X172475Y296792D01*
G01X172100Y299350D02*
X174600D01*
X172808Y297808D01*
Y299892D01*
G01X174183Y301158D02*
X174433Y301408D01*
X174558Y301700D01*
X174600Y302033D01*
X174517Y302450D01*
X174308Y302742D01*
X174058Y302825D01*
X173808Y302783D01*
X173600Y302617D01*
X173183Y301783D01*
X172892Y301408D01*
X172475Y301158D01*
X172100Y301075D01*
Y302825D01*
G01X173142Y304258D02*
X173433Y304550D01*
X173600Y304800D01*
X173683Y305133D01*
X173600Y305425D01*
X173433Y305633D01*
X173183Y305800D01*
X172892Y305842D01*
X172642Y305800D01*
X172392Y305633D01*
X172183Y305383D01*
X172100Y305092D01*
X172183Y304758D01*
X172433Y304467D01*
X172808Y304300D01*
X173225Y304258D01*
X173767Y304342D01*
X174058Y304467D01*
X174350Y304675D01*
X174558Y304967D01*
X174600Y305258D01*
X174517Y305550D01*
X174308Y305758D01*
G01X164892Y296667D02*
X165017Y296417D01*
X165100Y296125D01*
Y295792D01*
X164975Y295417D01*
X164767Y295125D01*
X164517Y294917D01*
X164100Y294750D01*
X163725Y294708D01*
X163350Y294792D01*
X163100Y294917D01*
X162850Y295167D01*
X162683Y295458D01*
X162600Y295750D01*
Y296042D01*
X162683Y296333D01*
X162808Y296583D01*
X162975Y296792D01*
G01X162600Y299350D02*
X165100D01*
X163308Y297808D01*
Y299892D01*
G01X164683Y301158D02*
X164933Y301408D01*
X165058Y301700D01*
X165100Y302033D01*
X165017Y302450D01*
X164808Y302742D01*
X164558Y302825D01*
X164308Y302783D01*
X164100Y302617D01*
X163683Y301783D01*
X163392Y301408D01*
X162975Y301158D01*
X162600Y301075D01*
Y302825D01*
G01X163100Y304133D02*
X162808Y304383D01*
X162642Y304717D01*
X162600Y305092D01*
X162642Y305425D01*
X162850Y305758D01*
X163100Y305967D01*
X163350Y306008D01*
X163642Y305925D01*
X163850Y305633D01*
X163933Y305342D01*
Y304967D01*
G01Y305342D02*
X164058Y305592D01*
X164267Y305800D01*
X164517Y305883D01*
X164767Y305800D01*
X164975Y305592D01*
X165100Y305217D01*
X165058Y304842D01*
X164892Y304467D01*
G01X169392Y296667D02*
X169517Y296417D01*
X169600Y296125D01*
Y295792D01*
X169475Y295417D01*
X169267Y295125D01*
X169017Y294917D01*
X168600Y294750D01*
X168225Y294708D01*
X167850Y294792D01*
X167600Y294917D01*
X167350Y295167D01*
X167183Y295458D01*
X167100Y295750D01*
Y296042D01*
X167183Y296333D01*
X167308Y296583D01*
X167475Y296792D01*
G01X167100Y299350D02*
X169600D01*
X167808Y297808D01*
Y299892D01*
G01X167100Y301950D02*
X169600D01*
X169100Y301450D01*
G01X167100D02*
Y302450D01*
G01X167392Y304342D02*
X167183Y304633D01*
X167100Y304967D01*
X167183Y305300D01*
X167433Y305592D01*
X167808Y305800D01*
X168183Y305883D01*
X168642D01*
X169017Y305800D01*
X169350Y305592D01*
X169517Y305342D01*
X169600Y305050D01*
X169517Y304717D01*
X169350Y304467D01*
X169100Y304300D01*
X168767Y304217D01*
X168475Y304300D01*
X168183Y304508D01*
X168017Y304758D01*
X167975Y305050D01*
X168058Y305383D01*
X168267Y305633D01*
X168642Y305883D01*
G01X145892Y279167D02*
X146017Y278917D01*
X146100Y278625D01*
Y278292D01*
X145975Y277917D01*
X145767Y277625D01*
X145517Y277417D01*
X145100Y277250D01*
X144725Y277208D01*
X144350Y277292D01*
X144100Y277417D01*
X143850Y277667D01*
X143683Y277958D01*
X143600Y278250D01*
Y278542D01*
X143683Y278833D01*
X143808Y279083D01*
X143975Y279292D01*
G01X144100Y280433D02*
X143808Y280683D01*
X143642Y281017D01*
X143600Y281392D01*
X143642Y281725D01*
X143850Y282058D01*
X144100Y282267D01*
X144350Y282308D01*
X144642Y282225D01*
X144850Y281933D01*
X144933Y281642D01*
Y281267D01*
G01Y281642D02*
X145058Y281892D01*
X145267Y282100D01*
X145517Y282183D01*
X145767Y282100D01*
X145975Y281892D01*
X146100Y281517D01*
X146058Y281142D01*
X145892Y280767D01*
G01X143892Y283742D02*
X143683Y284033D01*
X143600Y284367D01*
X143683Y284700D01*
X143933Y284992D01*
X144308Y285200D01*
X144683Y285283D01*
X145142D01*
X145517Y285200D01*
X145850Y284992D01*
X146017Y284742D01*
X146100Y284450D01*
X146017Y284117D01*
X145850Y283867D01*
X145600Y283700D01*
X145267Y283617D01*
X144975Y283700D01*
X144683Y283908D01*
X144517Y284158D01*
X144475Y284450D01*
X144558Y284783D01*
X144767Y285033D01*
X145142Y285283D01*
G01X144100Y286633D02*
X143808Y286883D01*
X143642Y287217D01*
X143600Y287592D01*
X143642Y287925D01*
X143850Y288258D01*
X144100Y288467D01*
X144350Y288508D01*
X144642Y288425D01*
X144850Y288133D01*
X144933Y287842D01*
Y287467D01*
G01Y287842D02*
X145058Y288092D01*
X145267Y288300D01*
X145517Y288383D01*
X145767Y288300D01*
X145975Y288092D01*
X146100Y287717D01*
X146058Y287342D01*
X145892Y286967D01*
G01X149892Y292667D02*
X150017Y292417D01*
X150100Y292125D01*
Y291792D01*
X149975Y291417D01*
X149767Y291125D01*
X149517Y290917D01*
X149100Y290750D01*
X148725Y290708D01*
X148350Y290792D01*
X148100Y290917D01*
X147850Y291167D01*
X147683Y291458D01*
X147600Y291750D01*
Y292042D01*
X147683Y292333D01*
X147808Y292583D01*
X147975Y292792D01*
G01X148100Y293933D02*
X147808Y294183D01*
X147642Y294517D01*
X147600Y294892D01*
X147642Y295225D01*
X147850Y295558D01*
X148100Y295767D01*
X148350Y295808D01*
X148642Y295725D01*
X148850Y295433D01*
X148933Y295142D01*
Y294767D01*
G01Y295142D02*
X149058Y295392D01*
X149267Y295600D01*
X149517Y295683D01*
X149767Y295600D01*
X149975Y295392D01*
X150100Y295017D01*
X150058Y294642D01*
X149892Y294267D01*
G01X147892Y297242D02*
X147683Y297533D01*
X147600Y297867D01*
X147683Y298200D01*
X147933Y298492D01*
X148308Y298700D01*
X148683Y298783D01*
X149142D01*
X149517Y298700D01*
X149850Y298492D01*
X150017Y298242D01*
X150100Y297950D01*
X150017Y297617D01*
X149850Y297367D01*
X149600Y297200D01*
X149267Y297117D01*
X148975Y297200D01*
X148683Y297408D01*
X148517Y297658D01*
X148475Y297950D01*
X148558Y298283D01*
X148767Y298533D01*
X149142Y298783D01*
G01X147600Y301050D02*
X150100D01*
X149600Y300550D01*
G01X147600D02*
Y301550D01*
G01X145392Y292667D02*
X145517Y292417D01*
X145600Y292125D01*
Y291792D01*
X145475Y291417D01*
X145267Y291125D01*
X145017Y290917D01*
X144600Y290750D01*
X144225Y290708D01*
X143850Y290792D01*
X143600Y290917D01*
X143350Y291167D01*
X143183Y291458D01*
X143100Y291750D01*
Y292042D01*
X143183Y292333D01*
X143308Y292583D01*
X143475Y292792D01*
G01X143600Y293933D02*
X143308Y294183D01*
X143142Y294517D01*
X143100Y294892D01*
X143142Y295225D01*
X143350Y295558D01*
X143600Y295767D01*
X143850Y295808D01*
X144142Y295725D01*
X144350Y295433D01*
X144433Y295142D01*
Y294767D01*
G01Y295142D02*
X144558Y295392D01*
X144767Y295600D01*
X145017Y295683D01*
X145267Y295600D01*
X145475Y295392D01*
X145600Y295017D01*
X145558Y294642D01*
X145392Y294267D01*
G01X143392Y297242D02*
X143183Y297533D01*
X143100Y297867D01*
X143183Y298200D01*
X143433Y298492D01*
X143808Y298700D01*
X144183Y298783D01*
X144642D01*
X145017Y298700D01*
X145350Y298492D01*
X145517Y298242D01*
X145600Y297950D01*
X145517Y297617D01*
X145350Y297367D01*
X145100Y297200D01*
X144767Y297117D01*
X144475Y297200D01*
X144183Y297408D01*
X144017Y297658D01*
X143975Y297950D01*
X144058Y298283D01*
X144267Y298533D01*
X144642Y298783D01*
G01X145600Y301050D02*
X145517Y300717D01*
X145308Y300467D01*
X145058Y300300D01*
X144725Y300175D01*
X144350Y300133D01*
X143975Y300175D01*
X143642Y300300D01*
X143392Y300467D01*
X143183Y300717D01*
X143100Y301050D01*
X143183Y301383D01*
X143392Y301633D01*
X143642Y301800D01*
X143975Y301925D01*
X144350Y301967D01*
X144725Y301925D01*
X145058Y301800D01*
X145308Y301633D01*
X145517Y301383D01*
X145600Y301050D01*
G01X153392Y292167D02*
X153517Y291917D01*
X153600Y291625D01*
Y291292D01*
X153475Y290917D01*
X153267Y290625D01*
X153017Y290417D01*
X152600Y290250D01*
X152225Y290208D01*
X151850Y290292D01*
X151600Y290417D01*
X151350Y290667D01*
X151183Y290958D01*
X151100Y291250D01*
Y291542D01*
X151183Y291833D01*
X151308Y292083D01*
X151475Y292292D01*
G01X151600Y293433D02*
X151308Y293683D01*
X151142Y294017D01*
X151100Y294392D01*
X151142Y294725D01*
X151350Y295058D01*
X151600Y295267D01*
X151850Y295308D01*
X152142Y295225D01*
X152350Y294933D01*
X152433Y294642D01*
Y294267D01*
G01Y294642D02*
X152558Y294892D01*
X152767Y295100D01*
X153017Y295183D01*
X153267Y295100D01*
X153475Y294892D01*
X153600Y294517D01*
X153558Y294142D01*
X153392Y293767D01*
G01X151100Y297450D02*
X151142Y297742D01*
X151267Y298075D01*
X151475Y298283D01*
X151767Y298367D01*
X152058Y298283D01*
X152308Y298033D01*
X152433Y297658D01*
Y297242D01*
X152517Y296992D01*
X152725Y296783D01*
X153017Y296700D01*
X153308Y296825D01*
X153517Y297117D01*
X153600Y297450D01*
X153517Y297783D01*
X153308Y298075D01*
X153017Y298200D01*
X152725Y298117D01*
X152517Y297908D01*
X152433Y297658D01*
Y297242D01*
X152308Y296867D01*
X152058Y296617D01*
X151767Y296533D01*
X151475Y296617D01*
X151267Y296825D01*
X151142Y297158D01*
X151100Y297450D01*
G01Y300550D02*
X151142Y300842D01*
X151267Y301175D01*
X151475Y301383D01*
X151767Y301467D01*
X152058Y301383D01*
X152308Y301133D01*
X152433Y300758D01*
Y300342D01*
X152517Y300092D01*
X152725Y299883D01*
X153017Y299800D01*
X153308Y299925D01*
X153517Y300217D01*
X153600Y300550D01*
X153517Y300883D01*
X153308Y301175D01*
X153017Y301300D01*
X152725Y301217D01*
X152517Y301008D01*
X152433Y300758D01*
Y300342D01*
X152308Y299967D01*
X152058Y299717D01*
X151767Y299633D01*
X151475Y299717D01*
X151267Y299925D01*
X151142Y300258D01*
X151100Y300550D01*
G01X178892Y270667D02*
X179017Y270417D01*
X179100Y270125D01*
Y269792D01*
X178975Y269417D01*
X178767Y269125D01*
X178517Y268917D01*
X178100Y268750D01*
X177725Y268708D01*
X177350Y268792D01*
X177100Y268917D01*
X176850Y269167D01*
X176683Y269458D01*
X176600Y269750D01*
Y270042D01*
X176683Y270333D01*
X176808Y270583D01*
X176975Y270792D01*
G01X177100Y271933D02*
X176808Y272183D01*
X176642Y272517D01*
X176600Y272892D01*
X176642Y273225D01*
X176850Y273558D01*
X177100Y273767D01*
X177350Y273808D01*
X177642Y273725D01*
X177850Y273433D01*
X177933Y273142D01*
Y272767D01*
G01Y273142D02*
X178058Y273392D01*
X178267Y273600D01*
X178517Y273683D01*
X178767Y273600D01*
X178975Y273392D01*
X179100Y273017D01*
X179058Y272642D01*
X178892Y272267D01*
G01X176600Y275950D02*
X176642Y276242D01*
X176767Y276575D01*
X176975Y276783D01*
X177267Y276867D01*
X177558Y276783D01*
X177808Y276533D01*
X177933Y276158D01*
Y275742D01*
X178017Y275492D01*
X178225Y275283D01*
X178517Y275200D01*
X178808Y275325D01*
X179017Y275617D01*
X179100Y275950D01*
X179017Y276283D01*
X178808Y276575D01*
X178517Y276700D01*
X178225Y276617D01*
X178017Y276408D01*
X177933Y276158D01*
Y275742D01*
X177808Y275367D01*
X177558Y275117D01*
X177267Y275033D01*
X176975Y275117D01*
X176767Y275325D01*
X176642Y275658D01*
X176600Y275950D01*
G01X177642Y278258D02*
X177933Y278550D01*
X178100Y278800D01*
X178183Y279133D01*
X178100Y279425D01*
X177933Y279633D01*
X177683Y279800D01*
X177392Y279842D01*
X177142Y279800D01*
X176892Y279633D01*
X176683Y279383D01*
X176600Y279092D01*
X176683Y278758D01*
X176933Y278467D01*
X177308Y278300D01*
X177725Y278258D01*
X178267Y278342D01*
X178558Y278467D01*
X178850Y278675D01*
X179058Y278967D01*
X179100Y279258D01*
X179017Y279550D01*
X178808Y279758D01*
G01X150972Y265792D02*
X151222Y265917D01*
X151514Y266000D01*
X151847D01*
X152222Y265875D01*
X152514Y265667D01*
X152722Y265417D01*
X152889Y265000D01*
X152931Y264625D01*
X152847Y264250D01*
X152722Y264000D01*
X152472Y263750D01*
X152181Y263583D01*
X151889Y263500D01*
X151597D01*
X151306Y263583D01*
X151056Y263708D01*
X150847Y263875D01*
G01X149581Y265583D02*
X149331Y265833D01*
X149039Y265958D01*
X148706Y266000D01*
X148289Y265917D01*
X147997Y265708D01*
X147914Y265458D01*
X147956Y265208D01*
X148122Y265000D01*
X148956Y264583D01*
X149331Y264292D01*
X149581Y263875D01*
X149664Y263500D01*
X147914D01*
G01X146397Y263792D02*
X146106Y263583D01*
X145772Y263500D01*
X145439Y263583D01*
X145147Y263833D01*
X144939Y264208D01*
X144856Y264583D01*
Y265042D01*
X144939Y265417D01*
X145147Y265750D01*
X145397Y265917D01*
X145689Y266000D01*
X146022Y265917D01*
X146272Y265750D01*
X146439Y265500D01*
X146522Y265167D01*
X146439Y264875D01*
X146231Y264583D01*
X145981Y264417D01*
X145689Y264375D01*
X145356Y264458D01*
X145106Y264667D01*
X144856Y265042D01*
G01X143297Y263792D02*
X143006Y263583D01*
X142672Y263500D01*
X142339Y263583D01*
X142047Y263833D01*
X141839Y264208D01*
X141756Y264583D01*
Y265042D01*
X141839Y265417D01*
X142047Y265750D01*
X142297Y265917D01*
X142589Y266000D01*
X142922Y265917D01*
X143172Y265750D01*
X143339Y265500D01*
X143422Y265167D01*
X143339Y264875D01*
X143131Y264583D01*
X142881Y264417D01*
X142589Y264375D01*
X142256Y264458D01*
X142006Y264667D01*
X141756Y265042D01*
G01X151022Y257292D02*
X151272Y257417D01*
X151564Y257500D01*
X151897D01*
X152272Y257375D01*
X152564Y257167D01*
X152772Y256917D01*
X152939Y256500D01*
X152981Y256125D01*
X152897Y255750D01*
X152772Y255500D01*
X152522Y255250D01*
X152231Y255083D01*
X151939Y255000D01*
X151647D01*
X151356Y255083D01*
X151106Y255208D01*
X150897Y255375D01*
G01X149631Y257083D02*
X149381Y257333D01*
X149089Y257458D01*
X148756Y257500D01*
X148339Y257417D01*
X148047Y257208D01*
X147964Y256958D01*
X148006Y256708D01*
X148172Y256500D01*
X149006Y256083D01*
X149381Y255792D01*
X149631Y255375D01*
X149714Y255000D01*
X147964D01*
G01X146447Y255292D02*
X146156Y255083D01*
X145822Y255000D01*
X145489Y255083D01*
X145197Y255333D01*
X144989Y255708D01*
X144906Y256083D01*
Y256542D01*
X144989Y256917D01*
X145197Y257250D01*
X145447Y257417D01*
X145739Y257500D01*
X146072Y257417D01*
X146322Y257250D01*
X146489Y257000D01*
X146572Y256667D01*
X146489Y256375D01*
X146281Y256083D01*
X146031Y255917D01*
X145739Y255875D01*
X145406Y255958D01*
X145156Y256167D01*
X144906Y256542D01*
G01X142722Y255000D02*
X142639Y255542D01*
X142514Y256000D01*
X142347Y256417D01*
X142139Y256875D01*
X141806Y257500D01*
X143472D01*
G01X150733Y269792D02*
X150983Y269917D01*
X151275Y270000D01*
X151608D01*
X151983Y269875D01*
X152275Y269667D01*
X152483Y269417D01*
X152650Y269000D01*
X152692Y268625D01*
X152608Y268250D01*
X152483Y268000D01*
X152233Y267750D01*
X151942Y267583D01*
X151650Y267500D01*
X151358D01*
X151067Y267583D01*
X150817Y267708D01*
X150608Y267875D01*
G01X149342Y269583D02*
X149092Y269833D01*
X148800Y269958D01*
X148467Y270000D01*
X148050Y269917D01*
X147758Y269708D01*
X147675Y269458D01*
X147717Y269208D01*
X147883Y269000D01*
X148717Y268583D01*
X149092Y268292D01*
X149342Y267875D01*
X149425Y267500D01*
X147675D01*
G01X145533D02*
X145450Y268042D01*
X145325Y268500D01*
X145158Y268917D01*
X144950Y269375D01*
X144617Y270000D01*
X146283D01*
G01X142350Y267500D02*
Y270000D01*
X142850Y269500D01*
G01Y267500D02*
X141850D01*
G01X150972Y261792D02*
X151222Y261917D01*
X151514Y262000D01*
X151847D01*
X152222Y261875D01*
X152514Y261667D01*
X152722Y261417D01*
X152889Y261000D01*
X152931Y260625D01*
X152847Y260250D01*
X152722Y260000D01*
X152472Y259750D01*
X152181Y259583D01*
X151889Y259500D01*
X151597D01*
X151306Y259583D01*
X151056Y259708D01*
X150847Y259875D01*
G01X149581Y261583D02*
X149331Y261833D01*
X149039Y261958D01*
X148706Y262000D01*
X148289Y261917D01*
X147997Y261708D01*
X147914Y261458D01*
X147956Y261208D01*
X148122Y261000D01*
X148956Y260583D01*
X149331Y260292D01*
X149581Y259875D01*
X149664Y259500D01*
X147914D01*
G01X146606Y260000D02*
X146356Y259708D01*
X146022Y259542D01*
X145647Y259500D01*
X145314Y259542D01*
X144981Y259750D01*
X144772Y260000D01*
X144731Y260250D01*
X144814Y260542D01*
X145106Y260750D01*
X145397Y260833D01*
X145772D01*
G01X145397D02*
X145147Y260958D01*
X144939Y261167D01*
X144856Y261417D01*
X144939Y261667D01*
X145147Y261875D01*
X145522Y262000D01*
X145897Y261958D01*
X146272Y261792D01*
G01X143381Y261583D02*
X143131Y261833D01*
X142839Y261958D01*
X142506Y262000D01*
X142089Y261917D01*
X141797Y261708D01*
X141714Y261458D01*
X141756Y261208D01*
X141922Y261000D01*
X142756Y260583D01*
X143131Y260292D01*
X143381Y259875D01*
X143464Y259500D01*
X141714D01*
G01X211083Y298900D02*
Y301400D01*
X210042D01*
X209708Y301275D01*
X209500Y301108D01*
X209417Y300775D01*
X209500Y300442D01*
X209750Y300233D01*
X210042Y300108D01*
X211083D01*
G01X210042D02*
X209417Y298900D01*
G01X207942Y300983D02*
X207692Y301233D01*
X207400Y301358D01*
X207067Y301400D01*
X206650Y301317D01*
X206358Y301108D01*
X206275Y300858D01*
X206317Y300608D01*
X206483Y300400D01*
X207317Y299983D01*
X207692Y299692D01*
X207942Y299275D01*
X208025Y298900D01*
X206275D01*
G01X204133D02*
X204050Y299442D01*
X203925Y299900D01*
X203758Y300317D01*
X203550Y300775D01*
X203217Y301400D01*
X204883D01*
G01X201867Y299400D02*
X201617Y299108D01*
X201283Y298942D01*
X200908Y298900D01*
X200575Y298942D01*
X200242Y299150D01*
X200033Y299400D01*
X199992Y299650D01*
X200075Y299942D01*
X200367Y300150D01*
X200658Y300233D01*
X201033D01*
G01X200658D02*
X200408Y300358D01*
X200200Y300567D01*
X200117Y300817D01*
X200200Y301067D01*
X200408Y301275D01*
X200783Y301400D01*
X201158Y301358D01*
X201533Y301192D01*
G01X153892Y279167D02*
X154017Y278917D01*
X154100Y278625D01*
Y278292D01*
X153975Y277917D01*
X153767Y277625D01*
X153517Y277417D01*
X153100Y277250D01*
X152725Y277208D01*
X152350Y277292D01*
X152100Y277417D01*
X151850Y277667D01*
X151683Y277958D01*
X151600Y278250D01*
Y278542D01*
X151683Y278833D01*
X151808Y279083D01*
X151975Y279292D01*
G01X152100Y280433D02*
X151808Y280683D01*
X151642Y281017D01*
X151600Y281392D01*
X151642Y281725D01*
X151850Y282058D01*
X152100Y282267D01*
X152350Y282308D01*
X152642Y282225D01*
X152850Y281933D01*
X152933Y281642D01*
Y281267D01*
G01Y281642D02*
X153058Y281892D01*
X153267Y282100D01*
X153517Y282183D01*
X153767Y282100D01*
X153975Y281892D01*
X154100Y281517D01*
X154058Y281142D01*
X153892Y280767D01*
G01X151600Y284450D02*
X151642Y284742D01*
X151767Y285075D01*
X151975Y285283D01*
X152267Y285367D01*
X152558Y285283D01*
X152808Y285033D01*
X152933Y284658D01*
Y284242D01*
X153017Y283992D01*
X153225Y283783D01*
X153517Y283700D01*
X153808Y283825D01*
X154017Y284117D01*
X154100Y284450D01*
X154017Y284783D01*
X153808Y285075D01*
X153517Y285200D01*
X153225Y285117D01*
X153017Y284908D01*
X152933Y284658D01*
Y284242D01*
X152808Y283867D01*
X152558Y283617D01*
X152267Y283533D01*
X151975Y283617D01*
X151767Y283825D01*
X151642Y284158D01*
X151600Y284450D01*
G01X153683Y286758D02*
X153933Y287008D01*
X154058Y287300D01*
X154100Y287633D01*
X154017Y288050D01*
X153808Y288342D01*
X153558Y288425D01*
X153308Y288383D01*
X153100Y288217D01*
X152683Y287383D01*
X152392Y287008D01*
X151975Y286758D01*
X151600Y286675D01*
Y288425D01*
G01X149892Y279167D02*
X150017Y278917D01*
X150100Y278625D01*
Y278292D01*
X149975Y277917D01*
X149767Y277625D01*
X149517Y277417D01*
X149100Y277250D01*
X148725Y277208D01*
X148350Y277292D01*
X148100Y277417D01*
X147850Y277667D01*
X147683Y277958D01*
X147600Y278250D01*
Y278542D01*
X147683Y278833D01*
X147808Y279083D01*
X147975Y279292D01*
G01X148100Y280433D02*
X147808Y280683D01*
X147642Y281017D01*
X147600Y281392D01*
X147642Y281725D01*
X147850Y282058D01*
X148100Y282267D01*
X148350Y282308D01*
X148642Y282225D01*
X148850Y281933D01*
X148933Y281642D01*
Y281267D01*
G01Y281642D02*
X149058Y281892D01*
X149267Y282100D01*
X149517Y282183D01*
X149767Y282100D01*
X149975Y281892D01*
X150100Y281517D01*
X150058Y281142D01*
X149892Y280767D01*
G01X147600Y284450D02*
X147642Y284742D01*
X147767Y285075D01*
X147975Y285283D01*
X148267Y285367D01*
X148558Y285283D01*
X148808Y285033D01*
X148933Y284658D01*
Y284242D01*
X149017Y283992D01*
X149225Y283783D01*
X149517Y283700D01*
X149808Y283825D01*
X150017Y284117D01*
X150100Y284450D01*
X150017Y284783D01*
X149808Y285075D01*
X149517Y285200D01*
X149225Y285117D01*
X149017Y284908D01*
X148933Y284658D01*
Y284242D01*
X148808Y283867D01*
X148558Y283617D01*
X148267Y283533D01*
X147975Y283617D01*
X147767Y283825D01*
X147642Y284158D01*
X147600Y284450D01*
G01X150100Y287550D02*
X150017Y287217D01*
X149808Y286967D01*
X149558Y286800D01*
X149225Y286675D01*
X148850Y286633D01*
X148475Y286675D01*
X148142Y286800D01*
X147892Y286967D01*
X147683Y287217D01*
X147600Y287550D01*
X147683Y287883D01*
X147892Y288133D01*
X148142Y288300D01*
X148475Y288425D01*
X148850Y288467D01*
X149225Y288425D01*
X149558Y288300D01*
X149808Y288133D01*
X150017Y287883D01*
X150100Y287550D01*
G01X207523Y284042D02*
X207773Y284167D01*
X208065Y284250D01*
X208398D01*
X208773Y284125D01*
X209065Y283917D01*
X209273Y283667D01*
X209440Y283250D01*
X209482Y282875D01*
X209398Y282500D01*
X209273Y282250D01*
X209023Y282000D01*
X208732Y281833D01*
X208440Y281750D01*
X208148D01*
X207857Y281833D01*
X207607Y281958D01*
X207398Y282125D01*
G01X204840Y281750D02*
Y284250D01*
X206382Y282458D01*
X204298D01*
G01X202240Y281750D02*
X201948Y281792D01*
X201615Y281917D01*
X201407Y282125D01*
X201323Y282417D01*
X201407Y282708D01*
X201657Y282958D01*
X202032Y283083D01*
X202448D01*
X202698Y283167D01*
X202907Y283375D01*
X202990Y283667D01*
X202865Y283958D01*
X202573Y284167D01*
X202240Y284250D01*
X201907Y284167D01*
X201615Y283958D01*
X201490Y283667D01*
X201573Y283375D01*
X201782Y283167D01*
X202032Y283083D01*
X202448D01*
X202823Y282958D01*
X203073Y282708D01*
X203157Y282417D01*
X203073Y282125D01*
X202865Y281917D01*
X202532Y281792D01*
X202240Y281750D01*
G01X199223D02*
X199140Y282292D01*
X199015Y282750D01*
X198848Y283167D01*
X198640Y283625D01*
X198307Y284250D01*
X199973D01*
G01X195023Y284042D02*
X195273Y284167D01*
X195565Y284250D01*
X195898D01*
X196273Y284125D01*
X196565Y283917D01*
X196773Y283667D01*
X196940Y283250D01*
X196982Y282875D01*
X196898Y282500D01*
X196773Y282250D01*
X196523Y282000D01*
X196232Y281833D01*
X195940Y281750D01*
X195648D01*
X195357Y281833D01*
X195107Y281958D01*
X194898Y282125D01*
G01X192340Y281750D02*
Y284250D01*
X193882Y282458D01*
X191798D01*
G01X189740Y281750D02*
X189448Y281792D01*
X189115Y281917D01*
X188907Y282125D01*
X188823Y282417D01*
X188907Y282708D01*
X189157Y282958D01*
X189532Y283083D01*
X189948D01*
X190198Y283167D01*
X190407Y283375D01*
X190490Y283667D01*
X190365Y283958D01*
X190073Y284167D01*
X189740Y284250D01*
X189407Y284167D01*
X189115Y283958D01*
X188990Y283667D01*
X189073Y283375D01*
X189282Y283167D01*
X189532Y283083D01*
X189948D01*
X190323Y282958D01*
X190573Y282708D01*
X190657Y282417D01*
X190573Y282125D01*
X190365Y281917D01*
X190032Y281792D01*
X189740Y281750D01*
G01X187432Y282792D02*
X187140Y283083D01*
X186890Y283250D01*
X186557Y283333D01*
X186265Y283250D01*
X186057Y283083D01*
X185890Y282833D01*
X185848Y282542D01*
X185890Y282292D01*
X186057Y282042D01*
X186307Y281833D01*
X186598Y281750D01*
X186932Y281833D01*
X187223Y282083D01*
X187390Y282458D01*
X187432Y282875D01*
X187348Y283417D01*
X187223Y283708D01*
X187015Y284000D01*
X186723Y284208D01*
X186432Y284250D01*
X186140Y284167D01*
X185932Y283958D01*
G01X181833Y284192D02*
X182083Y284317D01*
X182375Y284400D01*
X182708D01*
X183083Y284275D01*
X183375Y284067D01*
X183583Y283817D01*
X183750Y283400D01*
X183792Y283025D01*
X183708Y282650D01*
X183583Y282400D01*
X183333Y282150D01*
X183042Y281983D01*
X182750Y281900D01*
X182458D01*
X182167Y281983D01*
X181917Y282108D01*
X181708Y282275D01*
G01X179150Y281900D02*
Y284400D01*
X180692Y282608D01*
X178608D01*
G01X176550Y281900D02*
X176258Y281942D01*
X175925Y282067D01*
X175717Y282275D01*
X175633Y282567D01*
X175717Y282858D01*
X175967Y283108D01*
X176342Y283233D01*
X176758D01*
X177008Y283317D01*
X177217Y283525D01*
X177300Y283817D01*
X177175Y284108D01*
X176883Y284317D01*
X176550Y284400D01*
X176217Y284317D01*
X175925Y284108D01*
X175800Y283817D01*
X175883Y283525D01*
X176092Y283317D01*
X176342Y283233D01*
X176758D01*
X177133Y283108D01*
X177383Y282858D01*
X177467Y282567D01*
X177383Y282275D01*
X177175Y282067D01*
X176842Y281942D01*
X176550Y281900D01*
G01X174367Y282275D02*
X174117Y282067D01*
X173825Y281942D01*
X173450Y281900D01*
X173075Y281983D01*
X172783Y282150D01*
X172575Y282442D01*
X172533Y282775D01*
X172617Y283108D01*
X172825Y283317D01*
X173117Y283483D01*
X173408Y283525D01*
X173700Y283483D01*
X174075Y283317D01*
X173950Y284400D01*
X172825D01*
G01X170750Y287900D02*
Y285400D01*
G01X171708Y287900D02*
X169792D01*
G01X168483Y285400D02*
Y287900D01*
X167483D01*
X167150Y287775D01*
X166900Y287483D01*
X166817Y287150D01*
X166900Y286817D01*
X167108Y286567D01*
X167483Y286442D01*
X168483D01*
G01X165467Y285775D02*
X165217Y285567D01*
X164925Y285442D01*
X164550Y285400D01*
X164175Y285483D01*
X163883Y285650D01*
X163675Y285942D01*
X163633Y286275D01*
X163717Y286608D01*
X163925Y286817D01*
X164217Y286983D01*
X164508Y287025D01*
X164800Y286983D01*
X165175Y286817D01*
X165050Y287900D01*
X163925D01*
G01X161450Y285400D02*
X161158Y285442D01*
X160825Y285567D01*
X160617Y285775D01*
X160533Y286067D01*
X160617Y286358D01*
X160867Y286608D01*
X161242Y286733D01*
X161658D01*
X161908Y286817D01*
X162117Y287025D01*
X162200Y287317D01*
X162075Y287608D01*
X161783Y287817D01*
X161450Y287900D01*
X161117Y287817D01*
X160825Y287608D01*
X160700Y287317D01*
X160783Y287025D01*
X160992Y286817D01*
X161242Y286733D01*
X161658D01*
X162033Y286608D01*
X162283Y286358D01*
X162367Y286067D01*
X162283Y285775D01*
X162075Y285567D01*
X161742Y285442D01*
X161450Y285400D01*
G01X199250Y279900D02*
Y277400D01*
G01X200208Y279900D02*
X198292D01*
G01X196983Y277400D02*
Y279900D01*
X195983D01*
X195650Y279775D01*
X195400Y279483D01*
X195317Y279150D01*
X195400Y278817D01*
X195608Y278567D01*
X195983Y278442D01*
X196983D01*
G01X193967Y277775D02*
X193717Y277567D01*
X193425Y277442D01*
X193050Y277400D01*
X192675Y277483D01*
X192383Y277650D01*
X192175Y277942D01*
X192133Y278275D01*
X192217Y278608D01*
X192425Y278817D01*
X192717Y278983D01*
X193008Y279025D01*
X193300Y278983D01*
X193675Y278817D01*
X193550Y279900D01*
X192425D01*
G01X190867Y277775D02*
X190617Y277567D01*
X190325Y277442D01*
X189950Y277400D01*
X189575Y277483D01*
X189283Y277650D01*
X189075Y277942D01*
X189033Y278275D01*
X189117Y278608D01*
X189325Y278817D01*
X189617Y278983D01*
X189908Y279025D01*
X190200Y278983D01*
X190575Y278817D01*
X190450Y279900D01*
X189325D01*
G01X185800Y292900D02*
Y290400D01*
G01X186758Y292900D02*
X184842D01*
G01X183533Y290400D02*
Y292900D01*
X182533D01*
X182200Y292775D01*
X181950Y292483D01*
X181867Y292150D01*
X181950Y291817D01*
X182158Y291567D01*
X182533Y291442D01*
X183533D01*
G01X179600Y290400D02*
Y292900D01*
X180100Y292400D01*
G01Y290400D02*
X179100D01*
G01X176000D02*
Y292900D01*
X177542Y291108D01*
X175458D01*
G01X174108Y290692D02*
X173817Y290483D01*
X173483Y290400D01*
X173150Y290483D01*
X172858Y290733D01*
X172650Y291108D01*
X172567Y291483D01*
Y291942D01*
X172650Y292317D01*
X172858Y292650D01*
X173108Y292817D01*
X173400Y292900D01*
X173733Y292817D01*
X173983Y292650D01*
X174150Y292400D01*
X174233Y292067D01*
X174150Y291775D01*
X173942Y291483D01*
X173692Y291317D01*
X173400Y291275D01*
X173067Y291358D01*
X172817Y291567D01*
X172567Y291942D01*
G01X170300Y292400D02*
Y289900D01*
G01X171258Y292400D02*
X169342D01*
G01X168033Y289900D02*
Y292400D01*
X167033D01*
X166700Y292275D01*
X166450Y291983D01*
X166367Y291650D01*
X166450Y291317D01*
X166658Y291067D01*
X167033Y290942D01*
X168033D01*
G01X164100Y289900D02*
Y292400D01*
X164600Y291900D01*
G01Y289900D02*
X163600D01*
G01X160500D02*
Y292400D01*
X162042Y290608D01*
X159958D01*
G01X157983Y289900D02*
X157900Y290442D01*
X157775Y290900D01*
X157608Y291317D01*
X157400Y291775D01*
X157067Y292400D01*
X158733D01*
G01X212300Y295900D02*
Y293400D01*
G01X213258Y295900D02*
X211342D01*
G01X210033Y293400D02*
Y295900D01*
X209033D01*
X208700Y295775D01*
X208450Y295483D01*
X208367Y295150D01*
X208450Y294817D01*
X208658Y294567D01*
X209033Y294442D01*
X210033D01*
G01X206100Y293400D02*
Y295900D01*
X206600Y295400D01*
G01Y293400D02*
X205600D01*
G01X203917Y293900D02*
X203667Y293608D01*
X203333Y293442D01*
X202958Y293400D01*
X202625Y293442D01*
X202292Y293650D01*
X202083Y293900D01*
X202042Y294150D01*
X202125Y294442D01*
X202417Y294650D01*
X202708Y294733D01*
X203083D01*
G01X202708D02*
X202458Y294858D01*
X202250Y295067D01*
X202167Y295317D01*
X202250Y295567D01*
X202458Y295775D01*
X202833Y295900D01*
X203208Y295858D01*
X203583Y295692D01*
G01X200692Y295483D02*
X200442Y295733D01*
X200150Y295858D01*
X199817Y295900D01*
X199400Y295817D01*
X199108Y295608D01*
X199025Y295358D01*
X199067Y295108D01*
X199233Y294900D01*
X200067Y294483D01*
X200442Y294192D01*
X200692Y293775D01*
X200775Y293400D01*
X199025D01*
G01X194300Y274900D02*
Y272400D01*
G01X195258Y274900D02*
X193342D01*
G01X192033Y272400D02*
Y274900D01*
X191033D01*
X190700Y274775D01*
X190450Y274483D01*
X190367Y274150D01*
X190450Y273817D01*
X190658Y273567D01*
X191033Y273442D01*
X192033D01*
G01X188100Y272400D02*
Y274900D01*
X188600Y274400D01*
G01Y272400D02*
X187600D01*
G01X185000D02*
Y274900D01*
X185500Y274400D01*
G01Y272400D02*
X184500D01*
G01X182692Y273442D02*
X182400Y273733D01*
X182150Y273900D01*
X181817Y273983D01*
X181525Y273900D01*
X181317Y273733D01*
X181150Y273483D01*
X181108Y273192D01*
X181150Y272942D01*
X181317Y272692D01*
X181567Y272483D01*
X181858Y272400D01*
X182192Y272483D01*
X182483Y272733D01*
X182650Y273108D01*
X182692Y273525D01*
X182608Y274067D01*
X182483Y274358D01*
X182275Y274650D01*
X181983Y274858D01*
X181692Y274900D01*
X181400Y274817D01*
X181192Y274608D01*
G01X179333Y336692D02*
X179583Y336817D01*
X179875Y336900D01*
X180208D01*
X180583Y336775D01*
X180875Y336567D01*
X181083Y336317D01*
X181250Y335900D01*
X181292Y335525D01*
X181208Y335150D01*
X181083Y334900D01*
X180833Y334650D01*
X180542Y334483D01*
X180250Y334400D01*
X179958D01*
X179667Y334483D01*
X179417Y334608D01*
X179208Y334775D01*
G01X176650Y334400D02*
Y336900D01*
X178192Y335108D01*
X176108D01*
G01X174050Y334400D02*
Y336900D01*
X174550Y336400D01*
G01Y334400D02*
X173550D01*
G01X171742Y335442D02*
X171450Y335733D01*
X171200Y335900D01*
X170867Y335983D01*
X170575Y335900D01*
X170367Y335733D01*
X170200Y335483D01*
X170158Y335192D01*
X170200Y334942D01*
X170367Y334692D01*
X170617Y334483D01*
X170908Y334400D01*
X171242Y334483D01*
X171533Y334733D01*
X171700Y335108D01*
X171742Y335525D01*
X171658Y336067D01*
X171533Y336358D01*
X171325Y336650D01*
X171033Y336858D01*
X170742Y336900D01*
X170450Y336817D01*
X170242Y336608D01*
G01X191833Y336692D02*
X192083Y336817D01*
X192375Y336900D01*
X192708D01*
X193083Y336775D01*
X193375Y336567D01*
X193583Y336317D01*
X193750Y335900D01*
X193792Y335525D01*
X193708Y335150D01*
X193583Y334900D01*
X193333Y334650D01*
X193042Y334483D01*
X192750Y334400D01*
X192458D01*
X192167Y334483D01*
X191917Y334608D01*
X191708Y334775D01*
G01X189150Y334400D02*
Y336900D01*
X190692Y335108D01*
X188608D01*
G01X186550Y334400D02*
Y336900D01*
X187050Y336400D01*
G01Y334400D02*
X186050D01*
G01X184367Y334775D02*
X184117Y334567D01*
X183825Y334442D01*
X183450Y334400D01*
X183075Y334483D01*
X182783Y334650D01*
X182575Y334942D01*
X182533Y335275D01*
X182617Y335608D01*
X182825Y335817D01*
X183117Y335983D01*
X183408Y336025D01*
X183700Y335983D01*
X184075Y335817D01*
X183950Y336900D01*
X182825D01*
G01X191833Y318692D02*
X192083Y318817D01*
X192375Y318900D01*
X192708D01*
X193083Y318775D01*
X193375Y318567D01*
X193583Y318317D01*
X193750Y317900D01*
X193792Y317525D01*
X193708Y317150D01*
X193583Y316900D01*
X193333Y316650D01*
X193042Y316483D01*
X192750Y316400D01*
X192458D01*
X192167Y316483D01*
X191917Y316608D01*
X191708Y316775D01*
G01X189150Y316400D02*
Y318900D01*
X190692Y317108D01*
X188608D01*
G01X186550Y316400D02*
Y318900D01*
X187050Y318400D01*
G01Y316400D02*
X186050D01*
G01X184367Y316900D02*
X184117Y316608D01*
X183783Y316442D01*
X183408Y316400D01*
X183075Y316442D01*
X182742Y316650D01*
X182533Y316900D01*
X182492Y317150D01*
X182575Y317442D01*
X182867Y317650D01*
X183158Y317733D01*
X183533D01*
G01X183158D02*
X182908Y317858D01*
X182700Y318067D01*
X182617Y318317D01*
X182700Y318567D01*
X182908Y318775D01*
X183283Y318900D01*
X183658Y318858D01*
X184033Y318692D01*
G01X179333Y322692D02*
X179583Y322817D01*
X179875Y322900D01*
X180208D01*
X180583Y322775D01*
X180875Y322567D01*
X181083Y322317D01*
X181250Y321900D01*
X181292Y321525D01*
X181208Y321150D01*
X181083Y320900D01*
X180833Y320650D01*
X180542Y320483D01*
X180250Y320400D01*
X179958D01*
X179667Y320483D01*
X179417Y320608D01*
X179208Y320775D01*
G01X176650Y320400D02*
Y322900D01*
X178192Y321108D01*
X176108D01*
G01X174050Y320400D02*
Y322900D01*
X174550Y322400D01*
G01Y320400D02*
X173550D01*
G01X171742Y322483D02*
X171492Y322733D01*
X171200Y322858D01*
X170867Y322900D01*
X170450Y322817D01*
X170158Y322608D01*
X170075Y322358D01*
X170117Y322108D01*
X170283Y321900D01*
X171117Y321483D01*
X171492Y321192D01*
X171742Y320775D01*
X171825Y320400D01*
X170075D01*
G01X204833Y336692D02*
X205083Y336817D01*
X205375Y336900D01*
X205708D01*
X206083Y336775D01*
X206375Y336567D01*
X206583Y336317D01*
X206750Y335900D01*
X206792Y335525D01*
X206708Y335150D01*
X206583Y334900D01*
X206333Y334650D01*
X206042Y334483D01*
X205750Y334400D01*
X205458D01*
X205167Y334483D01*
X204917Y334608D01*
X204708Y334775D01*
G01X202150Y334400D02*
Y336900D01*
X203692Y335108D01*
X201608D01*
G01X199550Y334400D02*
Y336900D01*
X200050Y336400D01*
G01Y334400D02*
X199050D01*
G01X196450D02*
Y336900D01*
X196950Y336400D01*
G01Y334400D02*
X195950D01*
G01X199523Y362542D02*
X199773Y362667D01*
X200065Y362750D01*
X200398D01*
X200773Y362625D01*
X201065Y362417D01*
X201273Y362167D01*
X201440Y361750D01*
X201482Y361375D01*
X201398Y361000D01*
X201273Y360750D01*
X201023Y360500D01*
X200732Y360333D01*
X200440Y360250D01*
X200148D01*
X199857Y360333D01*
X199607Y360458D01*
X199398Y360625D01*
G01X196840Y360250D02*
Y362750D01*
X198382Y360958D01*
X196298D01*
G01X194948Y360542D02*
X194657Y360333D01*
X194323Y360250D01*
X193990Y360333D01*
X193698Y360583D01*
X193490Y360958D01*
X193407Y361333D01*
Y361792D01*
X193490Y362167D01*
X193698Y362500D01*
X193948Y362667D01*
X194240Y362750D01*
X194573Y362667D01*
X194823Y362500D01*
X194990Y362250D01*
X195073Y361917D01*
X194990Y361625D01*
X194782Y361333D01*
X194532Y361167D01*
X194240Y361125D01*
X193907Y361208D01*
X193657Y361417D01*
X193407Y361792D01*
G01X191932Y362333D02*
X191682Y362583D01*
X191390Y362708D01*
X191057Y362750D01*
X190640Y362667D01*
X190348Y362458D01*
X190265Y362208D01*
X190307Y361958D01*
X190473Y361750D01*
X191307Y361333D01*
X191682Y361042D01*
X191932Y360625D01*
X192015Y360250D01*
X190265D01*
G01X173523Y362542D02*
X173773Y362667D01*
X174065Y362750D01*
X174398D01*
X174773Y362625D01*
X175065Y362417D01*
X175273Y362167D01*
X175440Y361750D01*
X175482Y361375D01*
X175398Y361000D01*
X175273Y360750D01*
X175023Y360500D01*
X174732Y360333D01*
X174440Y360250D01*
X174148D01*
X173857Y360333D01*
X173607Y360458D01*
X173398Y360625D01*
G01X170840Y360250D02*
Y362750D01*
X172382Y360958D01*
X170298D01*
G01X168240Y360250D02*
X167948Y360292D01*
X167615Y360417D01*
X167407Y360625D01*
X167323Y360917D01*
X167407Y361208D01*
X167657Y361458D01*
X168032Y361583D01*
X168448D01*
X168698Y361667D01*
X168907Y361875D01*
X168990Y362167D01*
X168865Y362458D01*
X168573Y362667D01*
X168240Y362750D01*
X167907Y362667D01*
X167615Y362458D01*
X167490Y362167D01*
X167573Y361875D01*
X167782Y361667D01*
X168032Y361583D01*
X168448D01*
X168823Y361458D01*
X169073Y361208D01*
X169157Y360917D01*
X169073Y360625D01*
X168865Y360417D01*
X168532Y360292D01*
X168240Y360250D01*
G01X165140D02*
X164848Y360292D01*
X164515Y360417D01*
X164307Y360625D01*
X164223Y360917D01*
X164307Y361208D01*
X164557Y361458D01*
X164932Y361583D01*
X165348D01*
X165598Y361667D01*
X165807Y361875D01*
X165890Y362167D01*
X165765Y362458D01*
X165473Y362667D01*
X165140Y362750D01*
X164807Y362667D01*
X164515Y362458D01*
X164390Y362167D01*
X164473Y361875D01*
X164682Y361667D01*
X164932Y361583D01*
X165348D01*
X165723Y361458D01*
X165973Y361208D01*
X166057Y360917D01*
X165973Y360625D01*
X165765Y360417D01*
X165432Y360292D01*
X165140Y360250D01*
G01X147892Y347667D02*
X148017Y347417D01*
X148100Y347125D01*
Y346792D01*
X147975Y346417D01*
X147767Y346125D01*
X147517Y345917D01*
X147100Y345750D01*
X146725Y345708D01*
X146350Y345792D01*
X146100Y345917D01*
X145850Y346167D01*
X145683Y346458D01*
X145600Y346750D01*
Y347042D01*
X145683Y347333D01*
X145808Y347583D01*
X145975Y347792D01*
G01X145600Y350350D02*
X148100D01*
X146308Y348808D01*
Y350892D01*
G01X146642Y352158D02*
X146933Y352450D01*
X147100Y352700D01*
X147183Y353033D01*
X147100Y353325D01*
X146933Y353533D01*
X146683Y353700D01*
X146392Y353742D01*
X146142Y353700D01*
X145892Y353533D01*
X145683Y353283D01*
X145600Y352992D01*
X145683Y352658D01*
X145933Y352367D01*
X146308Y352200D01*
X146725Y352158D01*
X147267Y352242D01*
X147558Y352367D01*
X147850Y352575D01*
X148058Y352867D01*
X148100Y353158D01*
X148017Y353450D01*
X147808Y353658D01*
G01X145600Y356550D02*
X148100D01*
X146308Y355008D01*
Y357092D01*
G01X186523Y362542D02*
X186773Y362667D01*
X187065Y362750D01*
X187398D01*
X187773Y362625D01*
X188065Y362417D01*
X188273Y362167D01*
X188440Y361750D01*
X188482Y361375D01*
X188398Y361000D01*
X188273Y360750D01*
X188023Y360500D01*
X187732Y360333D01*
X187440Y360250D01*
X187148D01*
X186857Y360333D01*
X186607Y360458D01*
X186398Y360625D01*
G01X183840Y360250D02*
Y362750D01*
X185382Y360958D01*
X183298D01*
G01X182032Y361292D02*
X181740Y361583D01*
X181490Y361750D01*
X181157Y361833D01*
X180865Y361750D01*
X180657Y361583D01*
X180490Y361333D01*
X180448Y361042D01*
X180490Y360792D01*
X180657Y360542D01*
X180907Y360333D01*
X181198Y360250D01*
X181532Y360333D01*
X181823Y360583D01*
X181990Y360958D01*
X182032Y361375D01*
X181948Y361917D01*
X181823Y362208D01*
X181615Y362500D01*
X181323Y362708D01*
X181032Y362750D01*
X180740Y362667D01*
X180532Y362458D01*
G01X178932Y362333D02*
X178682Y362583D01*
X178390Y362708D01*
X178057Y362750D01*
X177640Y362667D01*
X177348Y362458D01*
X177265Y362208D01*
X177307Y361958D01*
X177473Y361750D01*
X178307Y361333D01*
X178682Y361042D01*
X178932Y360625D01*
X179015Y360250D01*
X177265D01*
G01X161023Y362542D02*
X161273Y362667D01*
X161565Y362750D01*
X161898D01*
X162273Y362625D01*
X162565Y362417D01*
X162773Y362167D01*
X162940Y361750D01*
X162982Y361375D01*
X162898Y361000D01*
X162773Y360750D01*
X162523Y360500D01*
X162232Y360333D01*
X161940Y360250D01*
X161648D01*
X161357Y360333D01*
X161107Y360458D01*
X160898Y360625D01*
G01X158340Y360250D02*
Y362750D01*
X159882Y360958D01*
X157798D01*
G01X156532Y361292D02*
X156240Y361583D01*
X155990Y361750D01*
X155657Y361833D01*
X155365Y361750D01*
X155157Y361583D01*
X154990Y361333D01*
X154948Y361042D01*
X154990Y360792D01*
X155157Y360542D01*
X155407Y360333D01*
X155698Y360250D01*
X156032Y360333D01*
X156323Y360583D01*
X156490Y360958D01*
X156532Y361375D01*
X156448Y361917D01*
X156323Y362208D01*
X156115Y362500D01*
X155823Y362708D01*
X155532Y362750D01*
X155240Y362667D01*
X155032Y362458D01*
G01X152640Y362750D02*
X152973Y362667D01*
X153223Y362458D01*
X153390Y362208D01*
X153515Y361875D01*
X153557Y361500D01*
X153515Y361125D01*
X153390Y360792D01*
X153223Y360542D01*
X152973Y360333D01*
X152640Y360250D01*
X152307Y360333D01*
X152057Y360542D01*
X151890Y360792D01*
X151765Y361125D01*
X151723Y361500D01*
X151765Y361875D01*
X151890Y362208D01*
X152057Y362458D01*
X152307Y362667D01*
X152640Y362750D01*
G01X163333Y330192D02*
X163583Y330317D01*
X163875Y330400D01*
X164208D01*
X164583Y330275D01*
X164875Y330067D01*
X165083Y329817D01*
X165250Y329400D01*
X165292Y329025D01*
X165208Y328650D01*
X165083Y328400D01*
X164833Y328150D01*
X164542Y327983D01*
X164250Y327900D01*
X163958D01*
X163667Y327983D01*
X163417Y328108D01*
X163208Y328275D01*
G01X160650Y327900D02*
Y330400D01*
X162192Y328608D01*
X160108D01*
G01X157550Y327900D02*
Y330400D01*
X159092Y328608D01*
X157008D01*
G01X155867Y328400D02*
X155617Y328108D01*
X155283Y327942D01*
X154908Y327900D01*
X154575Y327942D01*
X154242Y328150D01*
X154033Y328400D01*
X153992Y328650D01*
X154075Y328942D01*
X154367Y329150D01*
X154658Y329233D01*
X155033D01*
G01X154658D02*
X154408Y329358D01*
X154200Y329567D01*
X154117Y329817D01*
X154200Y330067D01*
X154408Y330275D01*
X154783Y330400D01*
X155158Y330358D01*
X155533Y330192D01*
G01X149833Y342692D02*
X150083Y342817D01*
X150375Y342900D01*
X150708D01*
X151083Y342775D01*
X151375Y342567D01*
X151583Y342317D01*
X151750Y341900D01*
X151792Y341525D01*
X151708Y341150D01*
X151583Y340900D01*
X151333Y340650D01*
X151042Y340483D01*
X150750Y340400D01*
X150458D01*
X150167Y340483D01*
X149917Y340608D01*
X149708Y340775D01*
G01X147150Y340400D02*
Y342900D01*
X148692Y341108D01*
X146608D01*
G01X144050Y340400D02*
Y342900D01*
X145592Y341108D01*
X143508D01*
G01X142242Y342483D02*
X141992Y342733D01*
X141700Y342858D01*
X141367Y342900D01*
X140950Y342817D01*
X140658Y342608D01*
X140575Y342358D01*
X140617Y342108D01*
X140783Y341900D01*
X141617Y341483D01*
X141992Y341192D01*
X142242Y340775D01*
X142325Y340400D01*
X140575D01*
G01X204833Y332692D02*
X205083Y332817D01*
X205375Y332900D01*
X205708D01*
X206083Y332775D01*
X206375Y332567D01*
X206583Y332317D01*
X206750Y331900D01*
X206792Y331525D01*
X206708Y331150D01*
X206583Y330900D01*
X206333Y330650D01*
X206042Y330483D01*
X205750Y330400D01*
X205458D01*
X205167Y330483D01*
X204917Y330608D01*
X204708Y330775D01*
G01X202150Y330400D02*
Y332900D01*
X203692Y331108D01*
X201608D01*
G01X199050Y330400D02*
Y332900D01*
X200592Y331108D01*
X198508D01*
G01X196450Y330400D02*
Y332900D01*
X196950Y332400D01*
G01Y330400D02*
X195950D01*
G01X205333Y328692D02*
X205583Y328817D01*
X205875Y328900D01*
X206208D01*
X206583Y328775D01*
X206875Y328567D01*
X207083Y328317D01*
X207250Y327900D01*
X207292Y327525D01*
X207208Y327150D01*
X207083Y326900D01*
X206833Y326650D01*
X206542Y326483D01*
X206250Y326400D01*
X205958D01*
X205667Y326483D01*
X205417Y326608D01*
X205208Y326775D01*
G01X202650Y326400D02*
Y328900D01*
X204192Y327108D01*
X202108D01*
G01X199550Y326400D02*
Y328900D01*
X201092Y327108D01*
X199008D01*
G01X196950Y328900D02*
X197283Y328817D01*
X197533Y328608D01*
X197700Y328358D01*
X197825Y328025D01*
X197867Y327650D01*
X197825Y327275D01*
X197700Y326942D01*
X197533Y326692D01*
X197283Y326483D01*
X196950Y326400D01*
X196617Y326483D01*
X196367Y326692D01*
X196200Y326942D01*
X196075Y327275D01*
X196033Y327650D01*
X196075Y328025D01*
X196200Y328358D01*
X196367Y328608D01*
X196617Y328817D01*
X196950Y328900D01*
G01X204833Y314692D02*
X205083Y314817D01*
X205375Y314900D01*
X205708D01*
X206083Y314775D01*
X206375Y314567D01*
X206583Y314317D01*
X206750Y313900D01*
X206792Y313525D01*
X206708Y313150D01*
X206583Y312900D01*
X206333Y312650D01*
X206042Y312483D01*
X205750Y312400D01*
X205458D01*
X205167Y312483D01*
X204917Y312608D01*
X204708Y312775D01*
G01X202150Y312400D02*
Y314900D01*
X203692Y313108D01*
X201608D01*
G01X200467Y312900D02*
X200217Y312608D01*
X199883Y312442D01*
X199508Y312400D01*
X199175Y312442D01*
X198842Y312650D01*
X198633Y312900D01*
X198592Y313150D01*
X198675Y313442D01*
X198967Y313650D01*
X199258Y313733D01*
X199633D01*
G01X199258D02*
X199008Y313858D01*
X198800Y314067D01*
X198717Y314317D01*
X198800Y314567D01*
X199008Y314775D01*
X199383Y314900D01*
X199758Y314858D01*
X200133Y314692D01*
G01X197158Y312692D02*
X196867Y312483D01*
X196533Y312400D01*
X196200Y312483D01*
X195908Y312733D01*
X195700Y313108D01*
X195617Y313483D01*
Y313942D01*
X195700Y314317D01*
X195908Y314650D01*
X196158Y314817D01*
X196450Y314900D01*
X196783Y314817D01*
X197033Y314650D01*
X197200Y314400D01*
X197283Y314067D01*
X197200Y313775D01*
X196992Y313483D01*
X196742Y313317D01*
X196450Y313275D01*
X196117Y313358D01*
X195867Y313567D01*
X195617Y313942D01*
G01X149333Y338192D02*
X149583Y338317D01*
X149875Y338400D01*
X150208D01*
X150583Y338275D01*
X150875Y338067D01*
X151083Y337817D01*
X151250Y337400D01*
X151292Y337025D01*
X151208Y336650D01*
X151083Y336400D01*
X150833Y336150D01*
X150542Y335983D01*
X150250Y335900D01*
X149958D01*
X149667Y335983D01*
X149417Y336108D01*
X149208Y336275D01*
G01X146650Y335900D02*
Y338400D01*
X148192Y336608D01*
X146108D01*
G01X144967Y336400D02*
X144717Y336108D01*
X144383Y335942D01*
X144008Y335900D01*
X143675Y335942D01*
X143342Y336150D01*
X143133Y336400D01*
X143092Y336650D01*
X143175Y336942D01*
X143467Y337150D01*
X143758Y337233D01*
X144133D01*
G01X143758D02*
X143508Y337358D01*
X143300Y337567D01*
X143217Y337817D01*
X143300Y338067D01*
X143508Y338275D01*
X143883Y338400D01*
X144258Y338358D01*
X144633Y338192D01*
G01X141033Y335900D02*
X140950Y336442D01*
X140825Y336900D01*
X140658Y337317D01*
X140450Y337775D01*
X140117Y338400D01*
X141783D01*
G01X191833Y332692D02*
X192083Y332817D01*
X192375Y332900D01*
X192708D01*
X193083Y332775D01*
X193375Y332567D01*
X193583Y332317D01*
X193750Y331900D01*
X193792Y331525D01*
X193708Y331150D01*
X193583Y330900D01*
X193333Y330650D01*
X193042Y330483D01*
X192750Y330400D01*
X192458D01*
X192167Y330483D01*
X191917Y330608D01*
X191708Y330775D01*
G01X189150Y330400D02*
Y332900D01*
X190692Y331108D01*
X188608D01*
G01X187467Y330900D02*
X187217Y330608D01*
X186883Y330442D01*
X186508Y330400D01*
X186175Y330442D01*
X185842Y330650D01*
X185633Y330900D01*
X185592Y331150D01*
X185675Y331442D01*
X185967Y331650D01*
X186258Y331733D01*
X186633D01*
G01X186258D02*
X186008Y331858D01*
X185800Y332067D01*
X185717Y332317D01*
X185800Y332567D01*
X186008Y332775D01*
X186383Y332900D01*
X186758Y332858D01*
X187133Y332692D01*
G01X184242Y331442D02*
X183950Y331733D01*
X183700Y331900D01*
X183367Y331983D01*
X183075Y331900D01*
X182867Y331733D01*
X182700Y331483D01*
X182658Y331192D01*
X182700Y330942D01*
X182867Y330692D01*
X183117Y330483D01*
X183408Y330400D01*
X183742Y330483D01*
X184033Y330733D01*
X184200Y331108D01*
X184242Y331525D01*
X184158Y332067D01*
X184033Y332358D01*
X183825Y332650D01*
X183533Y332858D01*
X183242Y332900D01*
X182950Y332817D01*
X182742Y332608D01*
G01X192333Y328692D02*
X192583Y328817D01*
X192875Y328900D01*
X193208D01*
X193583Y328775D01*
X193875Y328567D01*
X194083Y328317D01*
X194250Y327900D01*
X194292Y327525D01*
X194208Y327150D01*
X194083Y326900D01*
X193833Y326650D01*
X193542Y326483D01*
X193250Y326400D01*
X192958D01*
X192667Y326483D01*
X192417Y326608D01*
X192208Y326775D01*
G01X189650Y326400D02*
Y328900D01*
X191192Y327108D01*
X189108D01*
G01X187967Y326900D02*
X187717Y326608D01*
X187383Y326442D01*
X187008Y326400D01*
X186675Y326442D01*
X186342Y326650D01*
X186133Y326900D01*
X186092Y327150D01*
X186175Y327442D01*
X186467Y327650D01*
X186758Y327733D01*
X187133D01*
G01X186758D02*
X186508Y327858D01*
X186300Y328067D01*
X186217Y328317D01*
X186300Y328567D01*
X186508Y328775D01*
X186883Y328900D01*
X187258Y328858D01*
X187633Y328692D01*
G01X184867Y326775D02*
X184617Y326567D01*
X184325Y326442D01*
X183950Y326400D01*
X183575Y326483D01*
X183283Y326650D01*
X183075Y326942D01*
X183033Y327275D01*
X183117Y327608D01*
X183325Y327817D01*
X183617Y327983D01*
X183908Y328025D01*
X184200Y327983D01*
X184575Y327817D01*
X184450Y328900D01*
X183325D01*
G01X191833Y314692D02*
X192083Y314817D01*
X192375Y314900D01*
X192708D01*
X193083Y314775D01*
X193375Y314567D01*
X193583Y314317D01*
X193750Y313900D01*
X193792Y313525D01*
X193708Y313150D01*
X193583Y312900D01*
X193333Y312650D01*
X193042Y312483D01*
X192750Y312400D01*
X192458D01*
X192167Y312483D01*
X191917Y312608D01*
X191708Y312775D01*
G01X189150Y312400D02*
Y314900D01*
X190692Y313108D01*
X188608D01*
G01X187467Y312900D02*
X187217Y312608D01*
X186883Y312442D01*
X186508Y312400D01*
X186175Y312442D01*
X185842Y312650D01*
X185633Y312900D01*
X185592Y313150D01*
X185675Y313442D01*
X185967Y313650D01*
X186258Y313733D01*
X186633D01*
G01X186258D02*
X186008Y313858D01*
X185800Y314067D01*
X185717Y314317D01*
X185800Y314567D01*
X186008Y314775D01*
X186383Y314900D01*
X186758Y314858D01*
X187133Y314692D01*
G01X182950Y312400D02*
Y314900D01*
X184492Y313108D01*
X182408D01*
G01X192333Y310692D02*
X192583Y310817D01*
X192875Y310900D01*
X193208D01*
X193583Y310775D01*
X193875Y310567D01*
X194083Y310317D01*
X194250Y309900D01*
X194292Y309525D01*
X194208Y309150D01*
X194083Y308900D01*
X193833Y308650D01*
X193542Y308483D01*
X193250Y308400D01*
X192958D01*
X192667Y308483D01*
X192417Y308608D01*
X192208Y308775D01*
G01X189650Y308400D02*
Y310900D01*
X191192Y309108D01*
X189108D01*
G01X187967Y308900D02*
X187717Y308608D01*
X187383Y308442D01*
X187008Y308400D01*
X186675Y308442D01*
X186342Y308650D01*
X186133Y308900D01*
X186092Y309150D01*
X186175Y309442D01*
X186467Y309650D01*
X186758Y309733D01*
X187133D01*
G01X186758D02*
X186508Y309858D01*
X186300Y310067D01*
X186217Y310317D01*
X186300Y310567D01*
X186508Y310775D01*
X186883Y310900D01*
X187258Y310858D01*
X187633Y310692D01*
G01X184867Y308900D02*
X184617Y308608D01*
X184283Y308442D01*
X183908Y308400D01*
X183575Y308442D01*
X183242Y308650D01*
X183033Y308900D01*
X182992Y309150D01*
X183075Y309442D01*
X183367Y309650D01*
X183658Y309733D01*
X184033D01*
G01X183658D02*
X183408Y309858D01*
X183200Y310067D01*
X183117Y310317D01*
X183200Y310567D01*
X183408Y310775D01*
X183783Y310900D01*
X184158Y310858D01*
X184533Y310692D01*
G01X178833Y340192D02*
X179083Y340317D01*
X179375Y340400D01*
X179708D01*
X180083Y340275D01*
X180375Y340067D01*
X180583Y339817D01*
X180750Y339400D01*
X180792Y339025D01*
X180708Y338650D01*
X180583Y338400D01*
X180333Y338150D01*
X180042Y337983D01*
X179750Y337900D01*
X179458D01*
X179167Y337983D01*
X178917Y338108D01*
X178708Y338275D01*
G01X176150Y337900D02*
Y340400D01*
X177692Y338608D01*
X175608D01*
G01X174467Y338400D02*
X174217Y338108D01*
X173883Y337942D01*
X173508Y337900D01*
X173175Y337942D01*
X172842Y338150D01*
X172633Y338400D01*
X172592Y338650D01*
X172675Y338942D01*
X172967Y339150D01*
X173258Y339233D01*
X173633D01*
G01X173258D02*
X173008Y339358D01*
X172800Y339567D01*
X172717Y339817D01*
X172800Y340067D01*
X173008Y340275D01*
X173383Y340400D01*
X173758Y340358D01*
X174133Y340192D01*
G01X171242Y339983D02*
X170992Y340233D01*
X170700Y340358D01*
X170367Y340400D01*
X169950Y340317D01*
X169658Y340108D01*
X169575Y339858D01*
X169617Y339608D01*
X169783Y339400D01*
X170617Y338983D01*
X170992Y338692D01*
X171242Y338275D01*
X171325Y337900D01*
X169575D01*
G01X179333Y332692D02*
X179583Y332817D01*
X179875Y332900D01*
X180208D01*
X180583Y332775D01*
X180875Y332567D01*
X181083Y332317D01*
X181250Y331900D01*
X181292Y331525D01*
X181208Y331150D01*
X181083Y330900D01*
X180833Y330650D01*
X180542Y330483D01*
X180250Y330400D01*
X179958D01*
X179667Y330483D01*
X179417Y330608D01*
X179208Y330775D01*
G01X176650Y330400D02*
Y332900D01*
X178192Y331108D01*
X176108D01*
G01X174967Y330900D02*
X174717Y330608D01*
X174383Y330442D01*
X174008Y330400D01*
X173675Y330442D01*
X173342Y330650D01*
X173133Y330900D01*
X173092Y331150D01*
X173175Y331442D01*
X173467Y331650D01*
X173758Y331733D01*
X174133D01*
G01X173758D02*
X173508Y331858D01*
X173300Y332067D01*
X173217Y332317D01*
X173300Y332567D01*
X173508Y332775D01*
X173883Y332900D01*
X174258Y332858D01*
X174633Y332692D01*
G01X170950Y330400D02*
Y332900D01*
X171450Y332400D01*
G01Y330400D02*
X170450D01*
G01X179333Y328692D02*
X179583Y328817D01*
X179875Y328900D01*
X180208D01*
X180583Y328775D01*
X180875Y328567D01*
X181083Y328317D01*
X181250Y327900D01*
X181292Y327525D01*
X181208Y327150D01*
X181083Y326900D01*
X180833Y326650D01*
X180542Y326483D01*
X180250Y326400D01*
X179958D01*
X179667Y326483D01*
X179417Y326608D01*
X179208Y326775D01*
G01X176650Y326400D02*
Y328900D01*
X178192Y327108D01*
X176108D01*
G01X174967Y326900D02*
X174717Y326608D01*
X174383Y326442D01*
X174008Y326400D01*
X173675Y326442D01*
X173342Y326650D01*
X173133Y326900D01*
X173092Y327150D01*
X173175Y327442D01*
X173467Y327650D01*
X173758Y327733D01*
X174133D01*
G01X173758D02*
X173508Y327858D01*
X173300Y328067D01*
X173217Y328317D01*
X173300Y328567D01*
X173508Y328775D01*
X173883Y328900D01*
X174258Y328858D01*
X174633Y328692D01*
G01X170950Y328900D02*
X171283Y328817D01*
X171533Y328608D01*
X171700Y328358D01*
X171825Y328025D01*
X171867Y327650D01*
X171825Y327275D01*
X171700Y326942D01*
X171533Y326692D01*
X171283Y326483D01*
X170950Y326400D01*
X170617Y326483D01*
X170367Y326692D01*
X170200Y326942D01*
X170075Y327275D01*
X170033Y327650D01*
X170075Y328025D01*
X170200Y328358D01*
X170367Y328608D01*
X170617Y328817D01*
X170950Y328900D01*
G01X179333Y314692D02*
X179583Y314817D01*
X179875Y314900D01*
X180208D01*
X180583Y314775D01*
X180875Y314567D01*
X181083Y314317D01*
X181250Y313900D01*
X181292Y313525D01*
X181208Y313150D01*
X181083Y312900D01*
X180833Y312650D01*
X180542Y312483D01*
X180250Y312400D01*
X179958D01*
X179667Y312483D01*
X179417Y312608D01*
X179208Y312775D01*
G01X176650Y312400D02*
Y314900D01*
X178192Y313108D01*
X176108D01*
G01X174842Y314483D02*
X174592Y314733D01*
X174300Y314858D01*
X173967Y314900D01*
X173550Y314817D01*
X173258Y314608D01*
X173175Y314358D01*
X173217Y314108D01*
X173383Y313900D01*
X174217Y313483D01*
X174592Y313192D01*
X174842Y312775D01*
X174925Y312400D01*
X173175D01*
G01X171658Y312692D02*
X171367Y312483D01*
X171033Y312400D01*
X170700Y312483D01*
X170408Y312733D01*
X170200Y313108D01*
X170117Y313483D01*
Y313942D01*
X170200Y314317D01*
X170408Y314650D01*
X170658Y314817D01*
X170950Y314900D01*
X171283Y314817D01*
X171533Y314650D01*
X171700Y314400D01*
X171783Y314067D01*
X171700Y313775D01*
X171492Y313483D01*
X171242Y313317D01*
X170950Y313275D01*
X170617Y313358D01*
X170367Y313567D01*
X170117Y313942D01*
G01X179833Y310692D02*
X180083Y310817D01*
X180375Y310900D01*
X180708D01*
X181083Y310775D01*
X181375Y310567D01*
X181583Y310317D01*
X181750Y309900D01*
X181792Y309525D01*
X181708Y309150D01*
X181583Y308900D01*
X181333Y308650D01*
X181042Y308483D01*
X180750Y308400D01*
X180458D01*
X180167Y308483D01*
X179917Y308608D01*
X179708Y308775D01*
G01X177150Y308400D02*
Y310900D01*
X178692Y309108D01*
X176608D01*
G01X175342Y310483D02*
X175092Y310733D01*
X174800Y310858D01*
X174467Y310900D01*
X174050Y310817D01*
X173758Y310608D01*
X173675Y310358D01*
X173717Y310108D01*
X173883Y309900D01*
X174717Y309483D01*
X175092Y309192D01*
X175342Y308775D01*
X175425Y308400D01*
X173675D01*
G01X171450D02*
X171158Y308442D01*
X170825Y308567D01*
X170617Y308775D01*
X170533Y309067D01*
X170617Y309358D01*
X170867Y309608D01*
X171242Y309733D01*
X171658D01*
X171908Y309817D01*
X172117Y310025D01*
X172200Y310317D01*
X172075Y310608D01*
X171783Y310817D01*
X171450Y310900D01*
X171117Y310817D01*
X170825Y310608D01*
X170700Y310317D01*
X170783Y310025D01*
X170992Y309817D01*
X171242Y309733D01*
X171658D01*
X172033Y309608D01*
X172283Y309358D01*
X172367Y309067D01*
X172283Y308775D01*
X172075Y308567D01*
X171742Y308442D01*
X171450Y308400D01*
G01X163333Y338192D02*
X163583Y338317D01*
X163875Y338400D01*
X164208D01*
X164583Y338275D01*
X164875Y338067D01*
X165083Y337817D01*
X165250Y337400D01*
X165292Y337025D01*
X165208Y336650D01*
X165083Y336400D01*
X164833Y336150D01*
X164542Y335983D01*
X164250Y335900D01*
X163958D01*
X163667Y335983D01*
X163417Y336108D01*
X163208Y336275D01*
G01X160650Y335900D02*
Y338400D01*
X162192Y336608D01*
X160108D01*
G01X158842Y337983D02*
X158592Y338233D01*
X158300Y338358D01*
X157967Y338400D01*
X157550Y338317D01*
X157258Y338108D01*
X157175Y337858D01*
X157217Y337608D01*
X157383Y337400D01*
X158217Y336983D01*
X158592Y336692D01*
X158842Y336275D01*
X158925Y335900D01*
X157175D01*
G01X155033D02*
X154950Y336442D01*
X154825Y336900D01*
X154658Y337317D01*
X154450Y337775D01*
X154117Y338400D01*
X155783D01*
G01X163333Y334192D02*
X163583Y334317D01*
X163875Y334400D01*
X164208D01*
X164583Y334275D01*
X164875Y334067D01*
X165083Y333817D01*
X165250Y333400D01*
X165292Y333025D01*
X165208Y332650D01*
X165083Y332400D01*
X164833Y332150D01*
X164542Y331983D01*
X164250Y331900D01*
X163958D01*
X163667Y331983D01*
X163417Y332108D01*
X163208Y332275D01*
G01X160650Y331900D02*
Y334400D01*
X162192Y332608D01*
X160108D01*
G01X158842Y333983D02*
X158592Y334233D01*
X158300Y334358D01*
X157967Y334400D01*
X157550Y334317D01*
X157258Y334108D01*
X157175Y333858D01*
X157217Y333608D01*
X157383Y333400D01*
X158217Y332983D01*
X158592Y332692D01*
X158842Y332275D01*
X158925Y331900D01*
X157175D01*
G01X155867Y332275D02*
X155617Y332067D01*
X155325Y331942D01*
X154950Y331900D01*
X154575Y331983D01*
X154283Y332150D01*
X154075Y332442D01*
X154033Y332775D01*
X154117Y333108D01*
X154325Y333317D01*
X154617Y333483D01*
X154908Y333525D01*
X155200Y333483D01*
X155575Y333317D01*
X155450Y334400D01*
X154325D01*
G01X204833Y322692D02*
X205083Y322817D01*
X205375Y322900D01*
X205708D01*
X206083Y322775D01*
X206375Y322567D01*
X206583Y322317D01*
X206750Y321900D01*
X206792Y321525D01*
X206708Y321150D01*
X206583Y320900D01*
X206333Y320650D01*
X206042Y320483D01*
X205750Y320400D01*
X205458D01*
X205167Y320483D01*
X204917Y320608D01*
X204708Y320775D01*
G01X202150Y320400D02*
Y322900D01*
X203692Y321108D01*
X201608D01*
G01X200342Y322483D02*
X200092Y322733D01*
X199800Y322858D01*
X199467Y322900D01*
X199050Y322817D01*
X198758Y322608D01*
X198675Y322358D01*
X198717Y322108D01*
X198883Y321900D01*
X199717Y321483D01*
X200092Y321192D01*
X200342Y320775D01*
X200425Y320400D01*
X198675D01*
G01X195950D02*
Y322900D01*
X197492Y321108D01*
X195408D01*
G01X178833Y344192D02*
X179083Y344317D01*
X179375Y344400D01*
X179708D01*
X180083Y344275D01*
X180375Y344067D01*
X180583Y343817D01*
X180750Y343400D01*
X180792Y343025D01*
X180708Y342650D01*
X180583Y342400D01*
X180333Y342150D01*
X180042Y341983D01*
X179750Y341900D01*
X179458D01*
X179167Y341983D01*
X178917Y342108D01*
X178708Y342275D01*
G01X176150Y341900D02*
Y344400D01*
X177692Y342608D01*
X175608D01*
G01X174342Y343983D02*
X174092Y344233D01*
X173800Y344358D01*
X173467Y344400D01*
X173050Y344317D01*
X172758Y344108D01*
X172675Y343858D01*
X172717Y343608D01*
X172883Y343400D01*
X173717Y342983D01*
X174092Y342692D01*
X174342Y342275D01*
X174425Y341900D01*
X172675D01*
G01X171242Y343983D02*
X170992Y344233D01*
X170700Y344358D01*
X170367Y344400D01*
X169950Y344317D01*
X169658Y344108D01*
X169575Y343858D01*
X169617Y343608D01*
X169783Y343400D01*
X170617Y342983D01*
X170992Y342692D01*
X171242Y342275D01*
X171325Y341900D01*
X169575D01*
G01X191833Y322692D02*
X192083Y322817D01*
X192375Y322900D01*
X192708D01*
X193083Y322775D01*
X193375Y322567D01*
X193583Y322317D01*
X193750Y321900D01*
X193792Y321525D01*
X193708Y321150D01*
X193583Y320900D01*
X193333Y320650D01*
X193042Y320483D01*
X192750Y320400D01*
X192458D01*
X192167Y320483D01*
X191917Y320608D01*
X191708Y320775D01*
G01X189150Y320400D02*
Y322900D01*
X190692Y321108D01*
X188608D01*
G01X187342Y322483D02*
X187092Y322733D01*
X186800Y322858D01*
X186467Y322900D01*
X186050Y322817D01*
X185758Y322608D01*
X185675Y322358D01*
X185717Y322108D01*
X185883Y321900D01*
X186717Y321483D01*
X187092Y321192D01*
X187342Y320775D01*
X187425Y320400D01*
X185675D01*
G01X183450D02*
Y322900D01*
X183950Y322400D01*
G01Y320400D02*
X182950D01*
G01X204833Y318692D02*
X205083Y318817D01*
X205375Y318900D01*
X205708D01*
X206083Y318775D01*
X206375Y318567D01*
X206583Y318317D01*
X206750Y317900D01*
X206792Y317525D01*
X206708Y317150D01*
X206583Y316900D01*
X206333Y316650D01*
X206042Y316483D01*
X205750Y316400D01*
X205458D01*
X205167Y316483D01*
X204917Y316608D01*
X204708Y316775D01*
G01X202150Y316400D02*
Y318900D01*
X203692Y317108D01*
X201608D01*
G01X200342Y318483D02*
X200092Y318733D01*
X199800Y318858D01*
X199467Y318900D01*
X199050Y318817D01*
X198758Y318608D01*
X198675Y318358D01*
X198717Y318108D01*
X198883Y317900D01*
X199717Y317483D01*
X200092Y317192D01*
X200342Y316775D01*
X200425Y316400D01*
X198675D01*
G01X196450Y318900D02*
X196783Y318817D01*
X197033Y318608D01*
X197200Y318358D01*
X197325Y318025D01*
X197367Y317650D01*
X197325Y317275D01*
X197200Y316942D01*
X197033Y316692D01*
X196783Y316483D01*
X196450Y316400D01*
X196117Y316483D01*
X195867Y316692D01*
X195700Y316942D01*
X195575Y317275D01*
X195533Y317650D01*
X195575Y318025D01*
X195700Y318358D01*
X195867Y318608D01*
X196117Y318817D01*
X196450Y318900D01*
G01X163333Y342692D02*
X163583Y342817D01*
X163875Y342900D01*
X164208D01*
X164583Y342775D01*
X164875Y342567D01*
X165083Y342317D01*
X165250Y341900D01*
X165292Y341525D01*
X165208Y341150D01*
X165083Y340900D01*
X164833Y340650D01*
X164542Y340483D01*
X164250Y340400D01*
X163958D01*
X163667Y340483D01*
X163417Y340608D01*
X163208Y340775D01*
G01X160650Y340400D02*
Y342900D01*
X162192Y341108D01*
X160108D01*
G01X158050Y340400D02*
Y342900D01*
X158550Y342400D01*
G01Y340400D02*
X157550D01*
G01X154950D02*
X154658Y340442D01*
X154325Y340567D01*
X154117Y340775D01*
X154033Y341067D01*
X154117Y341358D01*
X154367Y341608D01*
X154742Y341733D01*
X155158D01*
X155408Y341817D01*
X155617Y342025D01*
X155700Y342317D01*
X155575Y342608D01*
X155283Y342817D01*
X154950Y342900D01*
X154617Y342817D01*
X154325Y342608D01*
X154200Y342317D01*
X154283Y342025D01*
X154492Y341817D01*
X154742Y341733D01*
X155158D01*
X155533Y341608D01*
X155783Y341358D01*
X155867Y341067D01*
X155783Y340775D01*
X155575Y340567D01*
X155242Y340442D01*
X154950Y340400D01*
G01X179333Y318692D02*
X179583Y318817D01*
X179875Y318900D01*
X180208D01*
X180583Y318775D01*
X180875Y318567D01*
X181083Y318317D01*
X181250Y317900D01*
X181292Y317525D01*
X181208Y317150D01*
X181083Y316900D01*
X180833Y316650D01*
X180542Y316483D01*
X180250Y316400D01*
X179958D01*
X179667Y316483D01*
X179417Y316608D01*
X179208Y316775D01*
G01X176650Y316400D02*
Y318900D01*
X178192Y317108D01*
X176108D01*
G01X174050Y316400D02*
Y318900D01*
X174550Y318400D01*
G01Y316400D02*
X173550D01*
G01X171033D02*
X170950Y316942D01*
X170825Y317400D01*
X170658Y317817D01*
X170450Y318275D01*
X170117Y318900D01*
X171783D01*
G01X204833Y310692D02*
X205083Y310817D01*
X205375Y310900D01*
X205708D01*
X206083Y310775D01*
X206375Y310567D01*
X206583Y310317D01*
X206750Y309900D01*
X206792Y309525D01*
X206708Y309150D01*
X206583Y308900D01*
X206333Y308650D01*
X206042Y308483D01*
X205750Y308400D01*
X205458D01*
X205167Y308483D01*
X204917Y308608D01*
X204708Y308775D01*
G01X202150Y308400D02*
Y310900D01*
X203692Y309108D01*
X201608D01*
G01X200467Y308775D02*
X200217Y308567D01*
X199925Y308442D01*
X199550Y308400D01*
X199175Y308483D01*
X198883Y308650D01*
X198675Y308942D01*
X198633Y309275D01*
X198717Y309608D01*
X198925Y309817D01*
X199217Y309983D01*
X199508Y310025D01*
X199800Y309983D01*
X200175Y309817D01*
X200050Y310900D01*
X198925D01*
G01X196450Y308400D02*
Y310900D01*
X196950Y310400D01*
G01Y308400D02*
X195950D01*
G01X191833Y343192D02*
X192083Y343317D01*
X192375Y343400D01*
X192708D01*
X193083Y343275D01*
X193375Y343067D01*
X193583Y342817D01*
X193750Y342400D01*
X193792Y342025D01*
X193708Y341650D01*
X193583Y341400D01*
X193333Y341150D01*
X193042Y340983D01*
X192750Y340900D01*
X192458D01*
X192167Y340983D01*
X191917Y341108D01*
X191708Y341275D01*
G01X189150Y340900D02*
Y343400D01*
X190692Y341608D01*
X188608D01*
G01X187467Y341275D02*
X187217Y341067D01*
X186925Y340942D01*
X186550Y340900D01*
X186175Y340983D01*
X185883Y341150D01*
X185675Y341442D01*
X185633Y341775D01*
X185717Y342108D01*
X185925Y342317D01*
X186217Y342483D01*
X186508Y342525D01*
X186800Y342483D01*
X187175Y342317D01*
X187050Y343400D01*
X185925D01*
G01X183450D02*
X183783Y343317D01*
X184033Y343108D01*
X184200Y342858D01*
X184325Y342525D01*
X184367Y342150D01*
X184325Y341775D01*
X184200Y341442D01*
X184033Y341192D01*
X183783Y340983D01*
X183450Y340900D01*
X183117Y340983D01*
X182867Y341192D01*
X182700Y341442D01*
X182575Y341775D01*
X182533Y342150D01*
X182575Y342525D01*
X182700Y342858D01*
X182867Y343108D01*
X183117Y343317D01*
X183450Y343400D01*
G01X204833Y343192D02*
X205083Y343317D01*
X205375Y343400D01*
X205708D01*
X206083Y343275D01*
X206375Y343067D01*
X206583Y342817D01*
X206750Y342400D01*
X206792Y342025D01*
X206708Y341650D01*
X206583Y341400D01*
X206333Y341150D01*
X206042Y340983D01*
X205750Y340900D01*
X205458D01*
X205167Y340983D01*
X204917Y341108D01*
X204708Y341275D01*
G01X202150Y340900D02*
Y343400D01*
X203692Y341608D01*
X201608D01*
G01X199050Y340900D02*
Y343400D01*
X200592Y341608D01*
X198508D01*
G01X197158Y341192D02*
X196867Y340983D01*
X196533Y340900D01*
X196200Y340983D01*
X195908Y341233D01*
X195700Y341608D01*
X195617Y341983D01*
Y342442D01*
X195700Y342817D01*
X195908Y343150D01*
X196158Y343317D01*
X196450Y343400D01*
X196783Y343317D01*
X197033Y343150D01*
X197200Y342900D01*
X197283Y342567D01*
X197200Y342275D01*
X196992Y341983D01*
X196742Y341817D01*
X196450Y341775D01*
X196117Y341858D01*
X195867Y342067D01*
X195617Y342442D01*
G01X149333Y318192D02*
X149583Y318317D01*
X149875Y318400D01*
X150208D01*
X150583Y318275D01*
X150875Y318067D01*
X151083Y317817D01*
X151250Y317400D01*
X151292Y317025D01*
X151208Y316650D01*
X151083Y316400D01*
X150833Y316150D01*
X150542Y315983D01*
X150250Y315900D01*
X149958D01*
X149667Y315983D01*
X149417Y316108D01*
X149208Y316275D01*
G01X146650Y315900D02*
Y318400D01*
X148192Y316608D01*
X146108D01*
G01X143550Y315900D02*
Y318400D01*
X145092Y316608D01*
X143008D01*
G01X140950Y315900D02*
X140658Y315942D01*
X140325Y316067D01*
X140117Y316275D01*
X140033Y316567D01*
X140117Y316858D01*
X140367Y317108D01*
X140742Y317233D01*
X141158D01*
X141408Y317317D01*
X141617Y317525D01*
X141700Y317817D01*
X141575Y318108D01*
X141283Y318317D01*
X140950Y318400D01*
X140617Y318317D01*
X140325Y318108D01*
X140200Y317817D01*
X140283Y317525D01*
X140492Y317317D01*
X140742Y317233D01*
X141158D01*
X141533Y317108D01*
X141783Y316858D01*
X141867Y316567D01*
X141783Y316275D01*
X141575Y316067D01*
X141242Y315942D01*
X140950Y315900D01*
G01X149333Y323192D02*
X149583Y323317D01*
X149875Y323400D01*
X150208D01*
X150583Y323275D01*
X150875Y323067D01*
X151083Y322817D01*
X151250Y322400D01*
X151292Y322025D01*
X151208Y321650D01*
X151083Y321400D01*
X150833Y321150D01*
X150542Y320983D01*
X150250Y320900D01*
X149958D01*
X149667Y320983D01*
X149417Y321108D01*
X149208Y321275D01*
G01X146650Y320900D02*
Y323400D01*
X148192Y321608D01*
X146108D01*
G01X143550Y320900D02*
Y323400D01*
X145092Y321608D01*
X143008D01*
G01X141033Y320900D02*
X140950Y321442D01*
X140825Y321900D01*
X140658Y322317D01*
X140450Y322775D01*
X140117Y323400D01*
X141783D01*
G01X163833Y311692D02*
X164083Y311817D01*
X164375Y311900D01*
X164708D01*
X165083Y311775D01*
X165375Y311567D01*
X165583Y311317D01*
X165750Y310900D01*
X165792Y310525D01*
X165708Y310150D01*
X165583Y309900D01*
X165333Y309650D01*
X165042Y309483D01*
X164750Y309400D01*
X164458D01*
X164167Y309483D01*
X163917Y309608D01*
X163708Y309775D01*
G01X161150Y309400D02*
Y311900D01*
X162692Y310108D01*
X160608D01*
G01X158050Y309400D02*
Y311900D01*
X159592Y310108D01*
X157508D01*
G01X156242Y310442D02*
X155950Y310733D01*
X155700Y310900D01*
X155367Y310983D01*
X155075Y310900D01*
X154867Y310733D01*
X154700Y310483D01*
X154658Y310192D01*
X154700Y309942D01*
X154867Y309692D01*
X155117Y309483D01*
X155408Y309400D01*
X155742Y309483D01*
X156033Y309733D01*
X156200Y310108D01*
X156242Y310525D01*
X156158Y311067D01*
X156033Y311358D01*
X155825Y311650D01*
X155533Y311858D01*
X155242Y311900D01*
X154950Y311817D01*
X154742Y311608D01*
G01X163333Y318192D02*
X163583Y318317D01*
X163875Y318400D01*
X164208D01*
X164583Y318275D01*
X164875Y318067D01*
X165083Y317817D01*
X165250Y317400D01*
X165292Y317025D01*
X165208Y316650D01*
X165083Y316400D01*
X164833Y316150D01*
X164542Y315983D01*
X164250Y315900D01*
X163958D01*
X163667Y315983D01*
X163417Y316108D01*
X163208Y316275D01*
G01X160650Y315900D02*
Y318400D01*
X162192Y316608D01*
X160108D01*
G01X157550Y315900D02*
Y318400D01*
X159092Y316608D01*
X157008D01*
G01X155867Y316275D02*
X155617Y316067D01*
X155325Y315942D01*
X154950Y315900D01*
X154575Y315983D01*
X154283Y316150D01*
X154075Y316442D01*
X154033Y316775D01*
X154117Y317108D01*
X154325Y317317D01*
X154617Y317483D01*
X154908Y317525D01*
X155200Y317483D01*
X155575Y317317D01*
X155450Y318400D01*
X154325D01*
G01X162833Y325192D02*
X163083Y325317D01*
X163375Y325400D01*
X163708D01*
X164083Y325275D01*
X164375Y325067D01*
X164583Y324817D01*
X164750Y324400D01*
X164792Y324025D01*
X164708Y323650D01*
X164583Y323400D01*
X164333Y323150D01*
X164042Y322983D01*
X163750Y322900D01*
X163458D01*
X163167Y322983D01*
X162917Y323108D01*
X162708Y323275D01*
G01X160150Y322900D02*
Y325400D01*
X161692Y323608D01*
X159608D01*
G01X157050Y322900D02*
Y325400D01*
X158592Y323608D01*
X156508D01*
G01X153950Y322900D02*
Y325400D01*
X155492Y323608D01*
X153408D01*
G01X159333Y350692D02*
X159583Y350817D01*
X159875Y350900D01*
X160208D01*
X160583Y350775D01*
X160875Y350567D01*
X161083Y350317D01*
X161250Y349900D01*
X161292Y349525D01*
X161208Y349150D01*
X161083Y348900D01*
X160833Y348650D01*
X160542Y348483D01*
X160250Y348400D01*
X159958D01*
X159667Y348483D01*
X159417Y348608D01*
X159208Y348775D01*
G01X156650Y348400D02*
Y350900D01*
X158192Y349108D01*
X156108D01*
G01X154050Y348400D02*
Y350900D01*
X154550Y350400D01*
G01Y348400D02*
X153550D01*
G01X150950Y350900D02*
X151283Y350817D01*
X151533Y350608D01*
X151700Y350358D01*
X151825Y350025D01*
X151867Y349650D01*
X151825Y349275D01*
X151700Y348942D01*
X151533Y348692D01*
X151283Y348483D01*
X150950Y348400D01*
X150617Y348483D01*
X150367Y348692D01*
X150200Y348942D01*
X150075Y349275D01*
X150033Y349650D01*
X150075Y350025D01*
X150200Y350358D01*
X150367Y350608D01*
X150617Y350817D01*
X150950Y350900D01*
G01X179392Y348167D02*
X179517Y347917D01*
X179600Y347625D01*
Y347292D01*
X179475Y346917D01*
X179267Y346625D01*
X179017Y346417D01*
X178600Y346250D01*
X178225Y346208D01*
X177850Y346292D01*
X177600Y346417D01*
X177350Y346667D01*
X177183Y346958D01*
X177100Y347250D01*
Y347542D01*
X177183Y347833D01*
X177308Y348083D01*
X177475Y348292D01*
G01X177100Y350850D02*
X179600D01*
X177808Y349308D01*
Y351392D01*
G01X179600Y353450D02*
X179517Y353117D01*
X179308Y352867D01*
X179058Y352700D01*
X178725Y352575D01*
X178350Y352533D01*
X177975Y352575D01*
X177642Y352700D01*
X177392Y352867D01*
X177183Y353117D01*
X177100Y353450D01*
X177183Y353783D01*
X177392Y354033D01*
X177642Y354200D01*
X177975Y354325D01*
X178350Y354367D01*
X178725Y354325D01*
X179058Y354200D01*
X179308Y354033D01*
X179517Y353783D01*
X179600Y353450D01*
G01X177100Y356550D02*
X177142Y356842D01*
X177267Y357175D01*
X177475Y357383D01*
X177767Y357467D01*
X178058Y357383D01*
X178308Y357133D01*
X178433Y356758D01*
Y356342D01*
X178517Y356092D01*
X178725Y355883D01*
X179017Y355800D01*
X179308Y355925D01*
X179517Y356217D01*
X179600Y356550D01*
X179517Y356883D01*
X179308Y357175D01*
X179017Y357300D01*
X178725Y357217D01*
X178517Y357008D01*
X178433Y356758D01*
Y356342D01*
X178308Y355967D01*
X178058Y355717D01*
X177767Y355633D01*
X177475Y355717D01*
X177267Y355925D01*
X177142Y356258D01*
X177100Y356550D01*
G01X188392Y348167D02*
X188517Y347917D01*
X188600Y347625D01*
Y347292D01*
X188475Y346917D01*
X188267Y346625D01*
X188017Y346417D01*
X187600Y346250D01*
X187225Y346208D01*
X186850Y346292D01*
X186600Y346417D01*
X186350Y346667D01*
X186183Y346958D01*
X186100Y347250D01*
Y347542D01*
X186183Y347833D01*
X186308Y348083D01*
X186475Y348292D01*
G01X186100Y350850D02*
X188600D01*
X186808Y349308D01*
Y351392D01*
G01X188600Y353450D02*
X188517Y353117D01*
X188308Y352867D01*
X188058Y352700D01*
X187725Y352575D01*
X187350Y352533D01*
X186975Y352575D01*
X186642Y352700D01*
X186392Y352867D01*
X186183Y353117D01*
X186100Y353450D01*
X186183Y353783D01*
X186392Y354033D01*
X186642Y354200D01*
X186975Y354325D01*
X187350Y354367D01*
X187725Y354325D01*
X188058Y354200D01*
X188308Y354033D01*
X188517Y353783D01*
X188600Y353450D01*
G01X186100Y356467D02*
X186642Y356550D01*
X187100Y356675D01*
X187517Y356842D01*
X187975Y357050D01*
X188600Y357383D01*
Y355717D01*
G01X159068Y355043D02*
X159318Y355168D01*
X159610Y355251D01*
X159943D01*
X160318Y355126D01*
X160610Y354918D01*
X160818Y354668D01*
X160985Y354251D01*
X161027Y353876D01*
X160943Y353501D01*
X160818Y353251D01*
X160568Y353001D01*
X160277Y352834D01*
X159985Y352751D01*
X159693D01*
X159402Y352834D01*
X159152Y352959D01*
X158943Y353126D01*
G01X156385Y352751D02*
Y355251D01*
X157927Y353459D01*
X155843D01*
G01X153785Y355251D02*
X154118Y355168D01*
X154368Y354959D01*
X154535Y354709D01*
X154660Y354376D01*
X154702Y354001D01*
X154660Y353626D01*
X154535Y353293D01*
X154368Y353043D01*
X154118Y352834D01*
X153785Y352751D01*
X153452Y352834D01*
X153202Y353043D01*
X153035Y353293D01*
X152910Y353626D01*
X152868Y354001D01*
X152910Y354376D01*
X153035Y354709D01*
X153202Y354959D01*
X153452Y355168D01*
X153785Y355251D01*
G01X151477Y353793D02*
X151185Y354084D01*
X150935Y354251D01*
X150602Y354334D01*
X150310Y354251D01*
X150102Y354084D01*
X149935Y353834D01*
X149893Y353543D01*
X149935Y353293D01*
X150102Y353043D01*
X150352Y352834D01*
X150643Y352751D01*
X150977Y352834D01*
X151268Y353084D01*
X151435Y353459D01*
X151477Y353876D01*
X151393Y354418D01*
X151268Y354709D01*
X151060Y355001D01*
X150768Y355209D01*
X150477Y355251D01*
X150185Y355168D01*
X149977Y354959D01*
G01X183892Y348167D02*
X184017Y347917D01*
X184100Y347625D01*
Y347292D01*
X183975Y346917D01*
X183767Y346625D01*
X183517Y346417D01*
X183100Y346250D01*
X182725Y346208D01*
X182350Y346292D01*
X182100Y346417D01*
X181850Y346667D01*
X181683Y346958D01*
X181600Y347250D01*
Y347542D01*
X181683Y347833D01*
X181808Y348083D01*
X181975Y348292D01*
G01X181600Y350850D02*
X184100D01*
X182308Y349308D01*
Y351392D01*
G01X184100Y353450D02*
X184017Y353117D01*
X183808Y352867D01*
X183558Y352700D01*
X183225Y352575D01*
X182850Y352533D01*
X182475Y352575D01*
X182142Y352700D01*
X181892Y352867D01*
X181683Y353117D01*
X181600Y353450D01*
X181683Y353783D01*
X181892Y354033D01*
X182142Y354200D01*
X182475Y354325D01*
X182850Y354367D01*
X183225Y354325D01*
X183558Y354200D01*
X183808Y354033D01*
X184017Y353783D01*
X184100Y353450D01*
G01X181975Y355633D02*
X181767Y355883D01*
X181642Y356175D01*
X181600Y356550D01*
X181683Y356925D01*
X181850Y357217D01*
X182142Y357425D01*
X182475Y357467D01*
X182808Y357383D01*
X183017Y357175D01*
X183183Y356883D01*
X183225Y356592D01*
X183183Y356300D01*
X183017Y355925D01*
X184100Y356050D01*
Y357175D01*
G01X206300Y347900D02*
Y345400D01*
G01X207258Y347900D02*
X205342D01*
G01X204033Y345400D02*
Y347900D01*
X203033D01*
X202700Y347775D01*
X202450Y347483D01*
X202367Y347150D01*
X202450Y346817D01*
X202658Y346567D01*
X203033Y346442D01*
X204033D01*
G01X200100Y345400D02*
Y347900D01*
X200600Y347400D01*
G01Y345400D02*
X199600D01*
G01X197917Y345775D02*
X197667Y345567D01*
X197375Y345442D01*
X197000Y345400D01*
X196625Y345483D01*
X196333Y345650D01*
X196125Y345942D01*
X196083Y346275D01*
X196167Y346608D01*
X196375Y346817D01*
X196667Y346983D01*
X196958Y347025D01*
X197250Y346983D01*
X197625Y346817D01*
X197500Y347900D01*
X196375D01*
G01X193900D02*
X194233Y347817D01*
X194483Y347608D01*
X194650Y347358D01*
X194775Y347025D01*
X194817Y346650D01*
X194775Y346275D01*
X194650Y345942D01*
X194483Y345692D01*
X194233Y345483D01*
X193900Y345400D01*
X193567Y345483D01*
X193317Y345692D01*
X193150Y345942D01*
X193025Y346275D01*
X192983Y346650D01*
X193025Y347025D01*
X193150Y347358D01*
X193317Y347608D01*
X193567Y347817D01*
X193900Y347900D01*
G01X150833Y367192D02*
X151083Y367317D01*
X151375Y367400D01*
X151708D01*
X152083Y367275D01*
X152375Y367067D01*
X152583Y366817D01*
X152750Y366400D01*
X152792Y366025D01*
X152708Y365650D01*
X152583Y365400D01*
X152333Y365150D01*
X152042Y364983D01*
X151750Y364900D01*
X151458D01*
X151167Y364983D01*
X150917Y365108D01*
X150708Y365275D01*
G01X148150Y364900D02*
Y367400D01*
X149692Y365608D01*
X147608D01*
G01X146342Y365942D02*
X146050Y366233D01*
X145800Y366400D01*
X145467Y366483D01*
X145175Y366400D01*
X144967Y366233D01*
X144800Y365983D01*
X144758Y365692D01*
X144800Y365442D01*
X144967Y365192D01*
X145217Y364983D01*
X145508Y364900D01*
X145842Y364983D01*
X146133Y365233D01*
X146300Y365608D01*
X146342Y366025D01*
X146258Y366567D01*
X146133Y366858D01*
X145925Y367150D01*
X145633Y367358D01*
X145342Y367400D01*
X145050Y367317D01*
X144842Y367108D01*
G01X143242Y365942D02*
X142950Y366233D01*
X142700Y366400D01*
X142367Y366483D01*
X142075Y366400D01*
X141867Y366233D01*
X141700Y365983D01*
X141658Y365692D01*
X141700Y365442D01*
X141867Y365192D01*
X142117Y364983D01*
X142408Y364900D01*
X142742Y364983D01*
X143033Y365233D01*
X143200Y365608D01*
X143242Y366025D01*
X143158Y366567D01*
X143033Y366858D01*
X142825Y367150D01*
X142533Y367358D01*
X142242Y367400D01*
X141950Y367317D01*
X141742Y367108D01*
G01X190833Y366692D02*
X191083Y366817D01*
X191375Y366900D01*
X191708D01*
X192083Y366775D01*
X192375Y366567D01*
X192583Y366317D01*
X192750Y365900D01*
X192792Y365525D01*
X192708Y365150D01*
X192583Y364900D01*
X192333Y364650D01*
X192042Y364483D01*
X191750Y364400D01*
X191458D01*
X191167Y364483D01*
X190917Y364608D01*
X190708Y364775D01*
G01X188150Y364400D02*
Y366900D01*
X189692Y365108D01*
X187608D01*
G01X186258Y364692D02*
X185967Y364483D01*
X185633Y364400D01*
X185300Y364483D01*
X185008Y364733D01*
X184800Y365108D01*
X184717Y365483D01*
Y365942D01*
X184800Y366317D01*
X185008Y366650D01*
X185258Y366817D01*
X185550Y366900D01*
X185883Y366817D01*
X186133Y366650D01*
X186300Y366400D01*
X186383Y366067D01*
X186300Y365775D01*
X186092Y365483D01*
X185842Y365317D01*
X185550Y365275D01*
X185217Y365358D01*
X184967Y365567D01*
X184717Y365942D01*
G01X182450Y364400D02*
X182158Y364442D01*
X181825Y364567D01*
X181617Y364775D01*
X181533Y365067D01*
X181617Y365358D01*
X181867Y365608D01*
X182242Y365733D01*
X182658D01*
X182908Y365817D01*
X183117Y366025D01*
X183200Y366317D01*
X183075Y366608D01*
X182783Y366817D01*
X182450Y366900D01*
X182117Y366817D01*
X181825Y366608D01*
X181700Y366317D01*
X181783Y366025D01*
X181992Y365817D01*
X182242Y365733D01*
X182658D01*
X183033Y365608D01*
X183283Y365358D01*
X183367Y365067D01*
X183283Y364775D01*
X183075Y364567D01*
X182742Y364442D01*
X182450Y364400D01*
G01X177833Y367192D02*
X178083Y367317D01*
X178375Y367400D01*
X178708D01*
X179083Y367275D01*
X179375Y367067D01*
X179583Y366817D01*
X179750Y366400D01*
X179792Y366025D01*
X179708Y365650D01*
X179583Y365400D01*
X179333Y365150D01*
X179042Y364983D01*
X178750Y364900D01*
X178458D01*
X178167Y364983D01*
X177917Y365108D01*
X177708Y365275D01*
G01X175150Y364900D02*
Y367400D01*
X176692Y365608D01*
X174608D01*
G01X173258Y365192D02*
X172967Y364983D01*
X172633Y364900D01*
X172300Y364983D01*
X172008Y365233D01*
X171800Y365608D01*
X171717Y365983D01*
Y366442D01*
X171800Y366817D01*
X172008Y367150D01*
X172258Y367317D01*
X172550Y367400D01*
X172883Y367317D01*
X173133Y367150D01*
X173300Y366900D01*
X173383Y366567D01*
X173300Y366275D01*
X173092Y365983D01*
X172842Y365817D01*
X172550Y365775D01*
X172217Y365858D01*
X171967Y366067D01*
X171717Y366442D01*
G01X169533Y364900D02*
X169450Y365442D01*
X169325Y365900D01*
X169158Y366317D01*
X168950Y366775D01*
X168617Y367400D01*
X170283D01*
G01X190733Y426292D02*
X190983Y426417D01*
X191275Y426500D01*
X191608D01*
X191983Y426375D01*
X192275Y426167D01*
X192483Y425917D01*
X192650Y425500D01*
X192692Y425125D01*
X192608Y424750D01*
X192483Y424500D01*
X192233Y424250D01*
X191942Y424083D01*
X191650Y424000D01*
X191358D01*
X191067Y424083D01*
X190817Y424208D01*
X190608Y424375D01*
G01X189467Y424500D02*
X189217Y424208D01*
X188883Y424042D01*
X188508Y424000D01*
X188175Y424042D01*
X187842Y424250D01*
X187633Y424500D01*
X187592Y424750D01*
X187675Y425042D01*
X187967Y425250D01*
X188258Y425333D01*
X188633D01*
G01X188258D02*
X188008Y425458D01*
X187800Y425667D01*
X187717Y425917D01*
X187800Y426167D01*
X188008Y426375D01*
X188383Y426500D01*
X188758Y426458D01*
X189133Y426292D01*
G01X184950Y424000D02*
Y426500D01*
X186492Y424708D01*
X184408D01*
G01X182433Y424000D02*
X182350Y424542D01*
X182225Y425000D01*
X182058Y425417D01*
X181850Y425875D01*
X181517Y426500D01*
X183183D01*
G01X190671Y419162D02*
X190921Y419287D01*
X191213Y419370D01*
X191546D01*
X191921Y419245D01*
X192213Y419037D01*
X192421Y418787D01*
X192588Y418370D01*
X192630Y417995D01*
X192546Y417620D01*
X192421Y417370D01*
X192171Y417120D01*
X191880Y416953D01*
X191588Y416870D01*
X191296D01*
X191005Y416953D01*
X190755Y417078D01*
X190546Y417245D01*
G01X188571Y416870D02*
X188488Y417412D01*
X188363Y417870D01*
X188196Y418287D01*
X187988Y418745D01*
X187655Y419370D01*
X189321D01*
G01X185388D02*
X185721Y419287D01*
X185971Y419078D01*
X186138Y418828D01*
X186263Y418495D01*
X186305Y418120D01*
X186263Y417745D01*
X186138Y417412D01*
X185971Y417162D01*
X185721Y416953D01*
X185388Y416870D01*
X185055Y416953D01*
X184805Y417162D01*
X184638Y417412D01*
X184513Y417745D01*
X184471Y418120D01*
X184513Y418495D01*
X184638Y418828D01*
X184805Y419078D01*
X185055Y419287D01*
X185388Y419370D01*
G01X182996Y417162D02*
X182705Y416953D01*
X182371Y416870D01*
X182038Y416953D01*
X181746Y417203D01*
X181538Y417578D01*
X181455Y417953D01*
Y418412D01*
X181538Y418787D01*
X181746Y419120D01*
X181996Y419287D01*
X182288Y419370D01*
X182621Y419287D01*
X182871Y419120D01*
X183038Y418870D01*
X183121Y418537D01*
X183038Y418245D01*
X182830Y417953D01*
X182580Y417787D01*
X182288Y417745D01*
X181955Y417828D01*
X181705Y418037D01*
X181455Y418412D01*
G01X203833Y366692D02*
X204083Y366817D01*
X204375Y366900D01*
X204708D01*
X205083Y366775D01*
X205375Y366567D01*
X205583Y366317D01*
X205750Y365900D01*
X205792Y365525D01*
X205708Y365150D01*
X205583Y364900D01*
X205333Y364650D01*
X205042Y364483D01*
X204750Y364400D01*
X204458D01*
X204167Y364483D01*
X203917Y364608D01*
X203708Y364775D01*
G01X201150Y364400D02*
Y366900D01*
X202692Y365108D01*
X200608D01*
G01X198550Y364400D02*
X198258Y364442D01*
X197925Y364567D01*
X197717Y364775D01*
X197633Y365067D01*
X197717Y365358D01*
X197967Y365608D01*
X198342Y365733D01*
X198758D01*
X199008Y365817D01*
X199217Y366025D01*
X199300Y366317D01*
X199175Y366608D01*
X198883Y366817D01*
X198550Y366900D01*
X198217Y366817D01*
X197925Y366608D01*
X197800Y366317D01*
X197883Y366025D01*
X198092Y365817D01*
X198342Y365733D01*
X198758D01*
X199133Y365608D01*
X199383Y365358D01*
X199467Y365067D01*
X199383Y364775D01*
X199175Y364567D01*
X198842Y364442D01*
X198550Y364400D01*
G01X196242Y366483D02*
X195992Y366733D01*
X195700Y366858D01*
X195367Y366900D01*
X194950Y366817D01*
X194658Y366608D01*
X194575Y366358D01*
X194617Y366108D01*
X194783Y365900D01*
X195617Y365483D01*
X195992Y365192D01*
X196242Y364775D01*
X196325Y364400D01*
X194575D01*
G01X190733Y433792D02*
X190983Y433917D01*
X191275Y434000D01*
X191608D01*
X191983Y433875D01*
X192275Y433667D01*
X192483Y433417D01*
X192650Y433000D01*
X192692Y432625D01*
X192608Y432250D01*
X192483Y432000D01*
X192233Y431750D01*
X191942Y431583D01*
X191650Y431500D01*
X191358D01*
X191067Y431583D01*
X190817Y431708D01*
X190608Y431875D01*
G01X189467Y432000D02*
X189217Y431708D01*
X188883Y431542D01*
X188508Y431500D01*
X188175Y431542D01*
X187842Y431750D01*
X187633Y432000D01*
X187592Y432250D01*
X187675Y432542D01*
X187967Y432750D01*
X188258Y432833D01*
X188633D01*
G01X188258D02*
X188008Y432958D01*
X187800Y433167D01*
X187717Y433417D01*
X187800Y433667D01*
X188008Y433875D01*
X188383Y434000D01*
X188758Y433958D01*
X189133Y433792D01*
G01X184950Y431500D02*
Y434000D01*
X186492Y432208D01*
X184408D01*
G01X182350Y431500D02*
X182058Y431542D01*
X181725Y431667D01*
X181517Y431875D01*
X181433Y432167D01*
X181517Y432458D01*
X181767Y432708D01*
X182142Y432833D01*
X182558D01*
X182808Y432917D01*
X183017Y433125D01*
X183100Y433417D01*
X182975Y433708D01*
X182683Y433917D01*
X182350Y434000D01*
X182017Y433917D01*
X181725Y433708D01*
X181600Y433417D01*
X181683Y433125D01*
X181892Y432917D01*
X182142Y432833D01*
X182558D01*
X182933Y432708D01*
X183183Y432458D01*
X183267Y432167D01*
X183183Y431875D01*
X182975Y431667D01*
X182642Y431542D01*
X182350Y431500D01*
G01X169967Y476167D02*
Y474375D01*
X169800Y474000D01*
X169467Y473750D01*
X169050Y473667D01*
X168633Y473750D01*
X168300Y474000D01*
X168133Y474375D01*
Y476167D01*
G01X166033Y473667D02*
X165950Y474209D01*
X165825Y474667D01*
X165658Y475084D01*
X165450Y475542D01*
X165117Y476167D01*
X166783D01*
G01X176538Y437136D02*
X147538D01*
G01X176538Y472136D02*
Y437136D01*
G01X147538Y472136D02*
X176538D01*
G01X147538Y437136D02*
Y472136D01*
G01X255900Y60887D02*
X256150Y61012D01*
X256442Y61095D01*
X256775D01*
X257150Y60970D01*
X257442Y60762D01*
X257650Y60512D01*
X257817Y60095D01*
X257859Y59720D01*
X257775Y59345D01*
X257650Y59095D01*
X257400Y58845D01*
X257109Y58678D01*
X256817Y58595D01*
X256525D01*
X256234Y58678D01*
X255984Y58803D01*
X255775Y58970D01*
G01X253717Y58595D02*
Y61095D01*
X254217Y60595D01*
G01Y58595D02*
X253217D01*
G01X250617Y61095D02*
X250950Y61012D01*
X251200Y60803D01*
X251367Y60553D01*
X251492Y60220D01*
X251534Y59845D01*
X251492Y59470D01*
X251367Y59137D01*
X251200Y58887D01*
X250950Y58678D01*
X250617Y58595D01*
X250284Y58678D01*
X250034Y58887D01*
X249867Y59137D01*
X249742Y59470D01*
X249700Y59845D01*
X249742Y60220D01*
X249867Y60553D01*
X250034Y60803D01*
X250284Y61012D01*
X250617Y61095D01*
G01X247517Y58595D02*
Y61095D01*
X248017Y60595D01*
G01Y58595D02*
X247017D01*
G01X265295Y146059D02*
Y148559D01*
X264254D01*
X263920Y148434D01*
X263712Y148267D01*
X263629Y147934D01*
X263712Y147601D01*
X263962Y147392D01*
X264254Y147267D01*
X265295D01*
G01X264254D02*
X263629Y146059D01*
G01X261362D02*
Y148559D01*
X261862Y148059D01*
G01Y146059D02*
X260862D01*
G01X259179Y146434D02*
X258929Y146226D01*
X258637Y146101D01*
X258262Y146059D01*
X257887Y146142D01*
X257595Y146309D01*
X257387Y146601D01*
X257345Y146934D01*
X257429Y147267D01*
X257637Y147476D01*
X257929Y147642D01*
X258220Y147684D01*
X258512Y147642D01*
X258887Y147476D01*
X258762Y148559D01*
X257637D01*
G01X255245Y146059D02*
X255162Y146601D01*
X255037Y147059D01*
X254870Y147476D01*
X254662Y147934D01*
X254329Y148559D01*
X255995D01*
G01X265295Y158059D02*
Y160559D01*
X264254D01*
X263920Y160434D01*
X263712Y160267D01*
X263629Y159934D01*
X263712Y159601D01*
X263962Y159392D01*
X264254Y159267D01*
X265295D01*
G01X264254D02*
X263629Y158059D01*
G01X261362D02*
Y160559D01*
X261862Y160059D01*
G01Y158059D02*
X260862D01*
G01X259054Y159101D02*
X258762Y159392D01*
X258512Y159559D01*
X258179Y159642D01*
X257887Y159559D01*
X257679Y159392D01*
X257512Y159142D01*
X257470Y158851D01*
X257512Y158601D01*
X257679Y158351D01*
X257929Y158142D01*
X258220Y158059D01*
X258554Y158142D01*
X258845Y158392D01*
X259012Y158767D01*
X259054Y159184D01*
X258970Y159726D01*
X258845Y160017D01*
X258637Y160309D01*
X258345Y160517D01*
X258054Y160559D01*
X257762Y160476D01*
X257554Y160267D01*
G01X255162Y158059D02*
X254870Y158101D01*
X254537Y158226D01*
X254329Y158434D01*
X254245Y158726D01*
X254329Y159017D01*
X254579Y159267D01*
X254954Y159392D01*
X255370D01*
X255620Y159476D01*
X255829Y159684D01*
X255912Y159976D01*
X255787Y160267D01*
X255495Y160476D01*
X255162Y160559D01*
X254829Y160476D01*
X254537Y160267D01*
X254412Y159976D01*
X254495Y159684D01*
X254704Y159476D01*
X254954Y159392D01*
X255370D01*
X255745Y159267D01*
X255995Y159017D01*
X256079Y158726D01*
X255995Y158434D01*
X255787Y158226D01*
X255454Y158101D01*
X255162Y158059D01*
G01X265295Y156559D02*
Y154059D01*
X263629D01*
G01X261362D02*
Y156559D01*
X261862Y156059D01*
G01Y154059D02*
X260862D01*
G01X258345D02*
X258262Y154601D01*
X258137Y155059D01*
X257970Y155476D01*
X257762Y155934D01*
X257429Y156559D01*
X259095D01*
G01X265295Y152559D02*
Y150059D01*
X263629D01*
G01X261445D02*
X261362Y150601D01*
X261237Y151059D01*
X261070Y151476D01*
X260862Y151934D01*
X260529Y152559D01*
X262195D01*
G01X263645Y198706D02*
Y201206D01*
X262604D01*
X262270Y201081D01*
X262062Y200914D01*
X261979Y200581D01*
X262062Y200248D01*
X262312Y200039D01*
X262604Y199914D01*
X263645D01*
G01X262604D02*
X261979Y198706D01*
G01X259712D02*
Y201206D01*
X260212Y200706D01*
G01Y198706D02*
X259212D01*
G01X257529Y199081D02*
X257279Y198873D01*
X256987Y198748D01*
X256612Y198706D01*
X256237Y198789D01*
X255945Y198956D01*
X255737Y199248D01*
X255695Y199581D01*
X255779Y199914D01*
X255987Y200123D01*
X256279Y200289D01*
X256570Y200331D01*
X256862Y200289D01*
X257237Y200123D01*
X257112Y201206D01*
X255987D01*
G01X254220Y198998D02*
X253929Y198789D01*
X253595Y198706D01*
X253262Y198789D01*
X252970Y199039D01*
X252762Y199414D01*
X252679Y199789D01*
Y200248D01*
X252762Y200623D01*
X252970Y200956D01*
X253220Y201123D01*
X253512Y201206D01*
X253845Y201123D01*
X254095Y200956D01*
X254262Y200706D01*
X254345Y200373D01*
X254262Y200081D01*
X254054Y199789D01*
X253804Y199623D01*
X253512Y199581D01*
X253179Y199664D01*
X252929Y199873D01*
X252679Y200248D01*
G01X265296Y232992D02*
Y235492D01*
X264255D01*
X263921Y235367D01*
X263713Y235200D01*
X263630Y234867D01*
X263713Y234534D01*
X263963Y234325D01*
X264255Y234200D01*
X265296D01*
G01X264255D02*
X263630Y232992D01*
G01X261363D02*
Y235492D01*
X261863Y234992D01*
G01Y232992D02*
X260863D01*
G01X259055Y234034D02*
X258763Y234325D01*
X258513Y234492D01*
X258180Y234575D01*
X257888Y234492D01*
X257680Y234325D01*
X257513Y234075D01*
X257471Y233784D01*
X257513Y233534D01*
X257680Y233284D01*
X257930Y233075D01*
X258221Y232992D01*
X258555Y233075D01*
X258846Y233325D01*
X259013Y233700D01*
X259055Y234117D01*
X258971Y234659D01*
X258846Y234950D01*
X258638Y235242D01*
X258346Y235450D01*
X258055Y235492D01*
X257763Y235409D01*
X257555Y235200D01*
G01X255163Y235492D02*
X255496Y235409D01*
X255746Y235200D01*
X255913Y234950D01*
X256038Y234617D01*
X256080Y234242D01*
X256038Y233867D01*
X255913Y233534D01*
X255746Y233284D01*
X255496Y233075D01*
X255163Y232992D01*
X254830Y233075D01*
X254580Y233284D01*
X254413Y233534D01*
X254288Y233867D01*
X254246Y234242D01*
X254288Y234617D01*
X254413Y234950D01*
X254580Y235200D01*
X254830Y235409D01*
X255163Y235492D01*
G01X263645Y186706D02*
Y189206D01*
X262604D01*
X262270Y189081D01*
X262062Y188914D01*
X261979Y188581D01*
X262062Y188248D01*
X262312Y188039D01*
X262604Y187914D01*
X263645D01*
G01X262604D02*
X261979Y186706D01*
G01X259712D02*
Y189206D01*
X260212Y188706D01*
G01Y186706D02*
X259212D01*
G01X257404Y187748D02*
X257112Y188039D01*
X256862Y188206D01*
X256529Y188289D01*
X256237Y188206D01*
X256029Y188039D01*
X255862Y187789D01*
X255820Y187498D01*
X255862Y187248D01*
X256029Y186998D01*
X256279Y186789D01*
X256570Y186706D01*
X256904Y186789D01*
X257195Y187039D01*
X257362Y187414D01*
X257404Y187831D01*
X257320Y188373D01*
X257195Y188664D01*
X256987Y188956D01*
X256695Y189164D01*
X256404Y189206D01*
X256112Y189123D01*
X255904Y188914D01*
G01X253595Y186706D02*
X253512Y187248D01*
X253387Y187706D01*
X253220Y188123D01*
X253012Y188581D01*
X252679Y189206D01*
X254345D01*
G01X265296Y239492D02*
Y236992D01*
X263630D01*
G01X261363D02*
Y239492D01*
X261863Y238992D01*
G01Y236992D02*
X260863D01*
G01X258263Y239492D02*
X258596Y239409D01*
X258846Y239200D01*
X259013Y238950D01*
X259138Y238617D01*
X259180Y238242D01*
X259138Y237867D01*
X259013Y237534D01*
X258846Y237284D01*
X258596Y237075D01*
X258263Y236992D01*
X257930Y237075D01*
X257680Y237284D01*
X257513Y237534D01*
X257388Y237867D01*
X257346Y238242D01*
X257388Y238617D01*
X257513Y238950D01*
X257680Y239200D01*
X257930Y239409D01*
X258263Y239492D01*
G01X263645Y193206D02*
Y190706D01*
X261979D01*
G01X259712D02*
Y193206D01*
X260212Y192706D01*
G01Y190706D02*
X259212D01*
G01X257404Y191748D02*
X257112Y192039D01*
X256862Y192206D01*
X256529Y192289D01*
X256237Y192206D01*
X256029Y192039D01*
X255862Y191789D01*
X255820Y191498D01*
X255862Y191248D01*
X256029Y190998D01*
X256279Y190789D01*
X256570Y190706D01*
X256904Y190789D01*
X257195Y191039D01*
X257362Y191414D01*
X257404Y191831D01*
X257320Y192373D01*
X257195Y192664D01*
X256987Y192956D01*
X256695Y193164D01*
X256404Y193206D01*
X256112Y193123D01*
X255904Y192914D01*
G01X263645Y197206D02*
Y194706D01*
X261979D01*
G01X260420Y194998D02*
X260129Y194789D01*
X259795Y194706D01*
X259462Y194789D01*
X259170Y195039D01*
X258962Y195414D01*
X258879Y195789D01*
Y196248D01*
X258962Y196623D01*
X259170Y196956D01*
X259420Y197123D01*
X259712Y197206D01*
X260045Y197123D01*
X260295Y196956D01*
X260462Y196706D01*
X260545Y196373D01*
X260462Y196081D01*
X260254Y195789D01*
X260004Y195623D01*
X259712Y195581D01*
X259379Y195664D01*
X259129Y195873D01*
X258879Y196248D01*
G01X241124Y202854D02*
X241374Y202979D01*
X241666Y203062D01*
X241999D01*
X242374Y202937D01*
X242666Y202729D01*
X242874Y202479D01*
X243041Y202062D01*
X243083Y201687D01*
X242999Y201312D01*
X242874Y201062D01*
X242624Y200812D01*
X242333Y200645D01*
X242041Y200562D01*
X241749D01*
X241458Y200645D01*
X241208Y200770D01*
X240999Y200937D01*
G01X239733Y201604D02*
X239441Y201895D01*
X239191Y202062D01*
X238858Y202145D01*
X238566Y202062D01*
X238358Y201895D01*
X238191Y201645D01*
X238149Y201354D01*
X238191Y201104D01*
X238358Y200854D01*
X238608Y200645D01*
X238899Y200562D01*
X239233Y200645D01*
X239524Y200895D01*
X239691Y201270D01*
X239733Y201687D01*
X239649Y202229D01*
X239524Y202520D01*
X239316Y202812D01*
X239024Y203020D01*
X238733Y203062D01*
X238441Y202979D01*
X238233Y202770D01*
G01X235841Y200562D02*
Y203062D01*
X236341Y202562D01*
G01Y200562D02*
X235341D01*
G01X232241D02*
Y203062D01*
X233783Y201270D01*
X231699D01*
G01X241124Y198854D02*
X241374Y198979D01*
X241666Y199062D01*
X241999D01*
X242374Y198937D01*
X242666Y198729D01*
X242874Y198479D01*
X243041Y198062D01*
X243083Y197687D01*
X242999Y197312D01*
X242874Y197062D01*
X242624Y196812D01*
X242333Y196645D01*
X242041Y196562D01*
X241749D01*
X241458Y196645D01*
X241208Y196770D01*
X240999Y196937D01*
G01X239733Y197604D02*
X239441Y197895D01*
X239191Y198062D01*
X238858Y198145D01*
X238566Y198062D01*
X238358Y197895D01*
X238191Y197645D01*
X238149Y197354D01*
X238191Y197104D01*
X238358Y196854D01*
X238608Y196645D01*
X238899Y196562D01*
X239233Y196645D01*
X239524Y196895D01*
X239691Y197270D01*
X239733Y197687D01*
X239649Y198229D01*
X239524Y198520D01*
X239316Y198812D01*
X239024Y199020D01*
X238733Y199062D01*
X238441Y198979D01*
X238233Y198770D01*
G01X235841Y196562D02*
Y199062D01*
X236341Y198562D01*
G01Y196562D02*
X235341D01*
G01X232824D02*
X232741Y197104D01*
X232616Y197562D01*
X232449Y197979D01*
X232241Y198437D01*
X231908Y199062D01*
X233574D01*
G01X241124Y194854D02*
X241374Y194979D01*
X241666Y195062D01*
X241999D01*
X242374Y194937D01*
X242666Y194729D01*
X242874Y194479D01*
X243041Y194062D01*
X243083Y193687D01*
X242999Y193312D01*
X242874Y193062D01*
X242624Y192812D01*
X242333Y192645D01*
X242041Y192562D01*
X241749D01*
X241458Y192645D01*
X241208Y192770D01*
X240999Y192937D01*
G01X239024Y192562D02*
X238941Y193104D01*
X238816Y193562D01*
X238649Y193979D01*
X238441Y194437D01*
X238108Y195062D01*
X239774D01*
G01X235841D02*
X236174Y194979D01*
X236424Y194770D01*
X236591Y194520D01*
X236716Y194187D01*
X236758Y193812D01*
X236716Y193437D01*
X236591Y193104D01*
X236424Y192854D01*
X236174Y192645D01*
X235841Y192562D01*
X235508Y192645D01*
X235258Y192854D01*
X235091Y193104D01*
X234966Y193437D01*
X234924Y193812D01*
X234966Y194187D01*
X235091Y194520D01*
X235258Y194770D01*
X235508Y194979D01*
X235841Y195062D01*
G01X232741Y192562D02*
X232449Y192604D01*
X232116Y192729D01*
X231908Y192937D01*
X231824Y193229D01*
X231908Y193520D01*
X232158Y193770D01*
X232533Y193895D01*
X232949D01*
X233199Y193979D01*
X233408Y194187D01*
X233491Y194479D01*
X233366Y194770D01*
X233074Y194979D01*
X232741Y195062D01*
X232408Y194979D01*
X232116Y194770D01*
X231991Y194479D01*
X232074Y194187D01*
X232283Y193979D01*
X232533Y193895D01*
X232949D01*
X233324Y193770D01*
X233574Y193520D01*
X233658Y193229D01*
X233574Y192937D01*
X233366Y192729D01*
X233033Y192604D01*
X232741Y192562D01*
G01X241124Y190854D02*
X241374Y190979D01*
X241666Y191062D01*
X241999D01*
X242374Y190937D01*
X242666Y190729D01*
X242874Y190479D01*
X243041Y190062D01*
X243083Y189687D01*
X242999Y189312D01*
X242874Y189062D01*
X242624Y188812D01*
X242333Y188645D01*
X242041Y188562D01*
X241749D01*
X241458Y188645D01*
X241208Y188770D01*
X240999Y188937D01*
G01X239733Y189604D02*
X239441Y189895D01*
X239191Y190062D01*
X238858Y190145D01*
X238566Y190062D01*
X238358Y189895D01*
X238191Y189645D01*
X238149Y189354D01*
X238191Y189104D01*
X238358Y188854D01*
X238608Y188645D01*
X238899Y188562D01*
X239233Y188645D01*
X239524Y188895D01*
X239691Y189270D01*
X239733Y189687D01*
X239649Y190229D01*
X239524Y190520D01*
X239316Y190812D01*
X239024Y191020D01*
X238733Y191062D01*
X238441Y190979D01*
X238233Y190770D01*
G01X235841Y188562D02*
X235549Y188604D01*
X235216Y188729D01*
X235008Y188937D01*
X234924Y189229D01*
X235008Y189520D01*
X235258Y189770D01*
X235633Y189895D01*
X236049D01*
X236299Y189979D01*
X236508Y190187D01*
X236591Y190479D01*
X236466Y190770D01*
X236174Y190979D01*
X235841Y191062D01*
X235508Y190979D01*
X235216Y190770D01*
X235091Y190479D01*
X235174Y190187D01*
X235383Y189979D01*
X235633Y189895D01*
X236049D01*
X236424Y189770D01*
X236674Y189520D01*
X236758Y189229D01*
X236674Y188937D01*
X236466Y188729D01*
X236133Y188604D01*
X235841Y188562D01*
G01X233658Y188937D02*
X233408Y188729D01*
X233116Y188604D01*
X232741Y188562D01*
X232366Y188645D01*
X232074Y188812D01*
X231866Y189104D01*
X231824Y189437D01*
X231908Y189770D01*
X232116Y189979D01*
X232408Y190145D01*
X232699Y190187D01*
X232991Y190145D01*
X233366Y189979D01*
X233241Y191062D01*
X232116D01*
G01X241124Y186854D02*
X241374Y186979D01*
X241666Y187062D01*
X241999D01*
X242374Y186937D01*
X242666Y186729D01*
X242874Y186479D01*
X243041Y186062D01*
X243083Y185687D01*
X242999Y185312D01*
X242874Y185062D01*
X242624Y184812D01*
X242333Y184645D01*
X242041Y184562D01*
X241749D01*
X241458Y184645D01*
X241208Y184770D01*
X240999Y184937D01*
G01X239733Y185604D02*
X239441Y185895D01*
X239191Y186062D01*
X238858Y186145D01*
X238566Y186062D01*
X238358Y185895D01*
X238191Y185645D01*
X238149Y185354D01*
X238191Y185104D01*
X238358Y184854D01*
X238608Y184645D01*
X238899Y184562D01*
X239233Y184645D01*
X239524Y184895D01*
X239691Y185270D01*
X239733Y185687D01*
X239649Y186229D01*
X239524Y186520D01*
X239316Y186812D01*
X239024Y187020D01*
X238733Y187062D01*
X238441Y186979D01*
X238233Y186770D01*
G01X235841Y184562D02*
X235549Y184604D01*
X235216Y184729D01*
X235008Y184937D01*
X234924Y185229D01*
X235008Y185520D01*
X235258Y185770D01*
X235633Y185895D01*
X236049D01*
X236299Y185979D01*
X236508Y186187D01*
X236591Y186479D01*
X236466Y186770D01*
X236174Y186979D01*
X235841Y187062D01*
X235508Y186979D01*
X235216Y186770D01*
X235091Y186479D01*
X235174Y186187D01*
X235383Y185979D01*
X235633Y185895D01*
X236049D01*
X236424Y185770D01*
X236674Y185520D01*
X236758Y185229D01*
X236674Y184937D01*
X236466Y184729D01*
X236133Y184604D01*
X235841Y184562D01*
G01X232241D02*
Y187062D01*
X233783Y185270D01*
X231699D01*
G01X246333Y300500D02*
X243000Y307500D01*
X239667Y300500D01*
G01X240867Y302950D02*
X245133D01*
G01X231333Y296692D02*
X231583Y296817D01*
X231875Y296900D01*
X232208D01*
X232583Y296775D01*
X232875Y296567D01*
X233083Y296317D01*
X233250Y295900D01*
X233292Y295525D01*
X233208Y295150D01*
X233083Y294900D01*
X232833Y294650D01*
X232542Y294483D01*
X232250Y294400D01*
X231958D01*
X231667Y294483D01*
X231417Y294608D01*
X231208Y294775D01*
G01X228650Y294400D02*
Y296900D01*
X230192Y295108D01*
X228108D01*
G01X226133Y294400D02*
X226050Y294942D01*
X225925Y295400D01*
X225758Y295817D01*
X225550Y296275D01*
X225217Y296900D01*
X226883D01*
G01X223742Y296483D02*
X223492Y296733D01*
X223200Y296858D01*
X222867Y296900D01*
X222450Y296817D01*
X222158Y296608D01*
X222075Y296358D01*
X222117Y296108D01*
X222283Y295900D01*
X223117Y295483D01*
X223492Y295192D01*
X223742Y294775D01*
X223825Y294400D01*
X222075D01*
G01X220523Y288042D02*
X220773Y288167D01*
X221065Y288250D01*
X221398D01*
X221773Y288125D01*
X222065Y287917D01*
X222273Y287667D01*
X222440Y287250D01*
X222482Y286875D01*
X222398Y286500D01*
X222273Y286250D01*
X222023Y286000D01*
X221732Y285833D01*
X221440Y285750D01*
X221148D01*
X220857Y285833D01*
X220607Y285958D01*
X220398Y286125D01*
G01X217840Y285750D02*
Y288250D01*
X219382Y286458D01*
X217298D01*
G01X216032Y286792D02*
X215740Y287083D01*
X215490Y287250D01*
X215157Y287333D01*
X214865Y287250D01*
X214657Y287083D01*
X214490Y286833D01*
X214448Y286542D01*
X214490Y286292D01*
X214657Y286042D01*
X214907Y285833D01*
X215198Y285750D01*
X215532Y285833D01*
X215823Y286083D01*
X215990Y286458D01*
X216032Y286875D01*
X215948Y287417D01*
X215823Y287708D01*
X215615Y288000D01*
X215323Y288208D01*
X215032Y288250D01*
X214740Y288167D01*
X214532Y287958D01*
G01X212140Y285750D02*
X211848Y285792D01*
X211515Y285917D01*
X211307Y286125D01*
X211223Y286417D01*
X211307Y286708D01*
X211557Y286958D01*
X211932Y287083D01*
X212348D01*
X212598Y287167D01*
X212807Y287375D01*
X212890Y287667D01*
X212765Y287958D01*
X212473Y288167D01*
X212140Y288250D01*
X211807Y288167D01*
X211515Y287958D01*
X211390Y287667D01*
X211473Y287375D01*
X211682Y287167D01*
X211932Y287083D01*
X212348D01*
X212723Y286958D01*
X212973Y286708D01*
X213057Y286417D01*
X212973Y286125D01*
X212765Y285917D01*
X212432Y285792D01*
X212140Y285750D01*
G01X238833Y289192D02*
X239083Y289317D01*
X239375Y289400D01*
X239708D01*
X240083Y289275D01*
X240375Y289067D01*
X240583Y288817D01*
X240750Y288400D01*
X240792Y288025D01*
X240708Y287650D01*
X240583Y287400D01*
X240333Y287150D01*
X240042Y286983D01*
X239750Y286900D01*
X239458D01*
X239167Y286983D01*
X238917Y287108D01*
X238708Y287275D01*
G01X236150Y286900D02*
Y289400D01*
X237692Y287608D01*
X235608D01*
G01X234342Y287942D02*
X234050Y288233D01*
X233800Y288400D01*
X233467Y288483D01*
X233175Y288400D01*
X232967Y288233D01*
X232800Y287983D01*
X232758Y287692D01*
X232800Y287442D01*
X232967Y287192D01*
X233217Y286983D01*
X233508Y286900D01*
X233842Y286983D01*
X234133Y287233D01*
X234300Y287608D01*
X234342Y288025D01*
X234258Y288567D01*
X234133Y288858D01*
X233925Y289150D01*
X233633Y289358D01*
X233342Y289400D01*
X233050Y289317D01*
X232842Y289108D01*
G01X230533Y286900D02*
X230450Y287442D01*
X230325Y287900D01*
X230158Y288317D01*
X229950Y288775D01*
X229617Y289400D01*
X231283D01*
G01X226902Y283612D02*
X227027Y283362D01*
X227110Y283070D01*
Y282737D01*
X226985Y282362D01*
X226777Y282070D01*
X226527Y281862D01*
X226110Y281695D01*
X225735Y281653D01*
X225360Y281737D01*
X225110Y281862D01*
X224860Y282112D01*
X224693Y282403D01*
X224610Y282695D01*
Y282987D01*
X224693Y283278D01*
X224818Y283528D01*
X224985Y283737D01*
G01X224610Y286295D02*
X227110D01*
X225318Y284753D01*
Y286837D01*
G01X224985Y287978D02*
X224777Y288228D01*
X224652Y288520D01*
X224610Y288895D01*
X224693Y289270D01*
X224860Y289562D01*
X225152Y289770D01*
X225485Y289812D01*
X225818Y289728D01*
X226027Y289520D01*
X226193Y289228D01*
X226235Y288937D01*
X226193Y288645D01*
X226027Y288270D01*
X227110Y288395D01*
Y289520D01*
G01X224902Y291287D02*
X224693Y291578D01*
X224610Y291912D01*
X224693Y292245D01*
X224943Y292537D01*
X225318Y292745D01*
X225693Y292828D01*
X226152D01*
X226527Y292745D01*
X226860Y292537D01*
X227027Y292287D01*
X227110Y291995D01*
X227027Y291662D01*
X226860Y291412D01*
X226610Y291245D01*
X226277Y291162D01*
X225985Y291245D01*
X225693Y291453D01*
X225527Y291703D01*
X225485Y291995D01*
X225568Y292328D01*
X225777Y292578D01*
X226152Y292828D01*
G01X217600Y298417D02*
X220100D01*
Y299458D01*
X219975Y299792D01*
X219808Y300000D01*
X219475Y300083D01*
X219142Y300000D01*
X218933Y299750D01*
X218808Y299458D01*
Y298417D01*
G01Y299458D02*
X217600Y300083D01*
G01X219683Y301558D02*
X219933Y301808D01*
X220058Y302100D01*
X220100Y302433D01*
X220017Y302850D01*
X219808Y303142D01*
X219558Y303225D01*
X219308Y303183D01*
X219100Y303017D01*
X218683Y302183D01*
X218392Y301808D01*
X217975Y301558D01*
X217600Y301475D01*
Y303225D01*
G01X217975Y304533D02*
X217767Y304783D01*
X217642Y305075D01*
X217600Y305450D01*
X217683Y305825D01*
X217850Y306117D01*
X218142Y306325D01*
X218475Y306367D01*
X218808Y306283D01*
X219017Y306075D01*
X219183Y305783D01*
X219225Y305492D01*
X219183Y305200D01*
X219017Y304825D01*
X220100Y304950D01*
Y306075D01*
G01X217600Y308467D02*
X218142Y308550D01*
X218600Y308675D01*
X219017Y308842D01*
X219475Y309050D01*
X220100Y309383D01*
Y307717D01*
G01X213100Y298417D02*
X215600D01*
Y299458D01*
X215475Y299792D01*
X215308Y300000D01*
X214975Y300083D01*
X214642Y300000D01*
X214433Y299750D01*
X214308Y299458D01*
Y298417D01*
G01Y299458D02*
X213100Y300083D01*
G01X215183Y301558D02*
X215433Y301808D01*
X215558Y302100D01*
X215600Y302433D01*
X215517Y302850D01*
X215308Y303142D01*
X215058Y303225D01*
X214808Y303183D01*
X214600Y303017D01*
X214183Y302183D01*
X213892Y301808D01*
X213475Y301558D01*
X213100Y301475D01*
Y303225D01*
G01X213475Y304533D02*
X213267Y304783D01*
X213142Y305075D01*
X213100Y305450D01*
X213183Y305825D01*
X213350Y306117D01*
X213642Y306325D01*
X213975Y306367D01*
X214308Y306283D01*
X214517Y306075D01*
X214683Y305783D01*
X214725Y305492D01*
X214683Y305200D01*
X214517Y304825D01*
X215600Y304950D01*
Y306075D01*
G01X213100Y308550D02*
X215600D01*
X215100Y308050D01*
G01X213100D02*
Y309050D01*
G01X265296Y244992D02*
Y247492D01*
X264255D01*
X263921Y247367D01*
X263713Y247200D01*
X263630Y246867D01*
X263713Y246534D01*
X263963Y246325D01*
X264255Y246200D01*
X265296D01*
G01X264255D02*
X263630Y244992D01*
G01X261363D02*
Y247492D01*
X261863Y246992D01*
G01Y244992D02*
X260863D01*
G01X259180Y245367D02*
X258930Y245159D01*
X258638Y245034D01*
X258263Y244992D01*
X257888Y245075D01*
X257596Y245242D01*
X257388Y245534D01*
X257346Y245867D01*
X257430Y246200D01*
X257638Y246409D01*
X257930Y246575D01*
X258221Y246617D01*
X258513Y246575D01*
X258888Y246409D01*
X258763Y247492D01*
X257638D01*
G01X255163Y244992D02*
X254871Y245034D01*
X254538Y245159D01*
X254330Y245367D01*
X254246Y245659D01*
X254330Y245950D01*
X254580Y246200D01*
X254955Y246325D01*
X255371D01*
X255621Y246409D01*
X255830Y246617D01*
X255913Y246909D01*
X255788Y247200D01*
X255496Y247409D01*
X255163Y247492D01*
X254830Y247409D01*
X254538Y247200D01*
X254413Y246909D01*
X254496Y246617D01*
X254705Y246409D01*
X254955Y246325D01*
X255371D01*
X255746Y246200D01*
X255996Y245950D01*
X256080Y245659D01*
X255996Y245367D01*
X255788Y245159D01*
X255455Y245034D01*
X255163Y244992D01*
G01X265296Y243492D02*
Y240992D01*
X263630D01*
G01X261363D02*
X261071Y241034D01*
X260738Y241159D01*
X260530Y241367D01*
X260446Y241659D01*
X260530Y241950D01*
X260780Y242200D01*
X261155Y242325D01*
X261571D01*
X261821Y242409D01*
X262030Y242617D01*
X262113Y242909D01*
X261988Y243200D01*
X261696Y243409D01*
X261363Y243492D01*
X261030Y243409D01*
X260738Y243200D01*
X260613Y242909D01*
X260696Y242617D01*
X260905Y242409D01*
X261155Y242325D01*
X261571D01*
X261946Y242200D01*
X262196Y241950D01*
X262280Y241659D01*
X262196Y241367D01*
X261988Y241159D01*
X261655Y241034D01*
X261363Y240992D01*
G01X220523Y284042D02*
X220773Y284167D01*
X221065Y284250D01*
X221398D01*
X221773Y284125D01*
X222065Y283917D01*
X222273Y283667D01*
X222440Y283250D01*
X222482Y282875D01*
X222398Y282500D01*
X222273Y282250D01*
X222023Y282000D01*
X221732Y281833D01*
X221440Y281750D01*
X221148D01*
X220857Y281833D01*
X220607Y281958D01*
X220398Y282125D01*
G01X217840Y281750D02*
Y284250D01*
X219382Y282458D01*
X217298D01*
G01X215240Y281750D02*
X214948Y281792D01*
X214615Y281917D01*
X214407Y282125D01*
X214323Y282417D01*
X214407Y282708D01*
X214657Y282958D01*
X215032Y283083D01*
X215448D01*
X215698Y283167D01*
X215907Y283375D01*
X215990Y283667D01*
X215865Y283958D01*
X215573Y284167D01*
X215240Y284250D01*
X214907Y284167D01*
X214615Y283958D01*
X214490Y283667D01*
X214573Y283375D01*
X214782Y283167D01*
X215032Y283083D01*
X215448D01*
X215823Y282958D01*
X216073Y282708D01*
X216157Y282417D01*
X216073Y282125D01*
X215865Y281917D01*
X215532Y281792D01*
X215240Y281750D01*
G01X213057Y282250D02*
X212807Y281958D01*
X212473Y281792D01*
X212098Y281750D01*
X211765Y281792D01*
X211432Y282000D01*
X211223Y282250D01*
X211182Y282500D01*
X211265Y282792D01*
X211557Y283000D01*
X211848Y283083D01*
X212223D01*
G01X211848D02*
X211598Y283208D01*
X211390Y283417D01*
X211307Y283667D01*
X211390Y283917D01*
X211598Y284125D01*
X211973Y284250D01*
X212348Y284208D01*
X212723Y284042D01*
G01X261750Y298400D02*
Y295900D01*
G01X262708Y298400D02*
X260792D01*
G01X259483Y295900D02*
Y298400D01*
X258483D01*
X258150Y298275D01*
X257900Y297983D01*
X257817Y297650D01*
X257900Y297317D01*
X258108Y297067D01*
X258483Y296942D01*
X259483D01*
G01X255550Y295900D02*
X255258Y295942D01*
X254925Y296067D01*
X254717Y296275D01*
X254633Y296567D01*
X254717Y296858D01*
X254967Y297108D01*
X255342Y297233D01*
X255758D01*
X256008Y297317D01*
X256217Y297525D01*
X256300Y297817D01*
X256175Y298108D01*
X255883Y298317D01*
X255550Y298400D01*
X255217Y298317D01*
X254925Y298108D01*
X254800Y297817D01*
X254883Y297525D01*
X255092Y297317D01*
X255342Y297233D01*
X255758D01*
X256133Y297108D01*
X256383Y296858D01*
X256467Y296567D01*
X256383Y296275D01*
X256175Y296067D01*
X255842Y295942D01*
X255550Y295900D01*
G01X253242Y296942D02*
X252950Y297233D01*
X252700Y297400D01*
X252367Y297483D01*
X252075Y297400D01*
X251867Y297233D01*
X251700Y296983D01*
X251658Y296692D01*
X251700Y296442D01*
X251867Y296192D01*
X252117Y295983D01*
X252408Y295900D01*
X252742Y295983D01*
X253033Y296233D01*
X253200Y296608D01*
X253242Y297025D01*
X253158Y297567D01*
X253033Y297858D01*
X252825Y298150D01*
X252533Y298358D01*
X252242Y298400D01*
X251950Y298317D01*
X251742Y298108D01*
G01X264250Y291400D02*
Y288900D01*
G01X265208Y291400D02*
X263292D01*
G01X261983Y288900D02*
Y291400D01*
X260983D01*
X260650Y291275D01*
X260400Y290983D01*
X260317Y290650D01*
X260400Y290317D01*
X260608Y290067D01*
X260983Y289942D01*
X261983D01*
G01X258050Y288900D02*
X257758Y288942D01*
X257425Y289067D01*
X257217Y289275D01*
X257133Y289567D01*
X257217Y289858D01*
X257467Y290108D01*
X257842Y290233D01*
X258258D01*
X258508Y290317D01*
X258717Y290525D01*
X258800Y290817D01*
X258675Y291108D01*
X258383Y291317D01*
X258050Y291400D01*
X257717Y291317D01*
X257425Y291108D01*
X257300Y290817D01*
X257383Y290525D01*
X257592Y290317D01*
X257842Y290233D01*
X258258D01*
X258633Y290108D01*
X258883Y289858D01*
X258967Y289567D01*
X258883Y289275D01*
X258675Y289067D01*
X258342Y288942D01*
X258050Y288900D01*
G01X255742Y290983D02*
X255492Y291233D01*
X255200Y291358D01*
X254867Y291400D01*
X254450Y291317D01*
X254158Y291108D01*
X254075Y290858D01*
X254117Y290608D01*
X254283Y290400D01*
X255117Y289983D01*
X255492Y289692D01*
X255742Y289275D01*
X255825Y288900D01*
X254075D01*
G01X266250Y286900D02*
Y284400D01*
G01X267208Y286900D02*
X265292D01*
G01X263983Y284400D02*
Y286900D01*
X262983D01*
X262650Y286775D01*
X262400Y286483D01*
X262317Y286150D01*
X262400Y285817D01*
X262608Y285567D01*
X262983Y285442D01*
X263983D01*
G01X260050Y284400D02*
X259758Y284442D01*
X259425Y284567D01*
X259217Y284775D01*
X259133Y285067D01*
X259217Y285358D01*
X259467Y285608D01*
X259842Y285733D01*
X260258D01*
X260508Y285817D01*
X260717Y286025D01*
X260800Y286317D01*
X260675Y286608D01*
X260383Y286817D01*
X260050Y286900D01*
X259717Y286817D01*
X259425Y286608D01*
X259300Y286317D01*
X259383Y286025D01*
X259592Y285817D01*
X259842Y285733D01*
X260258D01*
X260633Y285608D01*
X260883Y285358D01*
X260967Y285067D01*
X260883Y284775D01*
X260675Y284567D01*
X260342Y284442D01*
X260050Y284400D01*
G01X256950Y286900D02*
X257283Y286817D01*
X257533Y286608D01*
X257700Y286358D01*
X257825Y286025D01*
X257867Y285650D01*
X257825Y285275D01*
X257700Y284942D01*
X257533Y284692D01*
X257283Y284483D01*
X256950Y284400D01*
X256617Y284483D01*
X256367Y284692D01*
X256200Y284942D01*
X256075Y285275D01*
X256033Y285650D01*
X256075Y286025D01*
X256200Y286358D01*
X256367Y286608D01*
X256617Y286817D01*
X256950Y286900D01*
G01X272250Y282900D02*
Y280400D01*
G01X273208Y282900D02*
X271292D01*
G01X269983Y280400D02*
Y282900D01*
X268983D01*
X268650Y282775D01*
X268400Y282483D01*
X268317Y282150D01*
X268400Y281817D01*
X268608Y281567D01*
X268983Y281442D01*
X269983D01*
G01X266133Y280400D02*
X266050Y280942D01*
X265925Y281400D01*
X265758Y281817D01*
X265550Y282275D01*
X265217Y282900D01*
X266883D01*
G01X262950Y280400D02*
X262658Y280442D01*
X262325Y280567D01*
X262117Y280775D01*
X262033Y281067D01*
X262117Y281358D01*
X262367Y281608D01*
X262742Y281733D01*
X263158D01*
X263408Y281817D01*
X263617Y282025D01*
X263700Y282317D01*
X263575Y282608D01*
X263283Y282817D01*
X262950Y282900D01*
X262617Y282817D01*
X262325Y282608D01*
X262200Y282317D01*
X262283Y282025D01*
X262492Y281817D01*
X262742Y281733D01*
X263158D01*
X263533Y281608D01*
X263783Y281358D01*
X263867Y281067D01*
X263783Y280775D01*
X263575Y280567D01*
X263242Y280442D01*
X262950Y280400D01*
G01X260750Y278400D02*
Y275900D01*
G01X261708Y278400D02*
X259792D01*
G01X258483Y275900D02*
Y278400D01*
X257483D01*
X257150Y278275D01*
X256900Y277983D01*
X256817Y277650D01*
X256900Y277317D01*
X257108Y277067D01*
X257483Y276942D01*
X258483D01*
G01X254633Y275900D02*
X254550Y276442D01*
X254425Y276900D01*
X254258Y277317D01*
X254050Y277775D01*
X253717Y278400D01*
X255383D01*
G01X252367Y276400D02*
X252117Y276108D01*
X251783Y275942D01*
X251408Y275900D01*
X251075Y275942D01*
X250742Y276150D01*
X250533Y276400D01*
X250492Y276650D01*
X250575Y276942D01*
X250867Y277150D01*
X251158Y277233D01*
X251533D01*
G01X251158D02*
X250908Y277358D01*
X250700Y277567D01*
X250617Y277817D01*
X250700Y278067D01*
X250908Y278275D01*
X251283Y278400D01*
X251658Y278358D01*
X252033Y278192D01*
G01X251750Y266400D02*
Y263900D01*
G01X252708Y266400D02*
X250792D01*
G01X249483Y263900D02*
Y266400D01*
X248483D01*
X248150Y266275D01*
X247900Y265983D01*
X247817Y265650D01*
X247900Y265317D01*
X248108Y265067D01*
X248483Y264942D01*
X249483D01*
G01X245633Y263900D02*
X245550Y264442D01*
X245425Y264900D01*
X245258Y265317D01*
X245050Y265775D01*
X244717Y266400D01*
X246383D01*
G01X243242Y265983D02*
X242992Y266233D01*
X242700Y266358D01*
X242367Y266400D01*
X241950Y266317D01*
X241658Y266108D01*
X241575Y265858D01*
X241617Y265608D01*
X241783Y265400D01*
X242617Y264983D01*
X242992Y264692D01*
X243242Y264275D01*
X243325Y263900D01*
X241575D01*
G01X222750Y265900D02*
Y263400D01*
G01X223708Y265900D02*
X221792D01*
G01X220483Y263400D02*
Y265900D01*
X219483D01*
X219150Y265775D01*
X218900Y265483D01*
X218817Y265150D01*
X218900Y264817D01*
X219108Y264567D01*
X219483Y264442D01*
X220483D01*
G01X217342D02*
X217050Y264733D01*
X216800Y264900D01*
X216467Y264983D01*
X216175Y264900D01*
X215967Y264733D01*
X215800Y264483D01*
X215758Y264192D01*
X215800Y263942D01*
X215967Y263692D01*
X216217Y263483D01*
X216508Y263400D01*
X216842Y263483D01*
X217133Y263733D01*
X217300Y264108D01*
X217342Y264525D01*
X217258Y265067D01*
X217133Y265358D01*
X216925Y265650D01*
X216633Y265858D01*
X216342Y265900D01*
X216050Y265817D01*
X215842Y265608D01*
G01X214242Y264442D02*
X213950Y264733D01*
X213700Y264900D01*
X213367Y264983D01*
X213075Y264900D01*
X212867Y264733D01*
X212700Y264483D01*
X212658Y264192D01*
X212700Y263942D01*
X212867Y263692D01*
X213117Y263483D01*
X213408Y263400D01*
X213742Y263483D01*
X214033Y263733D01*
X214200Y264108D01*
X214242Y264525D01*
X214158Y265067D01*
X214033Y265358D01*
X213825Y265650D01*
X213533Y265858D01*
X213242Y265900D01*
X212950Y265817D01*
X212742Y265608D01*
G01X264250Y266500D02*
Y264000D01*
G01X265208Y266500D02*
X263292D01*
G01X261983Y264000D02*
Y266500D01*
X260983D01*
X260650Y266375D01*
X260400Y266083D01*
X260317Y265750D01*
X260400Y265417D01*
X260608Y265167D01*
X260983Y265042D01*
X261983D01*
G01X258842D02*
X258550Y265333D01*
X258300Y265500D01*
X257967Y265583D01*
X257675Y265500D01*
X257467Y265333D01*
X257300Y265083D01*
X257258Y264792D01*
X257300Y264542D01*
X257467Y264292D01*
X257717Y264083D01*
X258008Y264000D01*
X258342Y264083D01*
X258633Y264333D01*
X258800Y264708D01*
X258842Y265125D01*
X258758Y265667D01*
X258633Y265958D01*
X258425Y266250D01*
X258133Y266458D01*
X257842Y266500D01*
X257550Y266417D01*
X257342Y266208D01*
G01X255867Y264375D02*
X255617Y264167D01*
X255325Y264042D01*
X254950Y264000D01*
X254575Y264083D01*
X254283Y264250D01*
X254075Y264542D01*
X254033Y264875D01*
X254117Y265208D01*
X254325Y265417D01*
X254617Y265583D01*
X254908Y265625D01*
X255200Y265583D01*
X255575Y265417D01*
X255450Y266500D01*
X254325D01*
G01X235250Y273400D02*
Y270900D01*
G01X236208Y273400D02*
X234292D01*
G01X232983Y270900D02*
Y273400D01*
X231983D01*
X231650Y273275D01*
X231400Y272983D01*
X231317Y272650D01*
X231400Y272317D01*
X231608Y272067D01*
X231983Y271942D01*
X232983D01*
G01X229842D02*
X229550Y272233D01*
X229300Y272400D01*
X228967Y272483D01*
X228675Y272400D01*
X228467Y272233D01*
X228300Y271983D01*
X228258Y271692D01*
X228300Y271442D01*
X228467Y271192D01*
X228717Y270983D01*
X229008Y270900D01*
X229342Y270983D01*
X229633Y271233D01*
X229800Y271608D01*
X229842Y272025D01*
X229758Y272567D01*
X229633Y272858D01*
X229425Y273150D01*
X229133Y273358D01*
X228842Y273400D01*
X228550Y273317D01*
X228342Y273108D01*
G01X225950Y273400D02*
X226283Y273317D01*
X226533Y273108D01*
X226700Y272858D01*
X226825Y272525D01*
X226867Y272150D01*
X226825Y271775D01*
X226700Y271442D01*
X226533Y271192D01*
X226283Y270983D01*
X225950Y270900D01*
X225617Y270983D01*
X225367Y271192D01*
X225200Y271442D01*
X225075Y271775D01*
X225033Y272150D01*
X225075Y272525D01*
X225200Y272858D01*
X225367Y273108D01*
X225617Y273317D01*
X225950Y273400D01*
G01X229250Y278400D02*
Y275900D01*
G01X230208Y278400D02*
X228292D01*
G01X226983Y275900D02*
Y278400D01*
X225983D01*
X225650Y278275D01*
X225400Y277983D01*
X225317Y277650D01*
X225400Y277317D01*
X225608Y277067D01*
X225983Y276942D01*
X226983D01*
G01X223967Y276275D02*
X223717Y276067D01*
X223425Y275942D01*
X223050Y275900D01*
X222675Y275983D01*
X222383Y276150D01*
X222175Y276442D01*
X222133Y276775D01*
X222217Y277108D01*
X222425Y277317D01*
X222717Y277483D01*
X223008Y277525D01*
X223300Y277483D01*
X223675Y277317D01*
X223550Y278400D01*
X222425D01*
G01X220033Y275900D02*
X219950Y276442D01*
X219825Y276900D01*
X219658Y277317D01*
X219450Y277775D01*
X219117Y278400D01*
X220783D01*
G01X213750Y270900D02*
Y268400D01*
G01X214708Y270900D02*
X212792D01*
G01X211483Y268400D02*
Y270900D01*
X210483D01*
X210150Y270775D01*
X209900Y270483D01*
X209817Y270150D01*
X209900Y269817D01*
X210108Y269567D01*
X210483Y269442D01*
X211483D01*
G01X208467Y268775D02*
X208217Y268567D01*
X207925Y268442D01*
X207550Y268400D01*
X207175Y268483D01*
X206883Y268650D01*
X206675Y268942D01*
X206633Y269275D01*
X206717Y269608D01*
X206925Y269817D01*
X207217Y269983D01*
X207508Y270025D01*
X207800Y269983D01*
X208175Y269817D01*
X208050Y270900D01*
X206925D01*
G01X205242Y269442D02*
X204950Y269733D01*
X204700Y269900D01*
X204367Y269983D01*
X204075Y269900D01*
X203867Y269733D01*
X203700Y269483D01*
X203658Y269192D01*
X203700Y268942D01*
X203867Y268692D01*
X204117Y268483D01*
X204408Y268400D01*
X204742Y268483D01*
X205033Y268733D01*
X205200Y269108D01*
X205242Y269525D01*
X205158Y270067D01*
X205033Y270358D01*
X204825Y270650D01*
X204533Y270858D01*
X204242Y270900D01*
X203950Y270817D01*
X203742Y270608D01*
G01X236894Y266391D02*
Y263891D01*
G01X237852Y266391D02*
X235936D01*
G01X234627Y263891D02*
Y266391D01*
X233627D01*
X233294Y266266D01*
X233044Y265974D01*
X232961Y265641D01*
X233044Y265308D01*
X233252Y265058D01*
X233627Y264933D01*
X234627D01*
G01X231611Y264266D02*
X231361Y264058D01*
X231069Y263933D01*
X230694Y263891D01*
X230319Y263974D01*
X230027Y264141D01*
X229819Y264433D01*
X229777Y264766D01*
X229861Y265099D01*
X230069Y265308D01*
X230361Y265474D01*
X230652Y265516D01*
X230944Y265474D01*
X231319Y265308D01*
X231194Y266391D01*
X230069D01*
G01X227094Y263891D02*
Y266391D01*
X228636Y264599D01*
X226552D01*
G01X215800Y279900D02*
Y277400D01*
G01X216758Y279900D02*
X214842D01*
G01X213533Y277400D02*
Y279900D01*
X212533D01*
X212200Y279775D01*
X211950Y279483D01*
X211867Y279150D01*
X211950Y278817D01*
X212158Y278567D01*
X212533Y278442D01*
X213533D01*
G01X209600Y277400D02*
Y279900D01*
X210100Y279400D01*
G01Y277400D02*
X209100D01*
G01X206000D02*
Y279900D01*
X207542Y278108D01*
X205458D01*
G01X204192Y278442D02*
X203900Y278733D01*
X203650Y278900D01*
X203317Y278983D01*
X203025Y278900D01*
X202817Y278733D01*
X202650Y278483D01*
X202608Y278192D01*
X202650Y277942D01*
X202817Y277692D01*
X203067Y277483D01*
X203358Y277400D01*
X203692Y277483D01*
X203983Y277733D01*
X204150Y278108D01*
X204192Y278525D01*
X204108Y279067D01*
X203983Y279358D01*
X203775Y279650D01*
X203483Y279858D01*
X203192Y279900D01*
X202900Y279817D01*
X202692Y279608D01*
G01X258800Y282900D02*
Y280400D01*
G01X259758Y282900D02*
X257842D01*
G01X256533Y280400D02*
Y282900D01*
X255533D01*
X255200Y282775D01*
X254950Y282483D01*
X254867Y282150D01*
X254950Y281817D01*
X255158Y281567D01*
X255533Y281442D01*
X256533D01*
G01X252600Y280400D02*
Y282900D01*
X253100Y282400D01*
G01Y280400D02*
X252100D01*
G01X249000D02*
Y282900D01*
X250542Y281108D01*
X248458D01*
G01X245900Y280400D02*
Y282900D01*
X247442Y281108D01*
X245358D01*
G01X246800Y278400D02*
Y275900D01*
G01X247758Y278400D02*
X245842D01*
G01X244533Y275900D02*
Y278400D01*
X243533D01*
X243200Y278275D01*
X242950Y277983D01*
X242867Y277650D01*
X242950Y277317D01*
X243158Y277067D01*
X243533Y276942D01*
X244533D01*
G01X240600Y275900D02*
Y278400D01*
X241100Y277900D01*
G01Y275900D02*
X240100D01*
G01X237500D02*
Y278400D01*
X238000Y277900D01*
G01Y275900D02*
X237000D01*
G01X235317Y276275D02*
X235067Y276067D01*
X234775Y275942D01*
X234400Y275900D01*
X234025Y275983D01*
X233733Y276150D01*
X233525Y276442D01*
X233483Y276775D01*
X233567Y277108D01*
X233775Y277317D01*
X234067Y277483D01*
X234358Y277525D01*
X234650Y277483D01*
X235025Y277317D01*
X234900Y278400D01*
X233775D01*
G01X282000Y293500D02*
Y318500D01*
X237500D01*
Y341500D01*
G01X231523Y318042D02*
X231773Y318167D01*
X232065Y318250D01*
X232398D01*
X232773Y318125D01*
X233065Y317917D01*
X233273Y317667D01*
X233440Y317250D01*
X233482Y316875D01*
X233398Y316500D01*
X233273Y316250D01*
X233023Y316000D01*
X232732Y315833D01*
X232440Y315750D01*
X232148D01*
X231857Y315833D01*
X231607Y315958D01*
X231398Y316125D01*
G01X228840Y315750D02*
Y318250D01*
X230382Y316458D01*
X228298D01*
G01X226948Y316042D02*
X226657Y315833D01*
X226323Y315750D01*
X225990Y315833D01*
X225698Y316083D01*
X225490Y316458D01*
X225407Y316833D01*
Y317292D01*
X225490Y317667D01*
X225698Y318000D01*
X225948Y318167D01*
X226240Y318250D01*
X226573Y318167D01*
X226823Y318000D01*
X226990Y317750D01*
X227073Y317417D01*
X226990Y317125D01*
X226782Y316833D01*
X226532Y316667D01*
X226240Y316625D01*
X225907Y316708D01*
X225657Y316917D01*
X225407Y317292D01*
G01X223140Y315750D02*
Y318250D01*
X223640Y317750D01*
G01Y315750D02*
X222640D01*
G01X231523Y322042D02*
X231773Y322167D01*
X232065Y322250D01*
X232398D01*
X232773Y322125D01*
X233065Y321917D01*
X233273Y321667D01*
X233440Y321250D01*
X233482Y320875D01*
X233398Y320500D01*
X233273Y320250D01*
X233023Y320000D01*
X232732Y319833D01*
X232440Y319750D01*
X232148D01*
X231857Y319833D01*
X231607Y319958D01*
X231398Y320125D01*
G01X228840Y319750D02*
Y322250D01*
X230382Y320458D01*
X228298D01*
G01X226948Y320042D02*
X226657Y319833D01*
X226323Y319750D01*
X225990Y319833D01*
X225698Y320083D01*
X225490Y320458D01*
X225407Y320833D01*
Y321292D01*
X225490Y321667D01*
X225698Y322000D01*
X225948Y322167D01*
X226240Y322250D01*
X226573Y322167D01*
X226823Y322000D01*
X226990Y321750D01*
X227073Y321417D01*
X226990Y321125D01*
X226782Y320833D01*
X226532Y320667D01*
X226240Y320625D01*
X225907Y320708D01*
X225657Y320917D01*
X225407Y321292D01*
G01X223140Y322250D02*
X223473Y322167D01*
X223723Y321958D01*
X223890Y321708D01*
X224015Y321375D01*
X224057Y321000D01*
X224015Y320625D01*
X223890Y320292D01*
X223723Y320042D01*
X223473Y319833D01*
X223140Y319750D01*
X222807Y319833D01*
X222557Y320042D01*
X222390Y320292D01*
X222265Y320625D01*
X222223Y321000D01*
X222265Y321375D01*
X222390Y321708D01*
X222557Y321958D01*
X222807Y322167D01*
X223140Y322250D01*
G01X232023Y328042D02*
X232273Y328167D01*
X232565Y328250D01*
X232898D01*
X233273Y328125D01*
X233565Y327917D01*
X233773Y327667D01*
X233940Y327250D01*
X233982Y326875D01*
X233898Y326500D01*
X233773Y326250D01*
X233523Y326000D01*
X233232Y325833D01*
X232940Y325750D01*
X232648D01*
X232357Y325833D01*
X232107Y325958D01*
X231898Y326125D01*
G01X229340Y325750D02*
Y328250D01*
X230882Y326458D01*
X228798D01*
G01X226740Y325750D02*
X226448Y325792D01*
X226115Y325917D01*
X225907Y326125D01*
X225823Y326417D01*
X225907Y326708D01*
X226157Y326958D01*
X226532Y327083D01*
X226948D01*
X227198Y327167D01*
X227407Y327375D01*
X227490Y327667D01*
X227365Y327958D01*
X227073Y328167D01*
X226740Y328250D01*
X226407Y328167D01*
X226115Y327958D01*
X225990Y327667D01*
X226073Y327375D01*
X226282Y327167D01*
X226532Y327083D01*
X226948D01*
X227323Y326958D01*
X227573Y326708D01*
X227657Y326417D01*
X227573Y326125D01*
X227365Y325917D01*
X227032Y325792D01*
X226740Y325750D01*
G01X224348Y326042D02*
X224057Y325833D01*
X223723Y325750D01*
X223390Y325833D01*
X223098Y326083D01*
X222890Y326458D01*
X222807Y326833D01*
Y327292D01*
X222890Y327667D01*
X223098Y328000D01*
X223348Y328167D01*
X223640Y328250D01*
X223973Y328167D01*
X224223Y328000D01*
X224390Y327750D01*
X224473Y327417D01*
X224390Y327125D01*
X224182Y326833D01*
X223932Y326667D01*
X223640Y326625D01*
X223307Y326708D01*
X223057Y326917D01*
X222807Y327292D01*
G01X219303Y362042D02*
X219553Y362167D01*
X219845Y362250D01*
X220178D01*
X220553Y362125D01*
X220845Y361917D01*
X221053Y361667D01*
X221220Y361250D01*
X221262Y360875D01*
X221178Y360500D01*
X221053Y360250D01*
X220803Y360000D01*
X220512Y359833D01*
X220220Y359750D01*
X219928D01*
X219637Y359833D01*
X219387Y359958D01*
X219178Y360125D01*
G01X216620Y359750D02*
Y362250D01*
X218162Y360458D01*
X216078D01*
G01X214020Y359750D02*
X213728Y359792D01*
X213395Y359917D01*
X213187Y360125D01*
X213103Y360417D01*
X213187Y360708D01*
X213437Y360958D01*
X213812Y361083D01*
X214228D01*
X214478Y361167D01*
X214687Y361375D01*
X214770Y361667D01*
X214645Y361958D01*
X214353Y362167D01*
X214020Y362250D01*
X213687Y362167D01*
X213395Y361958D01*
X213270Y361667D01*
X213353Y361375D01*
X213562Y361167D01*
X213812Y361083D01*
X214228D01*
X214603Y360958D01*
X214853Y360708D01*
X214937Y360417D01*
X214853Y360125D01*
X214645Y359917D01*
X214312Y359792D01*
X214020Y359750D01*
G01X210920D02*
Y362250D01*
X211420Y361750D01*
G01Y359750D02*
X210420D01*
G01X219293Y353542D02*
X219543Y353667D01*
X219835Y353750D01*
X220168D01*
X220543Y353625D01*
X220835Y353417D01*
X221043Y353167D01*
X221210Y352750D01*
X221252Y352375D01*
X221168Y352000D01*
X221043Y351750D01*
X220793Y351500D01*
X220502Y351333D01*
X220210Y351250D01*
X219918D01*
X219627Y351333D01*
X219377Y351458D01*
X219168Y351625D01*
G01X216610Y351250D02*
Y353750D01*
X218152Y351958D01*
X216068D01*
G01X214010Y351250D02*
X213718Y351292D01*
X213385Y351417D01*
X213177Y351625D01*
X213093Y351917D01*
X213177Y352208D01*
X213427Y352458D01*
X213802Y352583D01*
X214218D01*
X214468Y352667D01*
X214677Y352875D01*
X214760Y353167D01*
X214635Y353458D01*
X214343Y353667D01*
X214010Y353750D01*
X213677Y353667D01*
X213385Y353458D01*
X213260Y353167D01*
X213343Y352875D01*
X213552Y352667D01*
X213802Y352583D01*
X214218D01*
X214593Y352458D01*
X214843Y352208D01*
X214927Y351917D01*
X214843Y351625D01*
X214635Y351417D01*
X214302Y351292D01*
X214010Y351250D01*
G01X210910Y353750D02*
X211243Y353667D01*
X211493Y353458D01*
X211660Y353208D01*
X211785Y352875D01*
X211827Y352500D01*
X211785Y352125D01*
X211660Y351792D01*
X211493Y351542D01*
X211243Y351333D01*
X210910Y351250D01*
X210577Y351333D01*
X210327Y351542D01*
X210160Y351792D01*
X210035Y352125D01*
X209993Y352500D01*
X210035Y352875D01*
X210160Y353208D01*
X210327Y353458D01*
X210577Y353667D01*
X210910Y353750D01*
G01X219113Y348042D02*
X219363Y348167D01*
X219655Y348250D01*
X219988D01*
X220363Y348125D01*
X220655Y347917D01*
X220863Y347667D01*
X221030Y347250D01*
X221072Y346875D01*
X220988Y346500D01*
X220863Y346250D01*
X220613Y346000D01*
X220322Y345833D01*
X220030Y345750D01*
X219738D01*
X219447Y345833D01*
X219197Y345958D01*
X218988Y346125D01*
G01X216430Y345750D02*
Y348250D01*
X217972Y346458D01*
X215888D01*
G01X213913Y345750D02*
X213830Y346292D01*
X213705Y346750D01*
X213538Y347167D01*
X213330Y347625D01*
X212997Y348250D01*
X214663D01*
G01X211438Y346042D02*
X211147Y345833D01*
X210813Y345750D01*
X210480Y345833D01*
X210188Y346083D01*
X209980Y346458D01*
X209897Y346833D01*
Y347292D01*
X209980Y347667D01*
X210188Y348000D01*
X210438Y348167D01*
X210730Y348250D01*
X211063Y348167D01*
X211313Y348000D01*
X211480Y347750D01*
X211563Y347417D01*
X211480Y347125D01*
X211272Y346833D01*
X211022Y346667D01*
X210730Y346625D01*
X210397Y346708D01*
X210147Y346917D01*
X209897Y347292D01*
G01X219113Y342042D02*
X219363Y342167D01*
X219655Y342250D01*
X219988D01*
X220363Y342125D01*
X220655Y341917D01*
X220863Y341667D01*
X221030Y341250D01*
X221072Y340875D01*
X220988Y340500D01*
X220863Y340250D01*
X220613Y340000D01*
X220322Y339833D01*
X220030Y339750D01*
X219738D01*
X219447Y339833D01*
X219197Y339958D01*
X218988Y340125D01*
G01X216430Y339750D02*
Y342250D01*
X217972Y340458D01*
X215888D01*
G01X213913Y339750D02*
X213830Y340292D01*
X213705Y340750D01*
X213538Y341167D01*
X213330Y341625D01*
X212997Y342250D01*
X214663D01*
G01X210730Y339750D02*
X210438Y339792D01*
X210105Y339917D01*
X209897Y340125D01*
X209813Y340417D01*
X209897Y340708D01*
X210147Y340958D01*
X210522Y341083D01*
X210938D01*
X211188Y341167D01*
X211397Y341375D01*
X211480Y341667D01*
X211355Y341958D01*
X211063Y342167D01*
X210730Y342250D01*
X210397Y342167D01*
X210105Y341958D01*
X209980Y341667D01*
X210063Y341375D01*
X210272Y341167D01*
X210522Y341083D01*
X210938D01*
X211313Y340958D01*
X211563Y340708D01*
X211647Y340417D01*
X211563Y340125D01*
X211355Y339917D01*
X211022Y339792D01*
X210730Y339750D01*
G01X218833Y337192D02*
X219083Y337317D01*
X219375Y337400D01*
X219708D01*
X220083Y337275D01*
X220375Y337067D01*
X220583Y336817D01*
X220750Y336400D01*
X220792Y336025D01*
X220708Y335650D01*
X220583Y335400D01*
X220333Y335150D01*
X220042Y334983D01*
X219750Y334900D01*
X219458D01*
X219167Y334983D01*
X218917Y335108D01*
X218708Y335275D01*
G01X216150Y334900D02*
Y337400D01*
X217692Y335608D01*
X215608D01*
G01X213633Y334900D02*
X213550Y335442D01*
X213425Y335900D01*
X213258Y336317D01*
X213050Y336775D01*
X212717Y337400D01*
X214383D01*
G01X210533Y334900D02*
X210450Y335442D01*
X210325Y335900D01*
X210158Y336317D01*
X209950Y336775D01*
X209617Y337400D01*
X211283D01*
G01X218665Y328257D02*
X218915Y328382D01*
X219207Y328465D01*
X219540D01*
X219915Y328340D01*
X220207Y328132D01*
X220415Y327882D01*
X220582Y327465D01*
X220624Y327090D01*
X220540Y326715D01*
X220415Y326465D01*
X220165Y326215D01*
X219874Y326048D01*
X219582Y325965D01*
X219290D01*
X218999Y326048D01*
X218749Y326173D01*
X218540Y326340D01*
G01X215982Y325965D02*
Y328465D01*
X217524Y326673D01*
X215440D01*
G01X213465Y325965D02*
X213382Y326507D01*
X213257Y326965D01*
X213090Y327382D01*
X212882Y327840D01*
X212549Y328465D01*
X214215D01*
G01X211074Y327007D02*
X210782Y327298D01*
X210532Y327465D01*
X210199Y327548D01*
X209907Y327465D01*
X209699Y327298D01*
X209532Y327048D01*
X209490Y326757D01*
X209532Y326507D01*
X209699Y326257D01*
X209949Y326048D01*
X210240Y325965D01*
X210574Y326048D01*
X210865Y326298D01*
X211032Y326673D01*
X211074Y327090D01*
X210990Y327632D01*
X210865Y327923D01*
X210657Y328215D01*
X210365Y328423D01*
X210074Y328465D01*
X209782Y328382D01*
X209574Y328173D01*
G01X218113Y322042D02*
X218363Y322167D01*
X218655Y322250D01*
X218988D01*
X219363Y322125D01*
X219655Y321917D01*
X219863Y321667D01*
X220030Y321250D01*
X220072Y320875D01*
X219988Y320500D01*
X219863Y320250D01*
X219613Y320000D01*
X219322Y319833D01*
X219030Y319750D01*
X218738D01*
X218447Y319833D01*
X218197Y319958D01*
X217988Y320125D01*
G01X215430Y319750D02*
Y322250D01*
X216972Y320458D01*
X214888D01*
G01X212913Y319750D02*
X212830Y320292D01*
X212705Y320750D01*
X212538Y321167D01*
X212330Y321625D01*
X211997Y322250D01*
X213663D01*
G01X210647Y320125D02*
X210397Y319917D01*
X210105Y319792D01*
X209730Y319750D01*
X209355Y319833D01*
X209063Y320000D01*
X208855Y320292D01*
X208813Y320625D01*
X208897Y320958D01*
X209105Y321167D01*
X209397Y321333D01*
X209688Y321375D01*
X209980Y321333D01*
X210355Y321167D01*
X210230Y322250D01*
X209105D01*
G01X218023Y318042D02*
X218273Y318167D01*
X218565Y318250D01*
X218898D01*
X219273Y318125D01*
X219565Y317917D01*
X219773Y317667D01*
X219940Y317250D01*
X219982Y316875D01*
X219898Y316500D01*
X219773Y316250D01*
X219523Y316000D01*
X219232Y315833D01*
X218940Y315750D01*
X218648D01*
X218357Y315833D01*
X218107Y315958D01*
X217898Y316125D01*
G01X215340Y315750D02*
Y318250D01*
X216882Y316458D01*
X214798D01*
G01X212823Y315750D02*
X212740Y316292D01*
X212615Y316750D01*
X212448Y317167D01*
X212240Y317625D01*
X211907Y318250D01*
X213573D01*
G01X209140Y315750D02*
Y318250D01*
X210682Y316458D01*
X208598D01*
G01X231833Y308692D02*
X232083Y308817D01*
X232375Y308900D01*
X232708D01*
X233083Y308775D01*
X233375Y308567D01*
X233583Y308317D01*
X233750Y307900D01*
X233792Y307525D01*
X233708Y307150D01*
X233583Y306900D01*
X233333Y306650D01*
X233042Y306483D01*
X232750Y306400D01*
X232458D01*
X232167Y306483D01*
X231917Y306608D01*
X231708Y306775D01*
G01X229150Y306400D02*
Y308900D01*
X230692Y307108D01*
X228608D01*
G01X226633Y306400D02*
X226550Y306942D01*
X226425Y307400D01*
X226258Y307817D01*
X226050Y308275D01*
X225717Y308900D01*
X227383D01*
G01X224367Y306900D02*
X224117Y306608D01*
X223783Y306442D01*
X223408Y306400D01*
X223075Y306442D01*
X222742Y306650D01*
X222533Y306900D01*
X222492Y307150D01*
X222575Y307442D01*
X222867Y307650D01*
X223158Y307733D01*
X223533D01*
G01X223158D02*
X222908Y307858D01*
X222700Y308067D01*
X222617Y308317D01*
X222700Y308567D01*
X222908Y308775D01*
X223283Y308900D01*
X223658Y308858D01*
X224033Y308692D01*
G01X232833Y347692D02*
X233083Y347817D01*
X233375Y347900D01*
X233708D01*
X234083Y347775D01*
X234375Y347567D01*
X234583Y347317D01*
X234750Y346900D01*
X234792Y346525D01*
X234708Y346150D01*
X234583Y345900D01*
X234333Y345650D01*
X234042Y345483D01*
X233750Y345400D01*
X233458D01*
X233167Y345483D01*
X232917Y345608D01*
X232708Y345775D01*
G01X230150Y345400D02*
Y347900D01*
X231692Y346108D01*
X229608D01*
G01X228342Y346442D02*
X228050Y346733D01*
X227800Y346900D01*
X227467Y346983D01*
X227175Y346900D01*
X226967Y346733D01*
X226800Y346483D01*
X226758Y346192D01*
X226800Y345942D01*
X226967Y345692D01*
X227217Y345483D01*
X227508Y345400D01*
X227842Y345483D01*
X228133Y345733D01*
X228300Y346108D01*
X228342Y346525D01*
X228258Y347067D01*
X228133Y347358D01*
X227925Y347650D01*
X227633Y347858D01*
X227342Y347900D01*
X227050Y347817D01*
X226842Y347608D01*
G01X224450Y345400D02*
Y347900D01*
X224950Y347400D01*
G01Y345400D02*
X223950D01*
G01X233333Y342192D02*
X233583Y342317D01*
X233875Y342400D01*
X234208D01*
X234583Y342275D01*
X234875Y342067D01*
X235083Y341817D01*
X235250Y341400D01*
X235292Y341025D01*
X235208Y340650D01*
X235083Y340400D01*
X234833Y340150D01*
X234542Y339983D01*
X234250Y339900D01*
X233958D01*
X233667Y339983D01*
X233417Y340108D01*
X233208Y340275D01*
G01X230650Y339900D02*
Y342400D01*
X232192Y340608D01*
X230108D01*
G01X228967Y340275D02*
X228717Y340067D01*
X228425Y339942D01*
X228050Y339900D01*
X227675Y339983D01*
X227383Y340150D01*
X227175Y340442D01*
X227133Y340775D01*
X227217Y341108D01*
X227425Y341317D01*
X227717Y341483D01*
X228008Y341525D01*
X228300Y341483D01*
X228675Y341317D01*
X228550Y342400D01*
X227425D01*
G01X224950Y339900D02*
X224658Y339942D01*
X224325Y340067D01*
X224117Y340275D01*
X224033Y340567D01*
X224117Y340858D01*
X224367Y341108D01*
X224742Y341233D01*
X225158D01*
X225408Y341317D01*
X225617Y341525D01*
X225700Y341817D01*
X225575Y342108D01*
X225283Y342317D01*
X224950Y342400D01*
X224617Y342317D01*
X224325Y342108D01*
X224200Y341817D01*
X224283Y341525D01*
X224492Y341317D01*
X224742Y341233D01*
X225158D01*
X225533Y341108D01*
X225783Y340858D01*
X225867Y340567D01*
X225783Y340275D01*
X225575Y340067D01*
X225242Y339942D01*
X224950Y339900D01*
G01X234333Y361692D02*
X234583Y361817D01*
X234875Y361900D01*
X235208D01*
X235583Y361775D01*
X235875Y361567D01*
X236083Y361317D01*
X236250Y360900D01*
X236292Y360525D01*
X236208Y360150D01*
X236083Y359900D01*
X235833Y359650D01*
X235542Y359483D01*
X235250Y359400D01*
X234958D01*
X234667Y359483D01*
X234417Y359608D01*
X234208Y359775D01*
G01X231650Y359400D02*
Y361900D01*
X233192Y360108D01*
X231108D01*
G01X229967Y359775D02*
X229717Y359567D01*
X229425Y359442D01*
X229050Y359400D01*
X228675Y359483D01*
X228383Y359650D01*
X228175Y359942D01*
X228133Y360275D01*
X228217Y360608D01*
X228425Y360817D01*
X228717Y360983D01*
X229008Y361025D01*
X229300Y360983D01*
X229675Y360817D01*
X229550Y361900D01*
X228425D01*
G01X226033Y359400D02*
X225950Y359942D01*
X225825Y360400D01*
X225658Y360817D01*
X225450Y361275D01*
X225117Y361900D01*
X226783D01*
G01X233333Y353192D02*
X233583Y353317D01*
X233875Y353400D01*
X234208D01*
X234583Y353275D01*
X234875Y353067D01*
X235083Y352817D01*
X235250Y352400D01*
X235292Y352025D01*
X235208Y351650D01*
X235083Y351400D01*
X234833Y351150D01*
X234542Y350983D01*
X234250Y350900D01*
X233958D01*
X233667Y350983D01*
X233417Y351108D01*
X233208Y351275D01*
G01X230650Y350900D02*
Y353400D01*
X232192Y351608D01*
X230108D01*
G01X228967Y351275D02*
X228717Y351067D01*
X228425Y350942D01*
X228050Y350900D01*
X227675Y350983D01*
X227383Y351150D01*
X227175Y351442D01*
X227133Y351775D01*
X227217Y352108D01*
X227425Y352317D01*
X227717Y352483D01*
X228008Y352525D01*
X228300Y352483D01*
X228675Y352317D01*
X228550Y353400D01*
X227425D01*
G01X224450Y350900D02*
Y353400D01*
X225992Y351608D01*
X223908D01*
G01X206392Y351167D02*
X206517Y350917D01*
X206600Y350625D01*
Y350292D01*
X206475Y349917D01*
X206267Y349625D01*
X206017Y349417D01*
X205600Y349250D01*
X205225Y349208D01*
X204850Y349292D01*
X204600Y349417D01*
X204350Y349667D01*
X204183Y349958D01*
X204100Y350250D01*
Y350542D01*
X204183Y350833D01*
X204308Y351083D01*
X204475Y351292D01*
G01Y352433D02*
X204267Y352683D01*
X204142Y352975D01*
X204100Y353350D01*
X204183Y353725D01*
X204350Y354017D01*
X204642Y354225D01*
X204975Y354267D01*
X205308Y354183D01*
X205517Y353975D01*
X205683Y353683D01*
X205725Y353392D01*
X205683Y353100D01*
X205517Y352725D01*
X206600Y352850D01*
Y353975D01*
G01Y356450D02*
X206517Y356117D01*
X206308Y355867D01*
X206058Y355700D01*
X205725Y355575D01*
X205350Y355533D01*
X204975Y355575D01*
X204642Y355700D01*
X204392Y355867D01*
X204183Y356117D01*
X204100Y356450D01*
X204183Y356783D01*
X204392Y357033D01*
X204642Y357200D01*
X204975Y357325D01*
X205350Y357367D01*
X205725Y357325D01*
X206058Y357200D01*
X206308Y357033D01*
X206517Y356783D01*
X206600Y356450D01*
G01Y359550D02*
X206517Y359217D01*
X206308Y358967D01*
X206058Y358800D01*
X205725Y358675D01*
X205350Y358633D01*
X204975Y358675D01*
X204642Y358800D01*
X204392Y358967D01*
X204183Y359217D01*
X204100Y359550D01*
X204183Y359883D01*
X204392Y360133D01*
X204642Y360300D01*
X204975Y360425D01*
X205350Y360467D01*
X205725Y360425D01*
X206058Y360300D01*
X206308Y360133D01*
X206517Y359883D01*
X206600Y359550D01*
G01X248000Y358517D02*
X250500D01*
Y359558D01*
X250375Y359892D01*
X250208Y360100D01*
X249875Y360183D01*
X249542Y360100D01*
X249333Y359850D01*
X249208Y359558D01*
Y358517D01*
G01Y359558D02*
X248000Y360183D01*
G01Y362950D02*
X250500D01*
X248708Y361408D01*
Y363492D01*
G01X248292Y364842D02*
X248083Y365133D01*
X248000Y365467D01*
X248083Y365800D01*
X248333Y366092D01*
X248708Y366300D01*
X249083Y366383D01*
X249542D01*
X249917Y366300D01*
X250250Y366092D01*
X250417Y365842D01*
X250500Y365550D01*
X250417Y365217D01*
X250250Y364967D01*
X250000Y364800D01*
X249667Y364717D01*
X249375Y364800D01*
X249083Y365008D01*
X248917Y365258D01*
X248875Y365550D01*
X248958Y365883D01*
X249167Y366133D01*
X249542Y366383D01*
G01X248292Y367942D02*
X248083Y368233D01*
X248000Y368567D01*
X248083Y368900D01*
X248333Y369192D01*
X248708Y369400D01*
X249083Y369483D01*
X249542D01*
X249917Y369400D01*
X250250Y369192D01*
X250417Y368942D01*
X250500Y368650D01*
X250417Y368317D01*
X250250Y368067D01*
X250000Y367900D01*
X249667Y367817D01*
X249375Y367900D01*
X249083Y368108D01*
X248917Y368358D01*
X248875Y368650D01*
X248958Y368983D01*
X249167Y369233D01*
X249542Y369483D01*
G01X263250Y311900D02*
Y309400D01*
G01X264208Y311900D02*
X262292D01*
G01X260983Y309400D02*
Y311900D01*
X259983D01*
X259650Y311775D01*
X259400Y311483D01*
X259317Y311150D01*
X259400Y310817D01*
X259608Y310567D01*
X259983Y310442D01*
X260983D01*
G01X257758Y309692D02*
X257467Y309483D01*
X257133Y309400D01*
X256800Y309483D01*
X256508Y309733D01*
X256300Y310108D01*
X256217Y310483D01*
Y310942D01*
X256300Y311317D01*
X256508Y311650D01*
X256758Y311817D01*
X257050Y311900D01*
X257383Y311817D01*
X257633Y311650D01*
X257800Y311400D01*
X257883Y311067D01*
X257800Y310775D01*
X257592Y310483D01*
X257342Y310317D01*
X257050Y310275D01*
X256717Y310358D01*
X256467Y310567D01*
X256217Y310942D01*
G01X253950Y309400D02*
X253658Y309442D01*
X253325Y309567D01*
X253117Y309775D01*
X253033Y310067D01*
X253117Y310358D01*
X253367Y310608D01*
X253742Y310733D01*
X254158D01*
X254408Y310817D01*
X254617Y311025D01*
X254700Y311317D01*
X254575Y311608D01*
X254283Y311817D01*
X253950Y311900D01*
X253617Y311817D01*
X253325Y311608D01*
X253200Y311317D01*
X253283Y311025D01*
X253492Y310817D01*
X253742Y310733D01*
X254158D01*
X254533Y310608D01*
X254783Y310358D01*
X254867Y310067D01*
X254783Y309775D01*
X254575Y309567D01*
X254242Y309442D01*
X253950Y309400D01*
G01X265250Y305400D02*
Y302900D01*
G01X266208Y305400D02*
X264292D01*
G01X262983Y302900D02*
Y305400D01*
X261983D01*
X261650Y305275D01*
X261400Y304983D01*
X261317Y304650D01*
X261400Y304317D01*
X261608Y304067D01*
X261983Y303942D01*
X262983D01*
G01X259758Y303192D02*
X259467Y302983D01*
X259133Y302900D01*
X258800Y302983D01*
X258508Y303233D01*
X258300Y303608D01*
X258217Y303983D01*
Y304442D01*
X258300Y304817D01*
X258508Y305150D01*
X258758Y305317D01*
X259050Y305400D01*
X259383Y305317D01*
X259633Y305150D01*
X259800Y304900D01*
X259883Y304567D01*
X259800Y304275D01*
X259592Y303983D01*
X259342Y303817D01*
X259050Y303775D01*
X258717Y303858D01*
X258467Y304067D01*
X258217Y304442D01*
G01X256867Y303275D02*
X256617Y303067D01*
X256325Y302942D01*
X255950Y302900D01*
X255575Y302983D01*
X255283Y303150D01*
X255075Y303442D01*
X255033Y303775D01*
X255117Y304108D01*
X255325Y304317D01*
X255617Y304483D01*
X255908Y304525D01*
X256200Y304483D01*
X256575Y304317D01*
X256450Y305400D01*
X255325D01*
G01X266300Y317400D02*
Y314900D01*
G01X267258Y317400D02*
X265342D01*
G01X264033Y314900D02*
Y317400D01*
X263033D01*
X262700Y317275D01*
X262450Y316983D01*
X262367Y316650D01*
X262450Y316317D01*
X262658Y316067D01*
X263033Y315942D01*
X264033D01*
G01X260100Y314900D02*
Y317400D01*
X260600Y316900D01*
G01Y314900D02*
X259600D01*
G01X257000Y317400D02*
X257333Y317317D01*
X257583Y317108D01*
X257750Y316858D01*
X257875Y316525D01*
X257917Y316150D01*
X257875Y315775D01*
X257750Y315442D01*
X257583Y315192D01*
X257333Y314983D01*
X257000Y314900D01*
X256667Y314983D01*
X256417Y315192D01*
X256250Y315442D01*
X256125Y315775D01*
X256083Y316150D01*
X256125Y316525D01*
X256250Y316858D01*
X256417Y317108D01*
X256667Y317317D01*
X257000Y317400D01*
G01X253900D02*
X254233Y317317D01*
X254483Y317108D01*
X254650Y316858D01*
X254775Y316525D01*
X254817Y316150D01*
X254775Y315775D01*
X254650Y315442D01*
X254483Y315192D01*
X254233Y314983D01*
X253900Y314900D01*
X253567Y314983D01*
X253317Y315192D01*
X253150Y315442D01*
X253025Y315775D01*
X252983Y316150D01*
X253025Y316525D01*
X253150Y316858D01*
X253317Y317108D01*
X253567Y317317D01*
X253900Y317400D01*
G01X257233Y419959D02*
X257483Y420084D01*
X257775Y420167D01*
X258108D01*
X258483Y420042D01*
X258775Y419834D01*
X258983Y419584D01*
X259150Y419167D01*
X259192Y418792D01*
X259108Y418417D01*
X258983Y418167D01*
X258733Y417917D01*
X258442Y417750D01*
X258150Y417667D01*
X257858D01*
X257567Y417750D01*
X257317Y417875D01*
X257108Y418042D01*
G01X255842Y418709D02*
X255550Y419000D01*
X255300Y419167D01*
X254967Y419250D01*
X254675Y419167D01*
X254467Y419000D01*
X254300Y418750D01*
X254258Y418459D01*
X254300Y418209D01*
X254467Y417959D01*
X254717Y417750D01*
X255008Y417667D01*
X255342Y417750D01*
X255633Y418000D01*
X255800Y418375D01*
X255842Y418792D01*
X255758Y419334D01*
X255633Y419625D01*
X255425Y419917D01*
X255133Y420125D01*
X254842Y420167D01*
X254550Y420084D01*
X254342Y419875D01*
G01X251450Y417667D02*
Y420167D01*
X252992Y418375D01*
X250908D01*
G01X248850Y417667D02*
Y420167D01*
X249350Y419667D01*
G01Y417667D02*
X248350D01*
G01X218833Y366692D02*
X219083Y366817D01*
X219375Y366900D01*
X219708D01*
X220083Y366775D01*
X220375Y366567D01*
X220583Y366317D01*
X220750Y365900D01*
X220792Y365525D01*
X220708Y365150D01*
X220583Y364900D01*
X220333Y364650D01*
X220042Y364483D01*
X219750Y364400D01*
X219458D01*
X219167Y364483D01*
X218917Y364608D01*
X218708Y364775D01*
G01X217567D02*
X217317Y364567D01*
X217025Y364442D01*
X216650Y364400D01*
X216275Y364483D01*
X215983Y364650D01*
X215775Y364942D01*
X215733Y365275D01*
X215817Y365608D01*
X216025Y365817D01*
X216317Y365983D01*
X216608Y366025D01*
X216900Y365983D01*
X217275Y365817D01*
X217150Y366900D01*
X216025D01*
G01X213550D02*
X213883Y366817D01*
X214133Y366608D01*
X214300Y366358D01*
X214425Y366025D01*
X214467Y365650D01*
X214425Y365275D01*
X214300Y364942D01*
X214133Y364692D01*
X213883Y364483D01*
X213550Y364400D01*
X213217Y364483D01*
X212967Y364692D01*
X212800Y364942D01*
X212675Y365275D01*
X212633Y365650D01*
X212675Y366025D01*
X212800Y366358D01*
X212967Y366608D01*
X213217Y366817D01*
X213550Y366900D01*
G01X210450Y364400D02*
Y366900D01*
X210950Y366400D01*
G01Y364400D02*
X209950D01*
G01X234333Y366692D02*
X234583Y366817D01*
X234875Y366900D01*
X235208D01*
X235583Y366775D01*
X235875Y366567D01*
X236083Y366317D01*
X236250Y365900D01*
X236292Y365525D01*
X236208Y365150D01*
X236083Y364900D01*
X235833Y364650D01*
X235542Y364483D01*
X235250Y364400D01*
X234958D01*
X234667Y364483D01*
X234417Y364608D01*
X234208Y364775D01*
G01X231650Y364400D02*
Y366900D01*
X233192Y365108D01*
X231108D01*
G01X229758Y364692D02*
X229467Y364483D01*
X229133Y364400D01*
X228800Y364483D01*
X228508Y364733D01*
X228300Y365108D01*
X228217Y365483D01*
Y365942D01*
X228300Y366317D01*
X228508Y366650D01*
X228758Y366817D01*
X229050Y366900D01*
X229383Y366817D01*
X229633Y366650D01*
X229800Y366400D01*
X229883Y366067D01*
X229800Y365775D01*
X229592Y365483D01*
X229342Y365317D01*
X229050Y365275D01*
X228717Y365358D01*
X228467Y365567D01*
X228217Y365942D01*
G01X226658Y364692D02*
X226367Y364483D01*
X226033Y364400D01*
X225700Y364483D01*
X225408Y364733D01*
X225200Y365108D01*
X225117Y365483D01*
Y365942D01*
X225200Y366317D01*
X225408Y366650D01*
X225658Y366817D01*
X225950Y366900D01*
X226283Y366817D01*
X226533Y366650D01*
X226700Y366400D01*
X226783Y366067D01*
X226700Y365775D01*
X226492Y365483D01*
X226242Y365317D01*
X225950Y365275D01*
X225617Y365358D01*
X225367Y365567D01*
X225117Y365942D01*
G01X249233Y378792D02*
X249483Y378917D01*
X249775Y379000D01*
X250108D01*
X250483Y378875D01*
X250775Y378667D01*
X250983Y378417D01*
X251150Y378000D01*
X251192Y377625D01*
X251108Y377250D01*
X250983Y377000D01*
X250733Y376750D01*
X250442Y376583D01*
X250150Y376500D01*
X249858D01*
X249567Y376583D01*
X249317Y376708D01*
X249108Y376875D01*
G01X247842Y377542D02*
X247550Y377833D01*
X247300Y378000D01*
X246967Y378083D01*
X246675Y378000D01*
X246467Y377833D01*
X246300Y377583D01*
X246258Y377292D01*
X246300Y377042D01*
X246467Y376792D01*
X246717Y376583D01*
X247008Y376500D01*
X247342Y376583D01*
X247633Y376833D01*
X247800Y377208D01*
X247842Y377625D01*
X247758Y378167D01*
X247633Y378458D01*
X247425Y378750D01*
X247133Y378958D01*
X246842Y379000D01*
X246550Y378917D01*
X246342Y378708D01*
G01X244867Y377000D02*
X244617Y376708D01*
X244283Y376542D01*
X243908Y376500D01*
X243575Y376542D01*
X243242Y376750D01*
X243033Y377000D01*
X242992Y377250D01*
X243075Y377542D01*
X243367Y377750D01*
X243658Y377833D01*
X244033D01*
G01X243658D02*
X243408Y377958D01*
X243200Y378167D01*
X243117Y378417D01*
X243200Y378667D01*
X243408Y378875D01*
X243783Y379000D01*
X244158Y378958D01*
X244533Y378792D01*
G01X241558Y376792D02*
X241267Y376583D01*
X240933Y376500D01*
X240600Y376583D01*
X240308Y376833D01*
X240100Y377208D01*
X240017Y377583D01*
Y378042D01*
X240100Y378417D01*
X240308Y378750D01*
X240558Y378917D01*
X240850Y379000D01*
X241183Y378917D01*
X241433Y378750D01*
X241600Y378500D01*
X241683Y378167D01*
X241600Y377875D01*
X241392Y377583D01*
X241142Y377417D01*
X240850Y377375D01*
X240517Y377458D01*
X240267Y377667D01*
X240017Y378042D01*
G01X286953Y64032D02*
X287078Y63782D01*
X287161Y63490D01*
Y63157D01*
X287036Y62782D01*
X286828Y62490D01*
X286578Y62282D01*
X286161Y62115D01*
X285786Y62073D01*
X285411Y62157D01*
X285161Y62282D01*
X284911Y62532D01*
X284744Y62823D01*
X284661Y63115D01*
Y63407D01*
X284744Y63698D01*
X284869Y63948D01*
X285036Y64157D01*
G01X284953Y65507D02*
X284744Y65798D01*
X284661Y66132D01*
X284744Y66465D01*
X284994Y66757D01*
X285369Y66965D01*
X285744Y67048D01*
X286203D01*
X286578Y66965D01*
X286911Y66757D01*
X287078Y66507D01*
X287161Y66215D01*
X287078Y65882D01*
X286911Y65632D01*
X286661Y65465D01*
X286328Y65382D01*
X286036Y65465D01*
X285744Y65673D01*
X285578Y65923D01*
X285536Y66215D01*
X285619Y66548D01*
X285828Y66798D01*
X286203Y67048D01*
G01X284661Y69232D02*
X285203Y69315D01*
X285661Y69440D01*
X286078Y69607D01*
X286536Y69815D01*
X287161Y70148D01*
Y68482D01*
G01X282992Y63635D02*
X283117Y63385D01*
X283200Y63093D01*
Y62760D01*
X283075Y62385D01*
X282867Y62093D01*
X282617Y61885D01*
X282200Y61718D01*
X281825Y61676D01*
X281450Y61760D01*
X281200Y61885D01*
X280950Y62135D01*
X280783Y62426D01*
X280700Y62718D01*
Y63010D01*
X280783Y63301D01*
X280908Y63551D01*
X281075Y63760D01*
G01X280992Y65110D02*
X280783Y65401D01*
X280700Y65735D01*
X280783Y66068D01*
X281033Y66360D01*
X281408Y66568D01*
X281783Y66651D01*
X282242D01*
X282617Y66568D01*
X282950Y66360D01*
X283117Y66110D01*
X283200Y65818D01*
X283117Y65485D01*
X282950Y65235D01*
X282700Y65068D01*
X282367Y64985D01*
X282075Y65068D01*
X281783Y65276D01*
X281617Y65526D01*
X281575Y65818D01*
X281658Y66151D01*
X281867Y66401D01*
X282242Y66651D01*
G01X280700Y68918D02*
X280742Y69210D01*
X280867Y69543D01*
X281075Y69751D01*
X281367Y69835D01*
X281658Y69751D01*
X281908Y69501D01*
X282033Y69126D01*
Y68710D01*
X282117Y68460D01*
X282325Y68251D01*
X282617Y68168D01*
X282908Y68293D01*
X283117Y68585D01*
X283200Y68918D01*
X283117Y69251D01*
X282908Y69543D01*
X282617Y69668D01*
X282325Y69585D01*
X282117Y69376D01*
X282033Y69126D01*
Y68710D01*
X281908Y68335D01*
X281658Y68085D01*
X281367Y68001D01*
X281075Y68085D01*
X280867Y68293D01*
X280742Y68626D01*
X280700Y68918D01*
G01X270800Y160000D02*
Y153000D01*
X284200D01*
Y160000D01*
X270800D01*
G01Y151000D02*
Y144000D01*
X284200D01*
Y151000D01*
X270800D01*
G01X297292Y136267D02*
X297417Y136017D01*
X297500Y135725D01*
Y135392D01*
X297375Y135017D01*
X297167Y134725D01*
X296917Y134517D01*
X296500Y134350D01*
X296125Y134308D01*
X295750Y134392D01*
X295500Y134517D01*
X295250Y134767D01*
X295083Y135058D01*
X295000Y135350D01*
Y135642D01*
X295083Y135933D01*
X295208Y136183D01*
X295375Y136392D01*
G01X297083Y137658D02*
X297333Y137908D01*
X297458Y138200D01*
X297500Y138533D01*
X297417Y138950D01*
X297208Y139242D01*
X296958Y139325D01*
X296708Y139283D01*
X296500Y139117D01*
X296083Y138283D01*
X295792Y137908D01*
X295375Y137658D01*
X295000Y137575D01*
Y139325D01*
G01X297083Y140758D02*
X297333Y141008D01*
X297458Y141300D01*
X297500Y141633D01*
X297417Y142050D01*
X297208Y142342D01*
X296958Y142425D01*
X296708Y142383D01*
X296500Y142217D01*
X296083Y141383D01*
X295792Y141008D01*
X295375Y140758D01*
X295000Y140675D01*
Y142425D01*
G01Y144567D02*
X295542Y144650D01*
X296000Y144775D01*
X296417Y144942D01*
X296875Y145150D01*
X297500Y145483D01*
Y143817D01*
G01X286000Y150800D02*
Y145300D01*
G01X294000Y150800D02*
X286000D01*
G01X294000Y145300D02*
Y150800D01*
G01Y133200D02*
Y138700D01*
G01X286000Y133200D02*
X294000D01*
G01X286000Y138700D02*
Y133200D01*
G01X294000Y175200D02*
Y180700D01*
G01X286000Y175200D02*
X294000D01*
G01X286000Y180700D02*
Y175200D01*
G01X297459Y158467D02*
X297584Y158217D01*
X297667Y157925D01*
Y157592D01*
X297542Y157217D01*
X297334Y156925D01*
X297084Y156717D01*
X296667Y156550D01*
X296292Y156508D01*
X295917Y156592D01*
X295667Y156717D01*
X295417Y156967D01*
X295250Y157258D01*
X295167Y157550D01*
Y157842D01*
X295250Y158133D01*
X295375Y158383D01*
X295542Y158592D01*
G01X295667Y159733D02*
X295375Y159983D01*
X295209Y160317D01*
X295167Y160692D01*
X295209Y161025D01*
X295417Y161358D01*
X295667Y161567D01*
X295917Y161608D01*
X296209Y161525D01*
X296417Y161233D01*
X296500Y160942D01*
Y160567D01*
G01Y160942D02*
X296625Y161192D01*
X296834Y161400D01*
X297084Y161483D01*
X297334Y161400D01*
X297542Y161192D01*
X297667Y160817D01*
X297625Y160442D01*
X297459Y160067D01*
G01X297667Y163750D02*
X297584Y163417D01*
X297375Y163167D01*
X297125Y163000D01*
X296792Y162875D01*
X296417Y162833D01*
X296042Y162875D01*
X295709Y163000D01*
X295459Y163167D01*
X295250Y163417D01*
X295167Y163750D01*
X295250Y164083D01*
X295459Y164333D01*
X295709Y164500D01*
X296042Y164625D01*
X296417Y164667D01*
X296792Y164625D01*
X297125Y164500D01*
X297375Y164333D01*
X297584Y164083D01*
X297667Y163750D01*
G01X295542Y165933D02*
X295334Y166183D01*
X295209Y166475D01*
X295167Y166850D01*
X295250Y167225D01*
X295417Y167517D01*
X295709Y167725D01*
X296042Y167767D01*
X296375Y167683D01*
X296584Y167475D01*
X296750Y167183D01*
X296792Y166892D01*
X296750Y166600D01*
X296584Y166225D01*
X297667Y166350D01*
Y167475D01*
G01X294000Y153200D02*
Y158700D01*
G01X286000Y153200D02*
X294000D01*
G01X286000Y158700D02*
Y153200D01*
G01Y170800D02*
Y165300D01*
G01X294000Y170800D02*
X286000D01*
G01X294000Y165300D02*
Y170800D01*
G01X305792Y137267D02*
X305917Y137017D01*
X306000Y136725D01*
Y136392D01*
X305875Y136017D01*
X305667Y135725D01*
X305417Y135517D01*
X305000Y135350D01*
X304625Y135308D01*
X304250Y135392D01*
X304000Y135517D01*
X303750Y135767D01*
X303583Y136058D01*
X303500Y136350D01*
Y136642D01*
X303583Y136933D01*
X303708Y137183D01*
X303875Y137392D01*
G01X305583Y138658D02*
X305833Y138908D01*
X305958Y139200D01*
X306000Y139533D01*
X305917Y139950D01*
X305708Y140242D01*
X305458Y140325D01*
X305208Y140283D01*
X305000Y140117D01*
X304583Y139283D01*
X304292Y138908D01*
X303875Y138658D01*
X303500Y138575D01*
Y140325D01*
G01X305583Y141758D02*
X305833Y142008D01*
X305958Y142300D01*
X306000Y142633D01*
X305917Y143050D01*
X305708Y143342D01*
X305458Y143425D01*
X305208Y143383D01*
X305000Y143217D01*
X304583Y142383D01*
X304292Y142008D01*
X303875Y141758D01*
X303500Y141675D01*
Y143425D01*
G01Y145650D02*
X303542Y145942D01*
X303667Y146275D01*
X303875Y146483D01*
X304167Y146567D01*
X304458Y146483D01*
X304708Y146233D01*
X304833Y145858D01*
Y145442D01*
X304917Y145192D01*
X305125Y144983D01*
X305417Y144900D01*
X305708Y145025D01*
X305917Y145317D01*
X306000Y145650D01*
X305917Y145983D01*
X305708Y146275D01*
X305417Y146400D01*
X305125Y146317D01*
X304917Y146108D01*
X304833Y145858D01*
Y145442D01*
X304708Y145067D01*
X304458Y144817D01*
X304167Y144733D01*
X303875Y144817D01*
X303667Y145025D01*
X303542Y145358D01*
X303500Y145650D01*
G01X306959Y160767D02*
X307084Y160517D01*
X307167Y160225D01*
Y159892D01*
X307042Y159517D01*
X306834Y159225D01*
X306584Y159017D01*
X306167Y158850D01*
X305792Y158808D01*
X305417Y158892D01*
X305167Y159017D01*
X304917Y159267D01*
X304750Y159558D01*
X304667Y159850D01*
Y160142D01*
X304750Y160433D01*
X304875Y160683D01*
X305042Y160892D01*
G01X305167Y162033D02*
X304875Y162283D01*
X304709Y162617D01*
X304667Y162992D01*
X304709Y163325D01*
X304917Y163658D01*
X305167Y163867D01*
X305417Y163908D01*
X305709Y163825D01*
X305917Y163533D01*
X306000Y163242D01*
Y162867D01*
G01Y163242D02*
X306125Y163492D01*
X306334Y163700D01*
X306584Y163783D01*
X306834Y163700D01*
X307042Y163492D01*
X307167Y163117D01*
X307125Y162742D01*
X306959Y162367D01*
G01X304667Y166050D02*
X307167D01*
X306667Y165550D01*
G01X304667D02*
Y166550D01*
G01X307167Y169150D02*
X307084Y168817D01*
X306875Y168567D01*
X306625Y168400D01*
X306292Y168275D01*
X305917Y168233D01*
X305542Y168275D01*
X305209Y168400D01*
X304959Y168567D01*
X304750Y168817D01*
X304667Y169150D01*
X304750Y169483D01*
X304959Y169733D01*
X305209Y169900D01*
X305542Y170025D01*
X305917Y170067D01*
X306292Y170025D01*
X306625Y169900D01*
X306875Y169733D01*
X307084Y169483D01*
X307167Y169150D01*
G01X270800Y234500D02*
Y227500D01*
X284200D01*
Y234500D01*
X270800D01*
G01Y193000D02*
Y186000D01*
X284200D01*
Y193000D01*
X270800D01*
G01Y243000D02*
Y236000D01*
X284200D01*
Y243000D01*
X270800D01*
G01Y201500D02*
Y194500D01*
X284200D01*
Y201500D01*
X270800D01*
G01X294000Y236200D02*
Y241700D01*
G01X286000Y236200D02*
X294000D01*
G01X286000Y241700D02*
Y236200D01*
G01X296959Y199967D02*
X297084Y199717D01*
X297167Y199425D01*
Y199092D01*
X297042Y198717D01*
X296834Y198425D01*
X296584Y198217D01*
X296167Y198050D01*
X295792Y198008D01*
X295417Y198092D01*
X295167Y198217D01*
X294917Y198467D01*
X294750Y198758D01*
X294667Y199050D01*
Y199342D01*
X294750Y199633D01*
X294875Y199883D01*
X295042Y200092D01*
G01X296750Y201358D02*
X297000Y201608D01*
X297125Y201900D01*
X297167Y202233D01*
X297084Y202650D01*
X296875Y202942D01*
X296625Y203025D01*
X296375Y202983D01*
X296167Y202817D01*
X295750Y201983D01*
X295459Y201608D01*
X295042Y201358D01*
X294667Y201275D01*
Y203025D01*
G01Y205750D02*
X297167D01*
X295375Y204208D01*
Y206292D01*
G01X294667Y208350D02*
X297167D01*
X296667Y207850D01*
G01X294667D02*
Y208850D01*
G01X294000Y194700D02*
Y200200D01*
G01X286000Y194700D02*
X294000D01*
G01X286000Y200200D02*
Y194700D01*
G01Y212300D02*
Y206800D01*
G01X294000Y212300D02*
X286000D01*
G01X294000Y206800D02*
Y212300D01*
G01X297459Y220267D02*
X297584Y220017D01*
X297667Y219725D01*
Y219392D01*
X297542Y219017D01*
X297334Y218725D01*
X297084Y218517D01*
X296667Y218350D01*
X296292Y218308D01*
X295917Y218392D01*
X295667Y218517D01*
X295417Y218767D01*
X295250Y219058D01*
X295167Y219350D01*
Y219642D01*
X295250Y219933D01*
X295375Y220183D01*
X295542Y220392D01*
G01X297250Y221658D02*
X297500Y221908D01*
X297625Y222200D01*
X297667Y222533D01*
X297584Y222950D01*
X297375Y223242D01*
X297125Y223325D01*
X296875Y223283D01*
X296667Y223117D01*
X296250Y222283D01*
X295959Y221908D01*
X295542Y221658D01*
X295167Y221575D01*
Y223325D01*
G01Y226050D02*
X297667D01*
X295875Y224508D01*
Y226592D01*
G01X295167Y228650D02*
X295209Y228942D01*
X295334Y229275D01*
X295542Y229483D01*
X295834Y229567D01*
X296125Y229483D01*
X296375Y229233D01*
X296500Y228858D01*
Y228442D01*
X296584Y228192D01*
X296792Y227983D01*
X297084Y227900D01*
X297375Y228025D01*
X297584Y228317D01*
X297667Y228650D01*
X297584Y228983D01*
X297375Y229275D01*
X297084Y229400D01*
X296792Y229317D01*
X296584Y229108D01*
X296500Y228858D01*
Y228442D01*
X296375Y228067D01*
X296125Y227817D01*
X295834Y227733D01*
X295542Y227817D01*
X295334Y228025D01*
X295209Y228358D01*
X295167Y228650D01*
G01X286000Y234300D02*
Y228800D01*
G01X294000Y234300D02*
X286000D01*
G01X294000Y228800D02*
Y234300D01*
G01Y216700D02*
Y222200D01*
G01X286000Y216700D02*
X294000D01*
G01X286000Y222200D02*
Y216700D01*
G01X297459Y178267D02*
X297584Y178017D01*
X297667Y177725D01*
Y177392D01*
X297542Y177017D01*
X297334Y176725D01*
X297084Y176517D01*
X296667Y176350D01*
X296292Y176308D01*
X295917Y176392D01*
X295667Y176517D01*
X295417Y176767D01*
X295250Y177058D01*
X295167Y177350D01*
Y177642D01*
X295250Y177933D01*
X295375Y178183D01*
X295542Y178392D01*
G01X297250Y179658D02*
X297500Y179908D01*
X297625Y180200D01*
X297667Y180533D01*
X297584Y180950D01*
X297375Y181242D01*
X297125Y181325D01*
X296875Y181283D01*
X296667Y181117D01*
X296250Y180283D01*
X295959Y179908D01*
X295542Y179658D01*
X295167Y179575D01*
Y181325D01*
G01X295459Y182842D02*
X295250Y183133D01*
X295167Y183467D01*
X295250Y183800D01*
X295500Y184092D01*
X295875Y184300D01*
X296250Y184383D01*
X296709D01*
X297084Y184300D01*
X297417Y184092D01*
X297584Y183842D01*
X297667Y183550D01*
X297584Y183217D01*
X297417Y182967D01*
X297167Y182800D01*
X296834Y182717D01*
X296542Y182800D01*
X296250Y183008D01*
X296084Y183258D01*
X296042Y183550D01*
X296125Y183883D01*
X296334Y184133D01*
X296709Y184383D01*
G01X295167Y186650D02*
X295209Y186942D01*
X295334Y187275D01*
X295542Y187483D01*
X295834Y187567D01*
X296125Y187483D01*
X296375Y187233D01*
X296500Y186858D01*
Y186442D01*
X296584Y186192D01*
X296792Y185983D01*
X297084Y185900D01*
X297375Y186025D01*
X297584Y186317D01*
X297667Y186650D01*
X297584Y186983D01*
X297375Y187275D01*
X297084Y187400D01*
X296792Y187317D01*
X296584Y187108D01*
X296500Y186858D01*
Y186442D01*
X296375Y186067D01*
X296125Y185817D01*
X295834Y185733D01*
X295542Y185817D01*
X295334Y186025D01*
X295209Y186358D01*
X295167Y186650D01*
G01X286000Y192800D02*
Y187300D01*
G01X294000Y192800D02*
X286000D01*
G01X294000Y187300D02*
Y192800D01*
G01X305959Y198767D02*
X306084Y198517D01*
X306167Y198225D01*
Y197892D01*
X306042Y197517D01*
X305834Y197225D01*
X305584Y197017D01*
X305167Y196850D01*
X304792Y196808D01*
X304417Y196892D01*
X304167Y197017D01*
X303917Y197267D01*
X303750Y197558D01*
X303667Y197850D01*
Y198142D01*
X303750Y198433D01*
X303875Y198683D01*
X304042Y198892D01*
G01X305750Y200158D02*
X306000Y200408D01*
X306125Y200700D01*
X306167Y201033D01*
X306084Y201450D01*
X305875Y201742D01*
X305625Y201825D01*
X305375Y201783D01*
X305167Y201617D01*
X304750Y200783D01*
X304459Y200408D01*
X304042Y200158D01*
X303667Y200075D01*
Y201825D01*
G01Y204550D02*
X306167D01*
X304375Y203008D01*
Y205092D01*
G01X305750Y206358D02*
X306000Y206608D01*
X306125Y206900D01*
X306167Y207233D01*
X306084Y207650D01*
X305875Y207942D01*
X305625Y208025D01*
X305375Y207983D01*
X305167Y207817D01*
X304750Y206983D01*
X304459Y206608D01*
X304042Y206358D01*
X303667Y206275D01*
Y208025D01*
G01X306959Y222267D02*
X307084Y222017D01*
X307167Y221725D01*
Y221392D01*
X307042Y221017D01*
X306834Y220725D01*
X306584Y220517D01*
X306167Y220350D01*
X305792Y220308D01*
X305417Y220392D01*
X305167Y220517D01*
X304917Y220767D01*
X304750Y221058D01*
X304667Y221350D01*
Y221642D01*
X304750Y221933D01*
X304875Y222183D01*
X305042Y222392D01*
G01X306750Y223658D02*
X307000Y223908D01*
X307125Y224200D01*
X307167Y224533D01*
X307084Y224950D01*
X306875Y225242D01*
X306625Y225325D01*
X306375Y225283D01*
X306167Y225117D01*
X305750Y224283D01*
X305459Y223908D01*
X305042Y223658D01*
X304667Y223575D01*
Y225325D01*
G01Y228050D02*
X307167D01*
X305375Y226508D01*
Y228592D01*
G01X304959Y229942D02*
X304750Y230233D01*
X304667Y230567D01*
X304750Y230900D01*
X305000Y231192D01*
X305375Y231400D01*
X305750Y231483D01*
X306209D01*
X306584Y231400D01*
X306917Y231192D01*
X307084Y230942D01*
X307167Y230650D01*
X307084Y230317D01*
X306917Y230067D01*
X306667Y229900D01*
X306334Y229817D01*
X306042Y229900D01*
X305750Y230108D01*
X305584Y230358D01*
X305542Y230650D01*
X305625Y230983D01*
X305834Y231233D01*
X306209Y231483D01*
G01X305959Y179767D02*
X306084Y179517D01*
X306167Y179225D01*
Y178892D01*
X306042Y178517D01*
X305834Y178225D01*
X305584Y178017D01*
X305167Y177850D01*
X304792Y177808D01*
X304417Y177892D01*
X304167Y178017D01*
X303917Y178267D01*
X303750Y178558D01*
X303667Y178850D01*
Y179142D01*
X303750Y179433D01*
X303875Y179683D01*
X304042Y179892D01*
G01X304167Y181033D02*
X303875Y181283D01*
X303709Y181617D01*
X303667Y181992D01*
X303709Y182325D01*
X303917Y182658D01*
X304167Y182867D01*
X304417Y182908D01*
X304709Y182825D01*
X304917Y182533D01*
X305000Y182242D01*
Y181867D01*
G01Y182242D02*
X305125Y182492D01*
X305334Y182700D01*
X305584Y182783D01*
X305834Y182700D01*
X306042Y182492D01*
X306167Y182117D01*
X306125Y181742D01*
X305959Y181367D01*
G01X306167Y185050D02*
X306084Y184717D01*
X305875Y184467D01*
X305625Y184300D01*
X305292Y184175D01*
X304917Y184133D01*
X304542Y184175D01*
X304209Y184300D01*
X303959Y184467D01*
X303750Y184717D01*
X303667Y185050D01*
X303750Y185383D01*
X303959Y185633D01*
X304209Y185800D01*
X304542Y185925D01*
X304917Y185967D01*
X305292Y185925D01*
X305625Y185800D01*
X305875Y185633D01*
X306084Y185383D01*
X306167Y185050D01*
G01X304167Y187233D02*
X303875Y187483D01*
X303709Y187817D01*
X303667Y188192D01*
X303709Y188525D01*
X303917Y188858D01*
X304167Y189067D01*
X304417Y189108D01*
X304709Y189025D01*
X304917Y188733D01*
X305000Y188442D01*
Y188067D01*
G01Y188442D02*
X305125Y188692D01*
X305334Y188900D01*
X305584Y188983D01*
X305834Y188900D01*
X306042Y188692D01*
X306167Y188317D01*
X306125Y187942D01*
X305959Y187567D01*
G01X298000Y281017D02*
X300500D01*
Y282058D01*
X300375Y282392D01*
X300208Y282600D01*
X299875Y282683D01*
X299542Y282600D01*
X299333Y282350D01*
X299208Y282058D01*
Y281017D01*
G01Y282058D02*
X298000Y282683D01*
G01X300083Y284158D02*
X300333Y284408D01*
X300458Y284700D01*
X300500Y285033D01*
X300417Y285450D01*
X300208Y285742D01*
X299958Y285825D01*
X299708Y285783D01*
X299500Y285617D01*
X299083Y284783D01*
X298792Y284408D01*
X298375Y284158D01*
X298000Y284075D01*
Y285825D01*
G01Y288050D02*
X298042Y288342D01*
X298167Y288675D01*
X298375Y288883D01*
X298667Y288967D01*
X298958Y288883D01*
X299208Y288633D01*
X299333Y288258D01*
Y287842D01*
X299417Y287592D01*
X299625Y287383D01*
X299917Y287300D01*
X300208Y287425D01*
X300417Y287717D01*
X300500Y288050D01*
X300417Y288383D01*
X300208Y288675D01*
X299917Y288800D01*
X299625Y288717D01*
X299417Y288508D01*
X299333Y288258D01*
Y287842D01*
X299208Y287467D01*
X298958Y287217D01*
X298667Y287133D01*
X298375Y287217D01*
X298167Y287425D01*
X298042Y287758D01*
X298000Y288050D01*
G01Y291067D02*
X298542Y291150D01*
X299000Y291275D01*
X299417Y291442D01*
X299875Y291650D01*
X300500Y291983D01*
Y290317D01*
G01X289500Y284300D02*
X285500D01*
Y291700D01*
G01X291500Y281017D02*
X294000D01*
Y282058D01*
X293875Y282392D01*
X293708Y282600D01*
X293375Y282683D01*
X293042Y282600D01*
X292833Y282350D01*
X292708Y282058D01*
Y281017D01*
G01Y282058D02*
X291500Y282683D01*
G01X293583Y284158D02*
X293833Y284408D01*
X293958Y284700D01*
X294000Y285033D01*
X293917Y285450D01*
X293708Y285742D01*
X293458Y285825D01*
X293208Y285783D01*
X293000Y285617D01*
X292583Y284783D01*
X292292Y284408D01*
X291875Y284158D01*
X291500Y284075D01*
Y285825D01*
G01Y288550D02*
X294000D01*
X292208Y287008D01*
Y289092D01*
G01X292542Y290358D02*
X292833Y290650D01*
X293000Y290900D01*
X293083Y291233D01*
X293000Y291525D01*
X292833Y291733D01*
X292583Y291900D01*
X292292Y291942D01*
X292042Y291900D01*
X291792Y291733D01*
X291583Y291483D01*
X291500Y291192D01*
X291583Y290858D01*
X291833Y290567D01*
X292208Y290400D01*
X292625Y290358D01*
X293167Y290442D01*
X293458Y290567D01*
X293750Y290775D01*
X293958Y291067D01*
X294000Y291358D01*
X293917Y291650D01*
X293708Y291858D01*
G01X281000Y291700D02*
X285000D01*
Y284300D01*
G01X318233Y287792D02*
X318483Y287917D01*
X318775Y288000D01*
X319108D01*
X319483Y287875D01*
X319775Y287667D01*
X319983Y287417D01*
X320150Y287000D01*
X320192Y286625D01*
X320108Y286250D01*
X319983Y286000D01*
X319733Y285750D01*
X319442Y285583D01*
X319150Y285500D01*
X318858D01*
X318567Y285583D01*
X318317Y285708D01*
X318108Y285875D01*
G01X316050Y285500D02*
Y288000D01*
X316550Y287500D01*
G01Y285500D02*
X315550D01*
G01X312950D02*
Y288000D01*
X313450Y287500D01*
G01Y285500D02*
X312450D01*
G01X309933D02*
X309850Y286042D01*
X309725Y286500D01*
X309558Y286917D01*
X309350Y287375D01*
X309017Y288000D01*
X310683D01*
G01X311579Y270937D02*
X311704Y270687D01*
X311787Y270395D01*
Y270062D01*
X311662Y269687D01*
X311454Y269395D01*
X311204Y269187D01*
X310787Y269020D01*
X310412Y268978D01*
X310037Y269062D01*
X309787Y269187D01*
X309537Y269437D01*
X309370Y269728D01*
X309287Y270020D01*
Y270312D01*
X309370Y270603D01*
X309495Y270853D01*
X309662Y271062D01*
G01Y272203D02*
X309454Y272453D01*
X309329Y272745D01*
X309287Y273120D01*
X309370Y273495D01*
X309537Y273787D01*
X309829Y273995D01*
X310162Y274037D01*
X310495Y273953D01*
X310704Y273745D01*
X310870Y273453D01*
X310912Y273162D01*
X310870Y272870D01*
X310704Y272495D01*
X311787Y272620D01*
Y273745D01*
G01X309287Y276220D02*
X311787D01*
X311287Y275720D01*
G01X309287D02*
Y276720D01*
G01X310329Y278528D02*
X310620Y278820D01*
X310787Y279070D01*
X310870Y279403D01*
X310787Y279695D01*
X310620Y279903D01*
X310370Y280070D01*
X310079Y280112D01*
X309829Y280070D01*
X309579Y279903D01*
X309370Y279653D01*
X309287Y279362D01*
X309370Y279028D01*
X309620Y278737D01*
X309995Y278570D01*
X310412Y278528D01*
X310954Y278612D01*
X311245Y278737D01*
X311537Y278945D01*
X311745Y279237D01*
X311787Y279528D01*
X311704Y279820D01*
X311495Y280028D01*
G01X315792Y270767D02*
X315917Y270517D01*
X316000Y270225D01*
Y269892D01*
X315875Y269517D01*
X315667Y269225D01*
X315417Y269017D01*
X315000Y268850D01*
X314625Y268808D01*
X314250Y268892D01*
X314000Y269017D01*
X313750Y269267D01*
X313583Y269558D01*
X313500Y269850D01*
Y270142D01*
X313583Y270433D01*
X313708Y270683D01*
X313875Y270892D01*
G01Y272033D02*
X313667Y272283D01*
X313542Y272575D01*
X313500Y272950D01*
X313583Y273325D01*
X313750Y273617D01*
X314042Y273825D01*
X314375Y273867D01*
X314708Y273783D01*
X314917Y273575D01*
X315083Y273283D01*
X315125Y272992D01*
X315083Y272700D01*
X314917Y272325D01*
X316000Y272450D01*
Y273575D01*
G01X313500Y276050D02*
X316000D01*
X315500Y275550D01*
G01X313500D02*
Y276550D01*
G01X313875Y278233D02*
X313667Y278483D01*
X313542Y278775D01*
X313500Y279150D01*
X313583Y279525D01*
X313750Y279817D01*
X314042Y280025D01*
X314375Y280067D01*
X314708Y279983D01*
X314917Y279775D01*
X315083Y279483D01*
X315125Y279192D01*
X315083Y278900D01*
X314917Y278525D01*
X316000Y278650D01*
Y279775D01*
G01X297459Y243267D02*
X297584Y243017D01*
X297667Y242725D01*
Y242392D01*
X297542Y242017D01*
X297334Y241725D01*
X297084Y241517D01*
X296667Y241350D01*
X296292Y241308D01*
X295917Y241392D01*
X295667Y241517D01*
X295417Y241767D01*
X295250Y242058D01*
X295167Y242350D01*
Y242642D01*
X295250Y242933D01*
X295375Y243183D01*
X295542Y243392D01*
G01X297250Y244658D02*
X297500Y244908D01*
X297625Y245200D01*
X297667Y245533D01*
X297584Y245950D01*
X297375Y246242D01*
X297125Y246325D01*
X296875Y246283D01*
X296667Y246117D01*
X296250Y245283D01*
X295959Y244908D01*
X295542Y244658D01*
X295167Y244575D01*
Y246325D01*
G01X295667Y247633D02*
X295375Y247883D01*
X295209Y248217D01*
X295167Y248592D01*
X295209Y248925D01*
X295417Y249258D01*
X295667Y249467D01*
X295917Y249508D01*
X296209Y249425D01*
X296417Y249133D01*
X296500Y248842D01*
Y248467D01*
G01Y248842D02*
X296625Y249092D01*
X296834Y249300D01*
X297084Y249383D01*
X297334Y249300D01*
X297542Y249092D01*
X297667Y248717D01*
X297625Y248342D01*
X297459Y247967D01*
G01X295167Y252150D02*
X297667D01*
X295875Y250608D01*
Y252692D01*
G01X286000Y253800D02*
Y248300D01*
G01X294000Y253800D02*
X286000D01*
G01X294000Y248300D02*
Y253800D01*
G01X305959Y242267D02*
X306084Y242017D01*
X306167Y241725D01*
Y241392D01*
X306042Y241017D01*
X305834Y240725D01*
X305584Y240517D01*
X305167Y240350D01*
X304792Y240308D01*
X304417Y240392D01*
X304167Y240517D01*
X303917Y240767D01*
X303750Y241058D01*
X303667Y241350D01*
Y241642D01*
X303750Y241933D01*
X303875Y242183D01*
X304042Y242392D01*
G01X305750Y243658D02*
X306000Y243908D01*
X306125Y244200D01*
X306167Y244533D01*
X306084Y244950D01*
X305875Y245242D01*
X305625Y245325D01*
X305375Y245283D01*
X305167Y245117D01*
X304750Y244283D01*
X304459Y243908D01*
X304042Y243658D01*
X303667Y243575D01*
Y245325D01*
G01X304167Y246633D02*
X303875Y246883D01*
X303709Y247217D01*
X303667Y247592D01*
X303709Y247925D01*
X303917Y248258D01*
X304167Y248467D01*
X304417Y248508D01*
X304709Y248425D01*
X304917Y248133D01*
X305000Y247842D01*
Y247467D01*
G01Y247842D02*
X305125Y248092D01*
X305334Y248300D01*
X305584Y248383D01*
X305834Y248300D01*
X306042Y248092D01*
X306167Y247717D01*
X306125Y247342D01*
X305959Y246967D01*
G01X304042Y249733D02*
X303834Y249983D01*
X303709Y250275D01*
X303667Y250650D01*
X303750Y251025D01*
X303917Y251317D01*
X304209Y251525D01*
X304542Y251567D01*
X304875Y251483D01*
X305084Y251275D01*
X305250Y250983D01*
X305292Y250692D01*
X305250Y250400D01*
X305084Y250025D01*
X306167Y250150D01*
Y251275D01*
G01X275250Y298400D02*
Y295900D01*
G01X276208Y298400D02*
X274292D01*
G01X272983Y295900D02*
Y298400D01*
X271983D01*
X271650Y298275D01*
X271400Y297983D01*
X271317Y297650D01*
X271400Y297317D01*
X271608Y297067D01*
X271983Y296942D01*
X272983D01*
G01X269050Y295900D02*
X268758Y295942D01*
X268425Y296067D01*
X268217Y296275D01*
X268133Y296567D01*
X268217Y296858D01*
X268467Y297108D01*
X268842Y297233D01*
X269258D01*
X269508Y297317D01*
X269717Y297525D01*
X269800Y297817D01*
X269675Y298108D01*
X269383Y298317D01*
X269050Y298400D01*
X268717Y298317D01*
X268425Y298108D01*
X268300Y297817D01*
X268383Y297525D01*
X268592Y297317D01*
X268842Y297233D01*
X269258D01*
X269633Y297108D01*
X269883Y296858D01*
X269967Y296567D01*
X269883Y296275D01*
X269675Y296067D01*
X269342Y295942D01*
X269050Y295900D01*
G01X265450D02*
Y298400D01*
X266992Y296608D01*
X264908D01*
G01X285250Y282900D02*
Y280400D01*
G01X286208Y282900D02*
X284292D01*
G01X282983Y280400D02*
Y282900D01*
X281983D01*
X281650Y282775D01*
X281400Y282483D01*
X281317Y282150D01*
X281400Y281817D01*
X281608Y281567D01*
X281983Y281442D01*
X282983D01*
G01X279133Y280400D02*
X279050Y280942D01*
X278925Y281400D01*
X278758Y281817D01*
X278550Y282275D01*
X278217Y282900D01*
X279883D01*
G01X275450Y280400D02*
Y282900D01*
X276992Y281108D01*
X274908D01*
G01X277750Y291400D02*
Y288900D01*
G01X278708Y291400D02*
X276792D01*
G01X275483Y288900D02*
Y291400D01*
X274483D01*
X274150Y291275D01*
X273900Y290983D01*
X273817Y290650D01*
X273900Y290317D01*
X274108Y290067D01*
X274483Y289942D01*
X275483D01*
G01X271633Y288900D02*
X271550Y289442D01*
X271425Y289900D01*
X271258Y290317D01*
X271050Y290775D01*
X270717Y291400D01*
X272383D01*
G01X268450D02*
X268783Y291317D01*
X269033Y291108D01*
X269200Y290858D01*
X269325Y290525D01*
X269367Y290150D01*
X269325Y289775D01*
X269200Y289442D01*
X269033Y289192D01*
X268783Y288983D01*
X268450Y288900D01*
X268117Y288983D01*
X267867Y289192D01*
X267700Y289442D01*
X267575Y289775D01*
X267533Y290150D01*
X267575Y290525D01*
X267700Y290858D01*
X267867Y291108D01*
X268117Y291317D01*
X268450Y291400D01*
G01X279250Y286900D02*
Y284400D01*
G01X280208Y286900D02*
X278292D01*
G01X276983Y284400D02*
Y286900D01*
X275983D01*
X275650Y286775D01*
X275400Y286483D01*
X275317Y286150D01*
X275400Y285817D01*
X275608Y285567D01*
X275983Y285442D01*
X276983D01*
G01X273842D02*
X273550Y285733D01*
X273300Y285900D01*
X272967Y285983D01*
X272675Y285900D01*
X272467Y285733D01*
X272300Y285483D01*
X272258Y285192D01*
X272300Y284942D01*
X272467Y284692D01*
X272717Y284483D01*
X273008Y284400D01*
X273342Y284483D01*
X273633Y284733D01*
X273800Y285108D01*
X273842Y285525D01*
X273758Y286067D01*
X273633Y286358D01*
X273425Y286650D01*
X273133Y286858D01*
X272842Y286900D01*
X272550Y286817D01*
X272342Y286608D01*
G01X270658Y284692D02*
X270367Y284483D01*
X270033Y284400D01*
X269700Y284483D01*
X269408Y284733D01*
X269200Y285108D01*
X269117Y285483D01*
Y285942D01*
X269200Y286317D01*
X269408Y286650D01*
X269658Y286817D01*
X269950Y286900D01*
X270283Y286817D01*
X270533Y286650D01*
X270700Y286400D01*
X270783Y286067D01*
X270700Y285775D01*
X270492Y285483D01*
X270242Y285317D01*
X269950Y285275D01*
X269617Y285358D01*
X269367Y285567D01*
X269117Y285942D01*
G01X274250Y278400D02*
Y275900D01*
G01X275208Y278400D02*
X273292D01*
G01X271983Y275900D02*
Y278400D01*
X270983D01*
X270650Y278275D01*
X270400Y277983D01*
X270317Y277650D01*
X270400Y277317D01*
X270608Y277067D01*
X270983Y276942D01*
X271983D01*
G01X268842D02*
X268550Y277233D01*
X268300Y277400D01*
X267967Y277483D01*
X267675Y277400D01*
X267467Y277233D01*
X267300Y276983D01*
X267258Y276692D01*
X267300Y276442D01*
X267467Y276192D01*
X267717Y275983D01*
X268008Y275900D01*
X268342Y275983D01*
X268633Y276233D01*
X268800Y276608D01*
X268842Y277025D01*
X268758Y277567D01*
X268633Y277858D01*
X268425Y278150D01*
X268133Y278358D01*
X267842Y278400D01*
X267550Y278317D01*
X267342Y278108D01*
G01X265867Y276400D02*
X265617Y276108D01*
X265283Y275942D01*
X264908Y275900D01*
X264575Y275942D01*
X264242Y276150D01*
X264033Y276400D01*
X263992Y276650D01*
X264075Y276942D01*
X264367Y277150D01*
X264658Y277233D01*
X265033D01*
G01X264658D02*
X264408Y277358D01*
X264200Y277567D01*
X264117Y277817D01*
X264200Y278067D01*
X264408Y278275D01*
X264783Y278400D01*
X265158Y278358D01*
X265533Y278192D01*
G01X287750Y278400D02*
Y275900D01*
G01X288708Y278400D02*
X286792D01*
G01X285483Y275900D02*
Y278400D01*
X284483D01*
X284150Y278275D01*
X283900Y277983D01*
X283817Y277650D01*
X283900Y277317D01*
X284108Y277067D01*
X284483Y276942D01*
X285483D01*
G01X282342D02*
X282050Y277233D01*
X281800Y277400D01*
X281467Y277483D01*
X281175Y277400D01*
X280967Y277233D01*
X280800Y276983D01*
X280758Y276692D01*
X280800Y276442D01*
X280967Y276192D01*
X281217Y275983D01*
X281508Y275900D01*
X281842Y275983D01*
X282133Y276233D01*
X282300Y276608D01*
X282342Y277025D01*
X282258Y277567D01*
X282133Y277858D01*
X281925Y278150D01*
X281633Y278358D01*
X281342Y278400D01*
X281050Y278317D01*
X280842Y278108D01*
G01X279242Y277983D02*
X278992Y278233D01*
X278700Y278358D01*
X278367Y278400D01*
X277950Y278317D01*
X277658Y278108D01*
X277575Y277858D01*
X277617Y277608D01*
X277783Y277400D01*
X278617Y276983D01*
X278992Y276692D01*
X279242Y276275D01*
X279325Y275900D01*
X277575D01*
G01X287300Y301800D02*
Y369200D01*
G01X343900Y301800D02*
X287300D01*
G01Y333800D02*
X289000Y335500D01*
G01D02*
X287300Y337200D01*
G01X276750Y311900D02*
Y309400D01*
G01X277708Y311900D02*
X275792D01*
G01X274483Y309400D02*
Y311900D01*
X273483D01*
X273150Y311775D01*
X272900Y311483D01*
X272817Y311150D01*
X272900Y310817D01*
X273108Y310567D01*
X273483Y310442D01*
X274483D01*
G01X271258Y309692D02*
X270967Y309483D01*
X270633Y309400D01*
X270300Y309483D01*
X270008Y309733D01*
X269800Y310108D01*
X269717Y310483D01*
Y310942D01*
X269800Y311317D01*
X270008Y311650D01*
X270258Y311817D01*
X270550Y311900D01*
X270883Y311817D01*
X271133Y311650D01*
X271300Y311400D01*
X271383Y311067D01*
X271300Y310775D01*
X271092Y310483D01*
X270842Y310317D01*
X270550Y310275D01*
X270217Y310358D01*
X269967Y310567D01*
X269717Y310942D01*
G01X268242Y310442D02*
X267950Y310733D01*
X267700Y310900D01*
X267367Y310983D01*
X267075Y310900D01*
X266867Y310733D01*
X266700Y310483D01*
X266658Y310192D01*
X266700Y309942D01*
X266867Y309692D01*
X267117Y309483D01*
X267408Y309400D01*
X267742Y309483D01*
X268033Y309733D01*
X268200Y310108D01*
X268242Y310525D01*
X268158Y311067D01*
X268033Y311358D01*
X267825Y311650D01*
X267533Y311858D01*
X267242Y311900D01*
X266950Y311817D01*
X266742Y311608D01*
G01X278750Y305400D02*
Y302900D01*
G01X279708Y305400D02*
X277792D01*
G01X276483Y302900D02*
Y305400D01*
X275483D01*
X275150Y305275D01*
X274900Y304983D01*
X274817Y304650D01*
X274900Y304317D01*
X275108Y304067D01*
X275483Y303942D01*
X276483D01*
G01X273258Y303192D02*
X272967Y302983D01*
X272633Y302900D01*
X272300Y302983D01*
X272008Y303233D01*
X271800Y303608D01*
X271717Y303983D01*
Y304442D01*
X271800Y304817D01*
X272008Y305150D01*
X272258Y305317D01*
X272550Y305400D01*
X272883Y305317D01*
X273133Y305150D01*
X273300Y304900D01*
X273383Y304567D01*
X273300Y304275D01*
X273092Y303983D01*
X272842Y303817D01*
X272550Y303775D01*
X272217Y303858D01*
X271967Y304067D01*
X271717Y304442D01*
G01X270367Y303400D02*
X270117Y303108D01*
X269783Y302942D01*
X269408Y302900D01*
X269075Y302942D01*
X268742Y303150D01*
X268533Y303400D01*
X268492Y303650D01*
X268575Y303942D01*
X268867Y304150D01*
X269158Y304233D01*
X269533D01*
G01X269158D02*
X268908Y304358D01*
X268700Y304567D01*
X268617Y304817D01*
X268700Y305067D01*
X268908Y305275D01*
X269283Y305400D01*
X269658Y305358D01*
X270033Y305192D01*
G01X279250Y317400D02*
Y314900D01*
G01X280208Y317400D02*
X278292D01*
G01X276983Y314900D02*
Y317400D01*
X275983D01*
X275650Y317275D01*
X275400Y316983D01*
X275317Y316650D01*
X275400Y316317D01*
X275608Y316067D01*
X275983Y315942D01*
X276983D01*
G01X273133Y314900D02*
X273050Y315442D01*
X272925Y315900D01*
X272758Y316317D01*
X272550Y316775D01*
X272217Y317400D01*
X273883D01*
G01X270033Y314900D02*
X269950Y315442D01*
X269825Y315900D01*
X269658Y316317D01*
X269450Y316775D01*
X269117Y317400D01*
X270783D01*
G01X321000Y386517D02*
X323500D01*
Y387558D01*
X323375Y387892D01*
X323208Y388100D01*
X322875Y388183D01*
X322542Y388100D01*
X322333Y387850D01*
X322208Y387558D01*
Y386517D01*
G01Y387558D02*
X321000Y388183D01*
G01Y390450D02*
X323500D01*
X323000Y389950D01*
G01X321000D02*
Y390950D01*
G01Y394050D02*
X323500D01*
X321708Y392508D01*
Y394592D01*
G01X321292Y395942D02*
X321083Y396233D01*
X321000Y396567D01*
X321083Y396900D01*
X321333Y397192D01*
X321708Y397400D01*
X322083Y397483D01*
X322542D01*
X322917Y397400D01*
X323250Y397192D01*
X323417Y396942D01*
X323500Y396650D01*
X323417Y396317D01*
X323250Y396067D01*
X323000Y395900D01*
X322667Y395817D01*
X322375Y395900D01*
X322083Y396108D01*
X321917Y396358D01*
X321875Y396650D01*
X321958Y396983D01*
X322167Y397233D01*
X322542Y397483D01*
G01X314786Y391942D02*
X318786D01*
Y384542D01*
G01X269400Y408017D02*
X271900D01*
Y409058D01*
X271775Y409392D01*
X271608Y409600D01*
X271275Y409683D01*
X270942Y409600D01*
X270733Y409350D01*
X270608Y409058D01*
Y408017D01*
G01Y409058D02*
X269400Y409683D01*
G01X269775Y411033D02*
X269567Y411283D01*
X269442Y411575D01*
X269400Y411950D01*
X269483Y412325D01*
X269650Y412617D01*
X269942Y412825D01*
X270275Y412867D01*
X270608Y412783D01*
X270817Y412575D01*
X270983Y412283D01*
X271025Y411992D01*
X270983Y411700D01*
X270817Y411325D01*
X271900Y411450D01*
Y412575D01*
G01X269400Y415050D02*
X271900D01*
X271400Y414550D01*
G01X269400D02*
Y415550D01*
G01X269775Y417233D02*
X269567Y417483D01*
X269442Y417775D01*
X269400Y418150D01*
X269483Y418525D01*
X269650Y418817D01*
X269942Y419025D01*
X270275Y419067D01*
X270608Y418983D01*
X270817Y418775D01*
X270983Y418483D01*
X271025Y418192D01*
X270983Y417900D01*
X270817Y417525D01*
X271900Y417650D01*
Y418775D01*
G01X315517Y382667D02*
Y380875D01*
X315350Y380500D01*
X315017Y380250D01*
X314600Y380167D01*
X314183Y380250D01*
X313850Y380500D01*
X313683Y380875D01*
Y382667D01*
G01X311500Y380167D02*
Y382667D01*
X312000Y382167D01*
G01Y380167D02*
X311000D01*
G01X309317Y380667D02*
X309067Y380375D01*
X308733Y380209D01*
X308358Y380167D01*
X308025Y380209D01*
X307692Y380417D01*
X307483Y380667D01*
X307442Y380917D01*
X307525Y381209D01*
X307817Y381417D01*
X308108Y381500D01*
X308483D01*
G01X308108D02*
X307858Y381625D01*
X307650Y381834D01*
X307567Y382084D01*
X307650Y382334D01*
X307858Y382542D01*
X308233Y382667D01*
X308608Y382625D01*
X308983Y382459D01*
G01X287300Y369200D02*
X343900D01*
G01X372567Y176917D02*
X373367Y177267D01*
X374300Y177500D01*
X375367D01*
X376567Y177150D01*
X377500Y176567D01*
X378167Y175867D01*
X378700Y174700D01*
X378833Y173650D01*
X378567Y172600D01*
X378167Y171900D01*
X377367Y171200D01*
X376433Y170733D01*
X375500Y170500D01*
X374567D01*
X373633Y170733D01*
X372833Y171083D01*
X372167Y171550D01*
G01X386000Y168500D02*
X384885D01*
G01X379500D02*
X371000D01*
Y178500D01*
G01X363992Y141317D02*
X364117Y141067D01*
X364200Y140775D01*
Y140442D01*
X364075Y140067D01*
X363867Y139775D01*
X363617Y139567D01*
X363200Y139400D01*
X362825Y139358D01*
X362450Y139442D01*
X362200Y139567D01*
X361950Y139817D01*
X361783Y140108D01*
X361700Y140400D01*
Y140692D01*
X361783Y140983D01*
X361908Y141233D01*
X362075Y141442D01*
G01Y142583D02*
X361867Y142833D01*
X361742Y143125D01*
X361700Y143500D01*
X361783Y143875D01*
X361950Y144167D01*
X362242Y144375D01*
X362575Y144417D01*
X362908Y144333D01*
X363117Y144125D01*
X363283Y143833D01*
X363325Y143542D01*
X363283Y143250D01*
X363117Y142875D01*
X364200Y143000D01*
Y144125D01*
G01X362742Y145808D02*
X363033Y146100D01*
X363200Y146350D01*
X363283Y146683D01*
X363200Y146975D01*
X363033Y147183D01*
X362783Y147350D01*
X362492Y147392D01*
X362242Y147350D01*
X361992Y147183D01*
X361783Y146933D01*
X361700Y146642D01*
X361783Y146308D01*
X362033Y146017D01*
X362408Y145850D01*
X362825Y145808D01*
X363367Y145892D01*
X363658Y146017D01*
X363950Y146225D01*
X364158Y146517D01*
X364200Y146808D01*
X364117Y147100D01*
X363908Y147308D01*
G01X367492Y141317D02*
X367617Y141067D01*
X367700Y140775D01*
Y140442D01*
X367575Y140067D01*
X367367Y139775D01*
X367117Y139567D01*
X366700Y139400D01*
X366325Y139358D01*
X365950Y139442D01*
X365700Y139567D01*
X365450Y139817D01*
X365283Y140108D01*
X365200Y140400D01*
Y140692D01*
X365283Y140983D01*
X365408Y141233D01*
X365575Y141442D01*
G01Y142583D02*
X365367Y142833D01*
X365242Y143125D01*
X365200Y143500D01*
X365283Y143875D01*
X365450Y144167D01*
X365742Y144375D01*
X366075Y144417D01*
X366408Y144333D01*
X366617Y144125D01*
X366783Y143833D01*
X366825Y143542D01*
X366783Y143250D01*
X366617Y142875D01*
X367700Y143000D01*
Y144125D01*
G01X365575Y145683D02*
X365367Y145933D01*
X365242Y146225D01*
X365200Y146600D01*
X365283Y146975D01*
X365450Y147267D01*
X365742Y147475D01*
X366075Y147517D01*
X366408Y147433D01*
X366617Y147225D01*
X366783Y146933D01*
X366825Y146642D01*
X366783Y146350D01*
X366617Y145975D01*
X367700Y146100D01*
Y147225D01*
G01X370992Y141317D02*
X371117Y141067D01*
X371200Y140775D01*
Y140442D01*
X371075Y140067D01*
X370867Y139775D01*
X370617Y139567D01*
X370200Y139400D01*
X369825Y139358D01*
X369450Y139442D01*
X369200Y139567D01*
X368950Y139817D01*
X368783Y140108D01*
X368700Y140400D01*
Y140692D01*
X368783Y140983D01*
X368908Y141233D01*
X369075Y141442D01*
G01Y142583D02*
X368867Y142833D01*
X368742Y143125D01*
X368700Y143500D01*
X368783Y143875D01*
X368950Y144167D01*
X369242Y144375D01*
X369575Y144417D01*
X369908Y144333D01*
X370117Y144125D01*
X370283Y143833D01*
X370325Y143542D01*
X370283Y143250D01*
X370117Y142875D01*
X371200Y143000D01*
Y144125D01*
G01X368700Y147100D02*
X371200D01*
X369408Y145558D01*
Y147642D01*
G01X374492Y141317D02*
X374617Y141067D01*
X374700Y140775D01*
Y140442D01*
X374575Y140067D01*
X374367Y139775D01*
X374117Y139567D01*
X373700Y139400D01*
X373325Y139358D01*
X372950Y139442D01*
X372700Y139567D01*
X372450Y139817D01*
X372283Y140108D01*
X372200Y140400D01*
Y140692D01*
X372283Y140983D01*
X372408Y141233D01*
X372575Y141442D01*
G01Y142583D02*
X372367Y142833D01*
X372242Y143125D01*
X372200Y143500D01*
X372283Y143875D01*
X372450Y144167D01*
X372742Y144375D01*
X373075Y144417D01*
X373408Y144333D01*
X373617Y144125D01*
X373783Y143833D01*
X373825Y143542D01*
X373783Y143250D01*
X373617Y142875D01*
X374700Y143000D01*
Y144125D01*
G01X372700Y145683D02*
X372408Y145933D01*
X372242Y146267D01*
X372200Y146642D01*
X372242Y146975D01*
X372450Y147308D01*
X372700Y147517D01*
X372950Y147558D01*
X373242Y147475D01*
X373450Y147183D01*
X373533Y146892D01*
Y146517D01*
G01Y146892D02*
X373658Y147142D01*
X373867Y147350D01*
X374117Y147433D01*
X374367Y147350D01*
X374575Y147142D01*
X374700Y146767D01*
X374658Y146392D01*
X374492Y146017D01*
G01X377992Y141317D02*
X378117Y141067D01*
X378200Y140775D01*
Y140442D01*
X378075Y140067D01*
X377867Y139775D01*
X377617Y139567D01*
X377200Y139400D01*
X376825Y139358D01*
X376450Y139442D01*
X376200Y139567D01*
X375950Y139817D01*
X375783Y140108D01*
X375700Y140400D01*
Y140692D01*
X375783Y140983D01*
X375908Y141233D01*
X376075Y141442D01*
G01Y142583D02*
X375867Y142833D01*
X375742Y143125D01*
X375700Y143500D01*
X375783Y143875D01*
X375950Y144167D01*
X376242Y144375D01*
X376575Y144417D01*
X376908Y144333D01*
X377117Y144125D01*
X377283Y143833D01*
X377325Y143542D01*
X377283Y143250D01*
X377117Y142875D01*
X378200Y143000D01*
Y144125D01*
G01X377783Y145808D02*
X378033Y146058D01*
X378158Y146350D01*
X378200Y146683D01*
X378117Y147100D01*
X377908Y147392D01*
X377658Y147475D01*
X377408Y147433D01*
X377200Y147267D01*
X376783Y146433D01*
X376492Y146058D01*
X376075Y145808D01*
X375700Y145725D01*
Y147475D01*
G01X381492Y141817D02*
X381617Y141567D01*
X381700Y141275D01*
Y140942D01*
X381575Y140567D01*
X381367Y140275D01*
X381117Y140067D01*
X380700Y139900D01*
X380325Y139858D01*
X379950Y139942D01*
X379700Y140067D01*
X379450Y140317D01*
X379283Y140608D01*
X379200Y140900D01*
Y141192D01*
X379283Y141483D01*
X379408Y141733D01*
X379575Y141942D01*
G01Y143083D02*
X379367Y143333D01*
X379242Y143625D01*
X379200Y144000D01*
X379283Y144375D01*
X379450Y144667D01*
X379742Y144875D01*
X380075Y144917D01*
X380408Y144833D01*
X380617Y144625D01*
X380783Y144333D01*
X380825Y144042D01*
X380783Y143750D01*
X380617Y143375D01*
X381700Y143500D01*
Y144625D01*
G01X379200Y147100D02*
X381700D01*
X381200Y146600D01*
G01X379200D02*
Y147600D01*
G01X384992Y141317D02*
X385117Y141067D01*
X385200Y140775D01*
Y140442D01*
X385075Y140067D01*
X384867Y139775D01*
X384617Y139567D01*
X384200Y139400D01*
X383825Y139358D01*
X383450Y139442D01*
X383200Y139567D01*
X382950Y139817D01*
X382783Y140108D01*
X382700Y140400D01*
Y140692D01*
X382783Y140983D01*
X382908Y141233D01*
X383075Y141442D01*
G01Y142583D02*
X382867Y142833D01*
X382742Y143125D01*
X382700Y143500D01*
X382783Y143875D01*
X382950Y144167D01*
X383242Y144375D01*
X383575Y144417D01*
X383908Y144333D01*
X384117Y144125D01*
X384283Y143833D01*
X384325Y143542D01*
X384283Y143250D01*
X384117Y142875D01*
X385200Y143000D01*
Y144125D01*
G01Y146600D02*
X385117Y146267D01*
X384908Y146017D01*
X384658Y145850D01*
X384325Y145725D01*
X383950Y145683D01*
X383575Y145725D01*
X383242Y145850D01*
X382992Y146017D01*
X382783Y146267D01*
X382700Y146600D01*
X382783Y146933D01*
X382992Y147183D01*
X383242Y147350D01*
X383575Y147475D01*
X383950Y147517D01*
X384325Y147475D01*
X384658Y147350D01*
X384908Y147183D01*
X385117Y146933D01*
X385200Y146600D01*
G01X388492Y141317D02*
X388617Y141067D01*
X388700Y140775D01*
Y140442D01*
X388575Y140067D01*
X388367Y139775D01*
X388117Y139567D01*
X387700Y139400D01*
X387325Y139358D01*
X386950Y139442D01*
X386700Y139567D01*
X386450Y139817D01*
X386283Y140108D01*
X386200Y140400D01*
Y140692D01*
X386283Y140983D01*
X386408Y141233D01*
X386575Y141442D01*
G01X386200Y144000D02*
X388700D01*
X386908Y142458D01*
Y144542D01*
G01X386492Y145892D02*
X386283Y146183D01*
X386200Y146517D01*
X386283Y146850D01*
X386533Y147142D01*
X386908Y147350D01*
X387283Y147433D01*
X387742D01*
X388117Y147350D01*
X388450Y147142D01*
X388617Y146892D01*
X388700Y146600D01*
X388617Y146267D01*
X388450Y146017D01*
X388200Y145850D01*
X387867Y145767D01*
X387575Y145850D01*
X387283Y146058D01*
X387117Y146308D01*
X387075Y146600D01*
X387158Y146933D01*
X387367Y147183D01*
X387742Y147433D01*
G01X371000Y178500D02*
X379500D01*
G01X384500D02*
X386000D01*
G01X386233Y226792D02*
X386483Y226917D01*
X386775Y227000D01*
X387108D01*
X387483Y226875D01*
X387775Y226667D01*
X387983Y226417D01*
X388150Y226000D01*
X388192Y225625D01*
X388108Y225250D01*
X387983Y225000D01*
X387733Y224750D01*
X387442Y224583D01*
X387150Y224500D01*
X386858D01*
X386567Y224583D01*
X386317Y224708D01*
X386108Y224875D01*
G01X384050Y224500D02*
Y227000D01*
X384550Y226500D01*
G01Y224500D02*
X383550D01*
G01X381658Y224792D02*
X381367Y224583D01*
X381033Y224500D01*
X380700Y224583D01*
X380408Y224833D01*
X380200Y225208D01*
X380117Y225583D01*
Y226042D01*
X380200Y226417D01*
X380408Y226750D01*
X380658Y226917D01*
X380950Y227000D01*
X381283Y226917D01*
X381533Y226750D01*
X381700Y226500D01*
X381783Y226167D01*
X381700Y225875D01*
X381492Y225583D01*
X381242Y225417D01*
X380950Y225375D01*
X380617Y225458D01*
X380367Y225667D01*
X380117Y226042D01*
G01X377350Y224500D02*
Y227000D01*
X378892Y225208D01*
X376808D01*
G01X373233Y226792D02*
X373483Y226917D01*
X373775Y227000D01*
X374108D01*
X374483Y226875D01*
X374775Y226667D01*
X374983Y226417D01*
X375150Y226000D01*
X375192Y225625D01*
X375108Y225250D01*
X374983Y225000D01*
X374733Y224750D01*
X374442Y224583D01*
X374150Y224500D01*
X373858D01*
X373567Y224583D01*
X373317Y224708D01*
X373108Y224875D01*
G01X371050Y224500D02*
Y227000D01*
X371550Y226500D01*
G01Y224500D02*
X370550D01*
G01X368658Y224792D02*
X368367Y224583D01*
X368033Y224500D01*
X367700Y224583D01*
X367408Y224833D01*
X367200Y225208D01*
X367117Y225583D01*
Y226042D01*
X367200Y226417D01*
X367408Y226750D01*
X367658Y226917D01*
X367950Y227000D01*
X368283Y226917D01*
X368533Y226750D01*
X368700Y226500D01*
X368783Y226167D01*
X368700Y225875D01*
X368492Y225583D01*
X368242Y225417D01*
X367950Y225375D01*
X367617Y225458D01*
X367367Y225667D01*
X367117Y226042D01*
G01X365767Y224875D02*
X365517Y224667D01*
X365225Y224542D01*
X364850Y224500D01*
X364475Y224583D01*
X364183Y224750D01*
X363975Y225042D01*
X363933Y225375D01*
X364017Y225708D01*
X364225Y225917D01*
X364517Y226083D01*
X364808Y226125D01*
X365100Y226083D01*
X365475Y225917D01*
X365350Y227000D01*
X364225D01*
G01X385233Y231292D02*
X385483Y231417D01*
X385775Y231500D01*
X386108D01*
X386483Y231375D01*
X386775Y231167D01*
X386983Y230917D01*
X387150Y230500D01*
X387192Y230125D01*
X387108Y229750D01*
X386983Y229500D01*
X386733Y229250D01*
X386442Y229083D01*
X386150Y229000D01*
X385858D01*
X385567Y229083D01*
X385317Y229208D01*
X385108Y229375D01*
G01X383050Y229000D02*
Y231500D01*
X383550Y231000D01*
G01Y229000D02*
X382550D01*
G01X380867Y229500D02*
X380617Y229208D01*
X380283Y229042D01*
X379908Y229000D01*
X379575Y229042D01*
X379242Y229250D01*
X379033Y229500D01*
X378992Y229750D01*
X379075Y230042D01*
X379367Y230250D01*
X379658Y230333D01*
X380033D01*
G01X379658D02*
X379408Y230458D01*
X379200Y230667D01*
X379117Y230917D01*
X379200Y231167D01*
X379408Y231375D01*
X379783Y231500D01*
X380158Y231458D01*
X380533Y231292D01*
G01X377642Y230042D02*
X377350Y230333D01*
X377100Y230500D01*
X376767Y230583D01*
X376475Y230500D01*
X376267Y230333D01*
X376100Y230083D01*
X376058Y229792D01*
X376100Y229542D01*
X376267Y229292D01*
X376517Y229083D01*
X376808Y229000D01*
X377142Y229083D01*
X377433Y229333D01*
X377600Y229708D01*
X377642Y230125D01*
X377558Y230667D01*
X377433Y230958D01*
X377225Y231250D01*
X376933Y231458D01*
X376642Y231500D01*
X376350Y231417D01*
X376142Y231208D01*
G01X342683Y197292D02*
X342933Y197417D01*
X343225Y197500D01*
X343558D01*
X343933Y197375D01*
X344225Y197167D01*
X344433Y196917D01*
X344600Y196500D01*
X344642Y196125D01*
X344558Y195750D01*
X344433Y195500D01*
X344183Y195250D01*
X343892Y195083D01*
X343600Y195000D01*
X343308D01*
X343017Y195083D01*
X342767Y195208D01*
X342558Y195375D01*
G01X340500Y195000D02*
X340208Y195042D01*
X339875Y195167D01*
X339667Y195375D01*
X339583Y195667D01*
X339667Y195958D01*
X339917Y196208D01*
X340292Y196333D01*
X340708D01*
X340958Y196417D01*
X341167Y196625D01*
X341250Y196917D01*
X341125Y197208D01*
X340833Y197417D01*
X340500Y197500D01*
X340167Y197417D01*
X339875Y197208D01*
X339750Y196917D01*
X339833Y196625D01*
X340042Y196417D01*
X340292Y196333D01*
X340708D01*
X341083Y196208D01*
X341333Y195958D01*
X341417Y195667D01*
X341333Y195375D01*
X341125Y195167D01*
X340792Y195042D01*
X340500Y195000D01*
G01X337400D02*
X337108Y195042D01*
X336775Y195167D01*
X336567Y195375D01*
X336483Y195667D01*
X336567Y195958D01*
X336817Y196208D01*
X337192Y196333D01*
X337608D01*
X337858Y196417D01*
X338067Y196625D01*
X338150Y196917D01*
X338025Y197208D01*
X337733Y197417D01*
X337400Y197500D01*
X337067Y197417D01*
X336775Y197208D01*
X336650Y196917D01*
X336733Y196625D01*
X336942Y196417D01*
X337192Y196333D01*
X337608D01*
X337983Y196208D01*
X338233Y195958D01*
X338317Y195667D01*
X338233Y195375D01*
X338025Y195167D01*
X337692Y195042D01*
X337400Y195000D01*
G01X342683Y201292D02*
X342933Y201417D01*
X343225Y201500D01*
X343558D01*
X343933Y201375D01*
X344225Y201167D01*
X344433Y200917D01*
X344600Y200500D01*
X344642Y200125D01*
X344558Y199750D01*
X344433Y199500D01*
X344183Y199250D01*
X343892Y199083D01*
X343600Y199000D01*
X343308D01*
X343017Y199083D01*
X342767Y199208D01*
X342558Y199375D01*
G01X341208Y199292D02*
X340917Y199083D01*
X340583Y199000D01*
X340250Y199083D01*
X339958Y199333D01*
X339750Y199708D01*
X339667Y200083D01*
Y200542D01*
X339750Y200917D01*
X339958Y201250D01*
X340208Y201417D01*
X340500Y201500D01*
X340833Y201417D01*
X341083Y201250D01*
X341250Y201000D01*
X341333Y200667D01*
X341250Y200375D01*
X341042Y200083D01*
X340792Y199917D01*
X340500Y199875D01*
X340167Y199958D01*
X339917Y200167D01*
X339667Y200542D01*
G01X337400Y201500D02*
X337733Y201417D01*
X337983Y201208D01*
X338150Y200958D01*
X338275Y200625D01*
X338317Y200250D01*
X338275Y199875D01*
X338150Y199542D01*
X337983Y199292D01*
X337733Y199083D01*
X337400Y199000D01*
X337067Y199083D01*
X336817Y199292D01*
X336650Y199542D01*
X336525Y199875D01*
X336483Y200250D01*
X336525Y200625D01*
X336650Y200958D01*
X336817Y201208D01*
X337067Y201417D01*
X337400Y201500D01*
G01X342683Y205292D02*
X342933Y205417D01*
X343225Y205500D01*
X343558D01*
X343933Y205375D01*
X344225Y205167D01*
X344433Y204917D01*
X344600Y204500D01*
X344642Y204125D01*
X344558Y203750D01*
X344433Y203500D01*
X344183Y203250D01*
X343892Y203083D01*
X343600Y203000D01*
X343308D01*
X343017Y203083D01*
X342767Y203208D01*
X342558Y203375D01*
G01X341208Y203292D02*
X340917Y203083D01*
X340583Y203000D01*
X340250Y203083D01*
X339958Y203333D01*
X339750Y203708D01*
X339667Y204083D01*
Y204542D01*
X339750Y204917D01*
X339958Y205250D01*
X340208Y205417D01*
X340500Y205500D01*
X340833Y205417D01*
X341083Y205250D01*
X341250Y205000D01*
X341333Y204667D01*
X341250Y204375D01*
X341042Y204083D01*
X340792Y203917D01*
X340500Y203875D01*
X340167Y203958D01*
X339917Y204167D01*
X339667Y204542D01*
G01X337400Y203000D02*
Y205500D01*
X337900Y205000D01*
G01Y203000D02*
X336900D01*
G01X343183Y209292D02*
X343433Y209417D01*
X343725Y209500D01*
X344058D01*
X344433Y209375D01*
X344725Y209167D01*
X344933Y208917D01*
X345100Y208500D01*
X345142Y208125D01*
X345058Y207750D01*
X344933Y207500D01*
X344683Y207250D01*
X344392Y207083D01*
X344100Y207000D01*
X343808D01*
X343517Y207083D01*
X343267Y207208D01*
X343058Y207375D01*
G01X341708Y207292D02*
X341417Y207083D01*
X341083Y207000D01*
X340750Y207083D01*
X340458Y207333D01*
X340250Y207708D01*
X340167Y208083D01*
Y208542D01*
X340250Y208917D01*
X340458Y209250D01*
X340708Y209417D01*
X341000Y209500D01*
X341333Y209417D01*
X341583Y209250D01*
X341750Y209000D01*
X341833Y208667D01*
X341750Y208375D01*
X341542Y208083D01*
X341292Y207917D01*
X341000Y207875D01*
X340667Y207958D01*
X340417Y208167D01*
X340167Y208542D01*
G01X338692Y209083D02*
X338442Y209333D01*
X338150Y209458D01*
X337817Y209500D01*
X337400Y209417D01*
X337108Y209208D01*
X337025Y208958D01*
X337067Y208708D01*
X337233Y208500D01*
X338067Y208083D01*
X338442Y207792D01*
X338692Y207375D01*
X338775Y207000D01*
X337025D01*
G01X343183Y217792D02*
X343433Y217917D01*
X343725Y218000D01*
X344058D01*
X344433Y217875D01*
X344725Y217667D01*
X344933Y217417D01*
X345100Y217000D01*
X345142Y216625D01*
X345058Y216250D01*
X344933Y216000D01*
X344683Y215750D01*
X344392Y215583D01*
X344100Y215500D01*
X343808D01*
X343517Y215583D01*
X343267Y215708D01*
X343058Y215875D01*
G01X341708Y215792D02*
X341417Y215583D01*
X341083Y215500D01*
X340750Y215583D01*
X340458Y215833D01*
X340250Y216208D01*
X340167Y216583D01*
Y217042D01*
X340250Y217417D01*
X340458Y217750D01*
X340708Y217917D01*
X341000Y218000D01*
X341333Y217917D01*
X341583Y217750D01*
X341750Y217500D01*
X341833Y217167D01*
X341750Y216875D01*
X341542Y216583D01*
X341292Y216417D01*
X341000Y216375D01*
X340667Y216458D01*
X340417Y216667D01*
X340167Y217042D01*
G01X338817Y216000D02*
X338567Y215708D01*
X338233Y215542D01*
X337858Y215500D01*
X337525Y215542D01*
X337192Y215750D01*
X336983Y216000D01*
X336942Y216250D01*
X337025Y216542D01*
X337317Y216750D01*
X337608Y216833D01*
X337983D01*
G01X337608D02*
X337358Y216958D01*
X337150Y217167D01*
X337067Y217417D01*
X337150Y217667D01*
X337358Y217875D01*
X337733Y218000D01*
X338108Y217958D01*
X338483Y217792D01*
G01X343233Y213252D02*
X343483Y213377D01*
X343775Y213460D01*
X344108D01*
X344483Y213335D01*
X344775Y213127D01*
X344983Y212877D01*
X345150Y212460D01*
X345192Y212085D01*
X345108Y211710D01*
X344983Y211460D01*
X344733Y211210D01*
X344442Y211043D01*
X344150Y210960D01*
X343858D01*
X343567Y211043D01*
X343317Y211168D01*
X343108Y211335D01*
G01X341758Y211252D02*
X341467Y211043D01*
X341133Y210960D01*
X340800Y211043D01*
X340508Y211293D01*
X340300Y211668D01*
X340217Y212043D01*
Y212502D01*
X340300Y212877D01*
X340508Y213210D01*
X340758Y213377D01*
X341050Y213460D01*
X341383Y213377D01*
X341633Y213210D01*
X341800Y212960D01*
X341883Y212627D01*
X341800Y212335D01*
X341592Y212043D01*
X341342Y211877D01*
X341050Y211835D01*
X340717Y211918D01*
X340467Y212127D01*
X340217Y212502D01*
G01X337450Y210960D02*
Y213460D01*
X338992Y211668D01*
X336908D01*
G01X343183Y221842D02*
X343433Y221967D01*
X343725Y222050D01*
X344058D01*
X344433Y221925D01*
X344725Y221717D01*
X344933Y221467D01*
X345100Y221050D01*
X345142Y220675D01*
X345058Y220300D01*
X344933Y220050D01*
X344683Y219800D01*
X344392Y219633D01*
X344100Y219550D01*
X343808D01*
X343517Y219633D01*
X343267Y219758D01*
X343058Y219925D01*
G01X341708Y219842D02*
X341417Y219633D01*
X341083Y219550D01*
X340750Y219633D01*
X340458Y219883D01*
X340250Y220258D01*
X340167Y220633D01*
Y221092D01*
X340250Y221467D01*
X340458Y221800D01*
X340708Y221967D01*
X341000Y222050D01*
X341333Y221967D01*
X341583Y221800D01*
X341750Y221550D01*
X341833Y221217D01*
X341750Y220925D01*
X341542Y220633D01*
X341292Y220467D01*
X341000Y220425D01*
X340667Y220508D01*
X340417Y220717D01*
X340167Y221092D01*
G01X338817Y219925D02*
X338567Y219717D01*
X338275Y219592D01*
X337900Y219550D01*
X337525Y219633D01*
X337233Y219800D01*
X337025Y220092D01*
X336983Y220425D01*
X337067Y220758D01*
X337275Y220967D01*
X337567Y221133D01*
X337858Y221175D01*
X338150Y221133D01*
X338525Y220967D01*
X338400Y222050D01*
X337275D01*
G01X343183Y225842D02*
X343433Y225967D01*
X343725Y226050D01*
X344058D01*
X344433Y225925D01*
X344725Y225717D01*
X344933Y225467D01*
X345100Y225050D01*
X345142Y224675D01*
X345058Y224300D01*
X344933Y224050D01*
X344683Y223800D01*
X344392Y223633D01*
X344100Y223550D01*
X343808D01*
X343517Y223633D01*
X343267Y223758D01*
X343058Y223925D01*
G01X341708Y223842D02*
X341417Y223633D01*
X341083Y223550D01*
X340750Y223633D01*
X340458Y223883D01*
X340250Y224258D01*
X340167Y224633D01*
Y225092D01*
X340250Y225467D01*
X340458Y225800D01*
X340708Y225967D01*
X341000Y226050D01*
X341333Y225967D01*
X341583Y225800D01*
X341750Y225550D01*
X341833Y225217D01*
X341750Y224925D01*
X341542Y224633D01*
X341292Y224467D01*
X341000Y224425D01*
X340667Y224508D01*
X340417Y224717D01*
X340167Y225092D01*
G01X338692Y224592D02*
X338400Y224883D01*
X338150Y225050D01*
X337817Y225133D01*
X337525Y225050D01*
X337317Y224883D01*
X337150Y224633D01*
X337108Y224342D01*
X337150Y224092D01*
X337317Y223842D01*
X337567Y223633D01*
X337858Y223550D01*
X338192Y223633D01*
X338483Y223883D01*
X338650Y224258D01*
X338692Y224675D01*
X338608Y225217D01*
X338483Y225508D01*
X338275Y225800D01*
X337983Y226008D01*
X337692Y226050D01*
X337400Y225967D01*
X337192Y225758D01*
G01X342733Y290459D02*
X342983Y290584D01*
X343275Y290667D01*
X343608D01*
X343983Y290542D01*
X344275Y290334D01*
X344483Y290084D01*
X344650Y289667D01*
X344692Y289292D01*
X344608Y288917D01*
X344483Y288667D01*
X344233Y288417D01*
X343942Y288250D01*
X343650Y288167D01*
X343358D01*
X343067Y288250D01*
X342817Y288375D01*
X342608Y288542D01*
G01X340550Y288167D02*
Y290667D01*
X341050Y290167D01*
G01Y288167D02*
X340050D01*
G01X337450D02*
Y290667D01*
X337950Y290167D01*
G01Y288167D02*
X336950D01*
G01X335142Y289209D02*
X334850Y289500D01*
X334600Y289667D01*
X334267Y289750D01*
X333975Y289667D01*
X333767Y289500D01*
X333600Y289250D01*
X333558Y288959D01*
X333600Y288709D01*
X333767Y288459D01*
X334017Y288250D01*
X334308Y288167D01*
X334642Y288250D01*
X334933Y288500D01*
X335100Y288875D01*
X335142Y289292D01*
X335058Y289834D01*
X334933Y290125D01*
X334725Y290417D01*
X334433Y290625D01*
X334142Y290667D01*
X333850Y290584D01*
X333642Y290375D01*
G01X339233Y274459D02*
X339483Y274584D01*
X339775Y274667D01*
X340108D01*
X340483Y274542D01*
X340775Y274334D01*
X340983Y274084D01*
X341150Y273667D01*
X341192Y273292D01*
X341108Y272917D01*
X340983Y272667D01*
X340733Y272417D01*
X340442Y272250D01*
X340150Y272167D01*
X339858D01*
X339567Y272250D01*
X339317Y272375D01*
X339108Y272542D01*
G01X337967D02*
X337717Y272334D01*
X337425Y272209D01*
X337050Y272167D01*
X336675Y272250D01*
X336383Y272417D01*
X336175Y272709D01*
X336133Y273042D01*
X336217Y273375D01*
X336425Y273584D01*
X336717Y273750D01*
X337008Y273792D01*
X337300Y273750D01*
X337675Y273584D01*
X337550Y274667D01*
X336425D01*
G01X333950Y272167D02*
Y274667D01*
X334450Y274167D01*
G01Y272167D02*
X333450D01*
G01X330933D02*
X330850Y272709D01*
X330725Y273167D01*
X330558Y273584D01*
X330350Y274042D01*
X330017Y274667D01*
X331683D01*
G01X383632Y240407D02*
X383757Y240157D01*
X383840Y239865D01*
Y239532D01*
X383715Y239157D01*
X383507Y238865D01*
X383257Y238657D01*
X382840Y238490D01*
X382465Y238448D01*
X382090Y238532D01*
X381840Y238657D01*
X381590Y238907D01*
X381423Y239198D01*
X381340Y239490D01*
Y239782D01*
X381423Y240073D01*
X381548Y240323D01*
X381715Y240532D01*
G01X381340Y242590D02*
X383840D01*
X383340Y242090D01*
G01X381340D02*
Y243090D01*
G01X381632Y244982D02*
X381423Y245273D01*
X381340Y245607D01*
X381423Y245940D01*
X381673Y246232D01*
X382048Y246440D01*
X382423Y246523D01*
X382882D01*
X383257Y246440D01*
X383590Y246232D01*
X383757Y245982D01*
X383840Y245690D01*
X383757Y245357D01*
X383590Y245107D01*
X383340Y244940D01*
X383007Y244857D01*
X382715Y244940D01*
X382423Y245148D01*
X382257Y245398D01*
X382215Y245690D01*
X382298Y246023D01*
X382507Y246273D01*
X382882Y246523D01*
G01X381840Y247873D02*
X381548Y248123D01*
X381382Y248457D01*
X381340Y248832D01*
X381382Y249165D01*
X381590Y249498D01*
X381840Y249707D01*
X382090Y249748D01*
X382382Y249665D01*
X382590Y249373D01*
X382673Y249082D01*
Y248707D01*
G01Y249082D02*
X382798Y249332D01*
X383007Y249540D01*
X383257Y249623D01*
X383507Y249540D01*
X383715Y249332D01*
X383840Y248957D01*
X383798Y248582D01*
X383632Y248207D01*
G01X383459Y269267D02*
X383584Y269017D01*
X383667Y268725D01*
Y268392D01*
X383542Y268017D01*
X383334Y267725D01*
X383084Y267517D01*
X382667Y267350D01*
X382292Y267308D01*
X381917Y267392D01*
X381667Y267517D01*
X381417Y267767D01*
X381250Y268058D01*
X381167Y268350D01*
Y268642D01*
X381250Y268933D01*
X381375Y269183D01*
X381542Y269392D01*
G01X381167Y271450D02*
X383667D01*
X383167Y270950D01*
G01X381167D02*
Y271950D01*
G01X381459Y273842D02*
X381250Y274133D01*
X381167Y274467D01*
X381250Y274800D01*
X381500Y275092D01*
X381875Y275300D01*
X382250Y275383D01*
X382709D01*
X383084Y275300D01*
X383417Y275092D01*
X383584Y274842D01*
X383667Y274550D01*
X383584Y274217D01*
X383417Y273967D01*
X383167Y273800D01*
X382834Y273717D01*
X382542Y273800D01*
X382250Y274008D01*
X382084Y274258D01*
X382042Y274550D01*
X382125Y274883D01*
X382334Y275133D01*
X382709Y275383D01*
G01X381167Y277567D02*
X381709Y277650D01*
X382167Y277775D01*
X382584Y277942D01*
X383042Y278150D01*
X383667Y278483D01*
Y276817D01*
G01X383792Y256267D02*
X383917Y256017D01*
X384000Y255725D01*
Y255392D01*
X383875Y255017D01*
X383667Y254725D01*
X383417Y254517D01*
X383000Y254350D01*
X382625Y254308D01*
X382250Y254392D01*
X382000Y254517D01*
X381750Y254767D01*
X381583Y255058D01*
X381500Y255350D01*
Y255642D01*
X381583Y255933D01*
X381708Y256183D01*
X381875Y256392D01*
G01X383583Y257658D02*
X383833Y257908D01*
X383958Y258200D01*
X384000Y258533D01*
X383917Y258950D01*
X383708Y259242D01*
X383458Y259325D01*
X383208Y259283D01*
X383000Y259117D01*
X382583Y258283D01*
X382292Y257908D01*
X381875Y257658D01*
X381500Y257575D01*
Y259325D01*
G01X384000Y261550D02*
X383917Y261217D01*
X383708Y260967D01*
X383458Y260800D01*
X383125Y260675D01*
X382750Y260633D01*
X382375Y260675D01*
X382042Y260800D01*
X381792Y260967D01*
X381583Y261217D01*
X381500Y261550D01*
X381583Y261883D01*
X381792Y262133D01*
X382042Y262300D01*
X382375Y262425D01*
X382750Y262467D01*
X383125Y262425D01*
X383458Y262300D01*
X383708Y262133D01*
X383917Y261883D01*
X384000Y261550D01*
G01X381500Y264650D02*
X384000D01*
X383500Y264150D01*
G01X381500D02*
Y265150D01*
G01X384292Y284267D02*
X384417Y284017D01*
X384500Y283725D01*
Y283392D01*
X384375Y283017D01*
X384167Y282725D01*
X383917Y282517D01*
X383500Y282350D01*
X383125Y282308D01*
X382750Y282392D01*
X382500Y282517D01*
X382250Y282767D01*
X382083Y283058D01*
X382000Y283350D01*
Y283642D01*
X382083Y283933D01*
X382208Y284183D01*
X382375Y284392D01*
G01X384083Y285658D02*
X384333Y285908D01*
X384458Y286200D01*
X384500Y286533D01*
X384417Y286950D01*
X384208Y287242D01*
X383958Y287325D01*
X383708Y287283D01*
X383500Y287117D01*
X383083Y286283D01*
X382792Y285908D01*
X382375Y285658D01*
X382000Y285575D01*
Y287325D01*
G01X384500Y289550D02*
X384417Y289217D01*
X384208Y288967D01*
X383958Y288800D01*
X383625Y288675D01*
X383250Y288633D01*
X382875Y288675D01*
X382542Y288800D01*
X382292Y288967D01*
X382083Y289217D01*
X382000Y289550D01*
X382083Y289883D01*
X382292Y290133D01*
X382542Y290300D01*
X382875Y290425D01*
X383250Y290467D01*
X383625Y290425D01*
X383958Y290300D01*
X384208Y290133D01*
X384417Y289883D01*
X384500Y289550D01*
G01X382375Y291733D02*
X382167Y291983D01*
X382042Y292275D01*
X382000Y292650D01*
X382083Y293025D01*
X382250Y293317D01*
X382542Y293525D01*
X382875Y293567D01*
X383208Y293483D01*
X383417Y293275D01*
X383583Y292983D01*
X383625Y292692D01*
X383583Y292400D01*
X383417Y292025D01*
X384500Y292150D01*
Y293275D01*
G01X371000Y240117D02*
X368500D01*
Y241783D01*
G01Y244050D02*
X371000D01*
X370500Y243550D01*
G01X368500D02*
Y244550D01*
G01X355730Y258271D02*
X348730D01*
Y244871D01*
X355730D01*
Y258271D01*
G01X371500Y271617D02*
X369000D01*
Y273283D01*
G01X371083Y274758D02*
X371333Y275008D01*
X371458Y275300D01*
X371500Y275633D01*
X371417Y276050D01*
X371208Y276342D01*
X370958Y276425D01*
X370708Y276383D01*
X370500Y276217D01*
X370083Y275383D01*
X369792Y275008D01*
X369375Y274758D01*
X369000Y274675D01*
Y276425D01*
G01X355728Y286387D02*
X348728D01*
Y272987D01*
X355728D01*
Y286387D01*
G01X371754Y256258D02*
X369254D01*
Y257924D01*
G01X369754Y259274D02*
X369462Y259524D01*
X369296Y259858D01*
X369254Y260233D01*
X369296Y260566D01*
X369504Y260899D01*
X369754Y261108D01*
X370004Y261149D01*
X370296Y261066D01*
X370504Y260774D01*
X370587Y260483D01*
Y260108D01*
G01Y260483D02*
X370712Y260733D01*
X370921Y260941D01*
X371171Y261024D01*
X371421Y260941D01*
X371629Y260733D01*
X371754Y260358D01*
X371712Y259983D01*
X371546Y259608D01*
G01X348754Y258941D02*
X355754D01*
Y272341D01*
X348754D01*
Y258941D01*
G01X371000Y285617D02*
X368500D01*
Y287283D01*
G01Y290050D02*
X371000D01*
X369208Y288508D01*
Y290592D01*
G01X348722Y287041D02*
X355722D01*
Y300441D01*
X348722D01*
Y287041D01*
G01X372298Y238661D02*
X374798D01*
Y239702D01*
X374673Y240036D01*
X374506Y240244D01*
X374173Y240327D01*
X373840Y240244D01*
X373631Y239994D01*
X373506Y239702D01*
Y238661D01*
G01Y239702D02*
X372298Y240327D01*
G01Y242594D02*
X374798D01*
X374298Y242094D01*
G01X372298D02*
Y243094D01*
G01X372673Y244777D02*
X372465Y245027D01*
X372340Y245319D01*
X372298Y245694D01*
X372381Y246069D01*
X372548Y246361D01*
X372840Y246569D01*
X373173Y246611D01*
X373506Y246527D01*
X373715Y246319D01*
X373881Y246027D01*
X373923Y245736D01*
X373881Y245444D01*
X373715Y245069D01*
X374798Y245194D01*
Y246319D01*
G01X372298Y248794D02*
X374798D01*
X374298Y248294D01*
G01X372298D02*
Y249294D01*
G01X360298Y248444D02*
X356298D01*
Y255844D01*
G01X373167Y269517D02*
X375667D01*
Y270558D01*
X375542Y270892D01*
X375375Y271100D01*
X375042Y271183D01*
X374709Y271100D01*
X374500Y270850D01*
X374375Y270558D01*
Y269517D01*
G01Y270558D02*
X373167Y271183D01*
G01Y273450D02*
X375667D01*
X375167Y272950D01*
G01X373167D02*
Y273950D01*
G01X373542Y275633D02*
X373334Y275883D01*
X373209Y276175D01*
X373167Y276550D01*
X373250Y276925D01*
X373417Y277217D01*
X373709Y277425D01*
X374042Y277467D01*
X374375Y277383D01*
X374584Y277175D01*
X374750Y276883D01*
X374792Y276592D01*
X374750Y276300D01*
X374584Y275925D01*
X375667Y276050D01*
Y277175D01*
G01X375250Y278858D02*
X375500Y279108D01*
X375625Y279400D01*
X375667Y279733D01*
X375584Y280150D01*
X375375Y280442D01*
X375125Y280525D01*
X374875Y280483D01*
X374667Y280317D01*
X374250Y279483D01*
X373959Y279108D01*
X373542Y278858D01*
X373167Y278775D01*
Y280525D01*
G01X360342Y276587D02*
X356342D01*
Y283987D01*
G01X373415Y254344D02*
X375915D01*
Y255385D01*
X375790Y255719D01*
X375623Y255927D01*
X375290Y256010D01*
X374957Y255927D01*
X374748Y255677D01*
X374623Y255385D01*
Y254344D01*
G01Y255385D02*
X373415Y256010D01*
G01Y258277D02*
X375915D01*
X375415Y257777D01*
G01X373415D02*
Y258777D01*
G01X373790Y260460D02*
X373582Y260710D01*
X373457Y261002D01*
X373415Y261377D01*
X373498Y261752D01*
X373665Y262044D01*
X373957Y262252D01*
X374290Y262294D01*
X374623Y262210D01*
X374832Y262002D01*
X374998Y261710D01*
X375040Y261419D01*
X374998Y261127D01*
X374832Y260752D01*
X375915Y260877D01*
Y262002D01*
G01X373915Y263560D02*
X373623Y263810D01*
X373457Y264144D01*
X373415Y264519D01*
X373457Y264852D01*
X373665Y265185D01*
X373915Y265394D01*
X374165Y265435D01*
X374457Y265352D01*
X374665Y265060D01*
X374748Y264769D01*
Y264394D01*
G01Y264769D02*
X374873Y265019D01*
X375082Y265227D01*
X375332Y265310D01*
X375582Y265227D01*
X375790Y265019D01*
X375915Y264644D01*
X375873Y264269D01*
X375707Y263894D01*
G01X356169Y270768D02*
X360169D01*
Y263368D01*
G01X372500Y283017D02*
X375000D01*
Y284058D01*
X374875Y284392D01*
X374708Y284600D01*
X374375Y284683D01*
X374042Y284600D01*
X373833Y284350D01*
X373708Y284058D01*
Y283017D01*
G01Y284058D02*
X372500Y284683D01*
G01Y286950D02*
X375000D01*
X374500Y286450D01*
G01X372500D02*
Y287450D01*
G01X372875Y289133D02*
X372667Y289383D01*
X372542Y289675D01*
X372500Y290050D01*
X372583Y290425D01*
X372750Y290717D01*
X373042Y290925D01*
X373375Y290967D01*
X373708Y290883D01*
X373917Y290675D01*
X374083Y290383D01*
X374125Y290092D01*
X374083Y289800D01*
X373917Y289425D01*
X375000Y289550D01*
Y290675D01*
G01X372500Y293650D02*
X375000D01*
X373208Y292108D01*
Y294192D01*
G01X356222Y298041D02*
X360222D01*
Y290641D01*
G01X379102Y240407D02*
X379227Y240157D01*
X379310Y239865D01*
Y239532D01*
X379185Y239157D01*
X378977Y238865D01*
X378727Y238657D01*
X378310Y238490D01*
X377935Y238448D01*
X377560Y238532D01*
X377310Y238657D01*
X377060Y238907D01*
X376893Y239198D01*
X376810Y239490D01*
Y239782D01*
X376893Y240073D01*
X377018Y240323D01*
X377185Y240532D01*
G01X376810Y242590D02*
X379310D01*
X378810Y242090D01*
G01X376810D02*
Y243090D01*
G01X377102Y244982D02*
X376893Y245273D01*
X376810Y245607D01*
X376893Y245940D01*
X377143Y246232D01*
X377518Y246440D01*
X377893Y246523D01*
X378352D01*
X378727Y246440D01*
X379060Y246232D01*
X379227Y245982D01*
X379310Y245690D01*
X379227Y245357D01*
X379060Y245107D01*
X378810Y244940D01*
X378477Y244857D01*
X378185Y244940D01*
X377893Y245148D01*
X377727Y245398D01*
X377685Y245690D01*
X377768Y246023D01*
X377977Y246273D01*
X378352Y246523D01*
G01X378893Y247998D02*
X379143Y248248D01*
X379268Y248540D01*
X379310Y248873D01*
X379227Y249290D01*
X379018Y249582D01*
X378768Y249665D01*
X378518Y249623D01*
X378310Y249457D01*
X377893Y248623D01*
X377602Y248248D01*
X377185Y247998D01*
X376810Y247915D01*
Y249665D01*
G01X379459Y268767D02*
X379584Y268517D01*
X379667Y268225D01*
Y267892D01*
X379542Y267517D01*
X379334Y267225D01*
X379084Y267017D01*
X378667Y266850D01*
X378292Y266808D01*
X377917Y266892D01*
X377667Y267017D01*
X377417Y267267D01*
X377250Y267558D01*
X377167Y267850D01*
Y268142D01*
X377250Y268433D01*
X377375Y268683D01*
X377542Y268892D01*
G01X377167Y270950D02*
X379667D01*
X379167Y270450D01*
G01X377167D02*
Y271450D01*
G01X377459Y273342D02*
X377250Y273633D01*
X377167Y273967D01*
X377250Y274300D01*
X377500Y274592D01*
X377875Y274800D01*
X378250Y274883D01*
X378709D01*
X379084Y274800D01*
X379417Y274592D01*
X379584Y274342D01*
X379667Y274050D01*
X379584Y273717D01*
X379417Y273467D01*
X379167Y273300D01*
X378834Y273217D01*
X378542Y273300D01*
X378250Y273508D01*
X378084Y273758D01*
X378042Y274050D01*
X378125Y274383D01*
X378334Y274633D01*
X378709Y274883D01*
G01X378209Y276358D02*
X378500Y276650D01*
X378667Y276900D01*
X378750Y277233D01*
X378667Y277525D01*
X378500Y277733D01*
X378250Y277900D01*
X377959Y277942D01*
X377709Y277900D01*
X377459Y277733D01*
X377250Y277483D01*
X377167Y277192D01*
X377250Y276858D01*
X377500Y276567D01*
X377875Y276400D01*
X378292Y276358D01*
X378834Y276442D01*
X379125Y276567D01*
X379417Y276775D01*
X379625Y277067D01*
X379667Y277358D01*
X379584Y277650D01*
X379375Y277858D01*
G01X379792Y256267D02*
X379917Y256017D01*
X380000Y255725D01*
Y255392D01*
X379875Y255017D01*
X379667Y254725D01*
X379417Y254517D01*
X379000Y254350D01*
X378625Y254308D01*
X378250Y254392D01*
X378000Y254517D01*
X377750Y254767D01*
X377583Y255058D01*
X377500Y255350D01*
Y255642D01*
X377583Y255933D01*
X377708Y256183D01*
X377875Y256392D01*
G01X379583Y257658D02*
X379833Y257908D01*
X379958Y258200D01*
X380000Y258533D01*
X379917Y258950D01*
X379708Y259242D01*
X379458Y259325D01*
X379208Y259283D01*
X379000Y259117D01*
X378583Y258283D01*
X378292Y257908D01*
X377875Y257658D01*
X377500Y257575D01*
Y259325D01*
G01X380000Y261550D02*
X379917Y261217D01*
X379708Y260967D01*
X379458Y260800D01*
X379125Y260675D01*
X378750Y260633D01*
X378375Y260675D01*
X378042Y260800D01*
X377792Y260967D01*
X377583Y261217D01*
X377500Y261550D01*
X377583Y261883D01*
X377792Y262133D01*
X378042Y262300D01*
X378375Y262425D01*
X378750Y262467D01*
X379125Y262425D01*
X379458Y262300D01*
X379708Y262133D01*
X379917Y261883D01*
X380000Y261550D01*
G01Y264650D02*
X379917Y264317D01*
X379708Y264067D01*
X379458Y263900D01*
X379125Y263775D01*
X378750Y263733D01*
X378375Y263775D01*
X378042Y263900D01*
X377792Y264067D01*
X377583Y264317D01*
X377500Y264650D01*
X377583Y264983D01*
X377792Y265233D01*
X378042Y265400D01*
X378375Y265525D01*
X378750Y265567D01*
X379125Y265525D01*
X379458Y265400D01*
X379708Y265233D01*
X379917Y264983D01*
X380000Y264650D01*
G01X379792Y284267D02*
X379917Y284017D01*
X380000Y283725D01*
Y283392D01*
X379875Y283017D01*
X379667Y282725D01*
X379417Y282517D01*
X379000Y282350D01*
X378625Y282308D01*
X378250Y282392D01*
X378000Y282517D01*
X377750Y282767D01*
X377583Y283058D01*
X377500Y283350D01*
Y283642D01*
X377583Y283933D01*
X377708Y284183D01*
X377875Y284392D01*
G01X379583Y285658D02*
X379833Y285908D01*
X379958Y286200D01*
X380000Y286533D01*
X379917Y286950D01*
X379708Y287242D01*
X379458Y287325D01*
X379208Y287283D01*
X379000Y287117D01*
X378583Y286283D01*
X378292Y285908D01*
X377875Y285658D01*
X377500Y285575D01*
Y287325D01*
G01X380000Y289550D02*
X379917Y289217D01*
X379708Y288967D01*
X379458Y288800D01*
X379125Y288675D01*
X378750Y288633D01*
X378375Y288675D01*
X378042Y288800D01*
X377792Y288967D01*
X377583Y289217D01*
X377500Y289550D01*
X377583Y289883D01*
X377792Y290133D01*
X378042Y290300D01*
X378375Y290425D01*
X378750Y290467D01*
X379125Y290425D01*
X379458Y290300D01*
X379708Y290133D01*
X379917Y289883D01*
X380000Y289550D01*
G01X377500Y293150D02*
X380000D01*
X378208Y291608D01*
Y293692D01*
G01X391700Y298000D02*
Y295500D01*
G01X392658Y298000D02*
X390742D01*
G01X389433Y295500D02*
Y298000D01*
X388433D01*
X388100Y297875D01*
X387850Y297583D01*
X387767Y297250D01*
X387850Y296917D01*
X388058Y296667D01*
X388433Y296542D01*
X389433D01*
G01X385500Y295500D02*
Y298000D01*
X386000Y297500D01*
G01Y295500D02*
X385000D01*
G01X383192Y296542D02*
X382900Y296833D01*
X382650Y297000D01*
X382317Y297083D01*
X382025Y297000D01*
X381817Y296833D01*
X381650Y296583D01*
X381608Y296292D01*
X381650Y296042D01*
X381817Y295792D01*
X382067Y295583D01*
X382358Y295500D01*
X382692Y295583D01*
X382983Y295833D01*
X383150Y296208D01*
X383192Y296625D01*
X383108Y297167D01*
X382983Y297458D01*
X382775Y297750D01*
X382483Y297958D01*
X382192Y298000D01*
X381900Y297917D01*
X381692Y297708D01*
G01X379300Y295500D02*
X379008Y295542D01*
X378675Y295667D01*
X378467Y295875D01*
X378383Y296167D01*
X378467Y296458D01*
X378717Y296708D01*
X379092Y296833D01*
X379508D01*
X379758Y296917D01*
X379967Y297125D01*
X380050Y297417D01*
X379925Y297708D01*
X379633Y297917D01*
X379300Y298000D01*
X378967Y297917D01*
X378675Y297708D01*
X378550Y297417D01*
X378633Y297125D01*
X378842Y296917D01*
X379092Y296833D01*
X379508D01*
X379883Y296708D01*
X380133Y296458D01*
X380217Y296167D01*
X380133Y295875D01*
X379925Y295667D01*
X379592Y295542D01*
X379300Y295500D01*
G01X377983Y348500D02*
Y351000D01*
X376942D01*
X376608Y350875D01*
X376400Y350708D01*
X376317Y350375D01*
X376400Y350042D01*
X376650Y349833D01*
X376942Y349708D01*
X377983D01*
G01X376942D02*
X376317Y348500D01*
G01X374050D02*
Y351000D01*
X374550Y350500D01*
G01Y348500D02*
X373550D01*
G01X371867Y349000D02*
X371617Y348708D01*
X371283Y348542D01*
X370908Y348500D01*
X370575Y348542D01*
X370242Y348750D01*
X370033Y349000D01*
X369992Y349250D01*
X370075Y349542D01*
X370367Y349750D01*
X370658Y349833D01*
X371033D01*
G01X370658D02*
X370408Y349958D01*
X370200Y350167D01*
X370117Y350417D01*
X370200Y350667D01*
X370408Y350875D01*
X370783Y351000D01*
X371158Y350958D01*
X371533Y350792D01*
G01X368767Y348875D02*
X368517Y348667D01*
X368225Y348542D01*
X367850Y348500D01*
X367475Y348583D01*
X367183Y348750D01*
X366975Y349042D01*
X366933Y349375D01*
X367017Y349708D01*
X367225Y349917D01*
X367517Y350083D01*
X367808Y350125D01*
X368100Y350083D01*
X368475Y349917D01*
X368350Y351000D01*
X367225D01*
G01X377098Y343070D02*
Y339070D01*
X369698D01*
G01X386863Y318543D02*
Y321043D01*
X385822D01*
X385488Y320918D01*
X385280Y320751D01*
X385197Y320418D01*
X385280Y320085D01*
X385530Y319876D01*
X385822Y319751D01*
X386863D01*
G01X385822D02*
X385197Y318543D01*
G01X383722Y320626D02*
X383472Y320876D01*
X383180Y321001D01*
X382847Y321043D01*
X382430Y320960D01*
X382138Y320751D01*
X382055Y320501D01*
X382097Y320251D01*
X382263Y320043D01*
X383097Y319626D01*
X383472Y319335D01*
X383722Y318918D01*
X383805Y318543D01*
X382055D01*
G01X379830Y321043D02*
X380163Y320960D01*
X380413Y320751D01*
X380580Y320501D01*
X380705Y320168D01*
X380747Y319793D01*
X380705Y319418D01*
X380580Y319085D01*
X380413Y318835D01*
X380163Y318626D01*
X379830Y318543D01*
X379497Y318626D01*
X379247Y318835D01*
X379080Y319085D01*
X378955Y319418D01*
X378913Y319793D01*
X378955Y320168D01*
X379080Y320501D01*
X379247Y320751D01*
X379497Y320960D01*
X379830Y321043D01*
G01X376813Y318543D02*
X376730Y319085D01*
X376605Y319543D01*
X376438Y319960D01*
X376230Y320418D01*
X375897Y321043D01*
X377563D01*
G01X382184Y312847D02*
Y308847D01*
X374784D01*
G01X386863Y322543D02*
Y325043D01*
X385822D01*
X385488Y324918D01*
X385280Y324751D01*
X385197Y324418D01*
X385280Y324085D01*
X385530Y323876D01*
X385822Y323751D01*
X386863D01*
G01X385822D02*
X385197Y322543D01*
G01X383847Y323043D02*
X383597Y322751D01*
X383263Y322585D01*
X382888Y322543D01*
X382555Y322585D01*
X382222Y322793D01*
X382013Y323043D01*
X381972Y323293D01*
X382055Y323585D01*
X382347Y323793D01*
X382638Y323876D01*
X383013D01*
G01X382638D02*
X382388Y324001D01*
X382180Y324210D01*
X382097Y324460D01*
X382180Y324710D01*
X382388Y324918D01*
X382763Y325043D01*
X383138Y325001D01*
X383513Y324835D01*
G01X379830Y322543D02*
Y325043D01*
X380330Y324543D01*
G01Y322543D02*
X379330D01*
G01X376730Y325043D02*
X377063Y324960D01*
X377313Y324751D01*
X377480Y324501D01*
X377605Y324168D01*
X377647Y323793D01*
X377605Y323418D01*
X377480Y323085D01*
X377313Y322835D01*
X377063Y322626D01*
X376730Y322543D01*
X376397Y322626D01*
X376147Y322835D01*
X375980Y323085D01*
X375855Y323418D01*
X375813Y323793D01*
X375855Y324168D01*
X375980Y324501D01*
X376147Y324751D01*
X376397Y324960D01*
X376730Y325043D01*
G01X375683Y312895D02*
Y316895D01*
X383083D01*
G01X387233Y341292D02*
X387483Y341417D01*
X387775Y341500D01*
X388108D01*
X388483Y341375D01*
X388775Y341167D01*
X388983Y340917D01*
X389150Y340500D01*
X389192Y340125D01*
X389108Y339750D01*
X388983Y339500D01*
X388733Y339250D01*
X388442Y339083D01*
X388150Y339000D01*
X387858D01*
X387567Y339083D01*
X387317Y339208D01*
X387108Y339375D01*
G01X385050Y339000D02*
Y341500D01*
X385550Y341000D01*
G01Y339000D02*
X384550D01*
G01X381950D02*
Y341500D01*
X382450Y341000D01*
G01Y339000D02*
X381450D01*
G01X378350D02*
Y341500D01*
X379892Y339708D01*
X377808D01*
G01X343900Y369200D02*
Y301800D01*
G01X381500Y300617D02*
X379000D01*
Y302283D01*
G01X379375Y303633D02*
X379167Y303883D01*
X379042Y304175D01*
X379000Y304550D01*
X379083Y304925D01*
X379250Y305217D01*
X379542Y305425D01*
X379875Y305467D01*
X380208Y305383D01*
X380417Y305175D01*
X380583Y304883D01*
X380625Y304592D01*
X380583Y304300D01*
X380417Y303925D01*
X381500Y304050D01*
Y305175D01*
G01X355714Y314462D02*
X348714D01*
Y301062D01*
X355714D01*
Y314462D01*
G01X383214Y300379D02*
X385714D01*
Y301420D01*
X385589Y301754D01*
X385422Y301962D01*
X385089Y302045D01*
X384756Y301962D01*
X384547Y301712D01*
X384422Y301420D01*
Y300379D01*
G01Y301420D02*
X383214Y302045D01*
G01Y304312D02*
X385714D01*
X385214Y303812D01*
G01X383214D02*
Y304812D01*
G01X383589Y306495D02*
X383381Y306745D01*
X383256Y307037D01*
X383214Y307412D01*
X383297Y307787D01*
X383464Y308079D01*
X383756Y308287D01*
X384089Y308329D01*
X384422Y308245D01*
X384631Y308037D01*
X384797Y307745D01*
X384839Y307454D01*
X384797Y307162D01*
X384631Y306787D01*
X385714Y306912D01*
Y308037D01*
G01X383589Y309595D02*
X383381Y309845D01*
X383256Y310137D01*
X383214Y310512D01*
X383297Y310887D01*
X383464Y311179D01*
X383756Y311387D01*
X384089Y311429D01*
X384422Y311345D01*
X384631Y311137D01*
X384797Y310845D01*
X384839Y310554D01*
X384797Y310262D01*
X384631Y309887D01*
X385714Y310012D01*
Y311137D01*
G01X360214Y304662D02*
X356214D01*
Y312062D01*
G01X389469Y302329D02*
X389594Y302079D01*
X389677Y301787D01*
Y301454D01*
X389552Y301079D01*
X389344Y300787D01*
X389094Y300579D01*
X388677Y300412D01*
X388302Y300370D01*
X387927Y300454D01*
X387677Y300579D01*
X387427Y300829D01*
X387260Y301120D01*
X387177Y301412D01*
Y301704D01*
X387260Y301995D01*
X387385Y302245D01*
X387552Y302454D01*
G01X389260Y303720D02*
X389510Y303970D01*
X389635Y304262D01*
X389677Y304595D01*
X389594Y305012D01*
X389385Y305304D01*
X389135Y305387D01*
X388885Y305345D01*
X388677Y305179D01*
X388260Y304345D01*
X387969Y303970D01*
X387552Y303720D01*
X387177Y303637D01*
Y305387D01*
G01X389677Y307612D02*
X389594Y307279D01*
X389385Y307029D01*
X389135Y306862D01*
X388802Y306737D01*
X388427Y306695D01*
X388052Y306737D01*
X387719Y306862D01*
X387469Y307029D01*
X387260Y307279D01*
X387177Y307612D01*
X387260Y307945D01*
X387469Y308195D01*
X387719Y308362D01*
X388052Y308487D01*
X388427Y308529D01*
X388802Y308487D01*
X389135Y308362D01*
X389385Y308195D01*
X389594Y307945D01*
X389677Y307612D01*
G01X387177Y310712D02*
X387219Y311004D01*
X387344Y311337D01*
X387552Y311545D01*
X387844Y311629D01*
X388135Y311545D01*
X388385Y311295D01*
X388510Y310920D01*
Y310504D01*
X388594Y310254D01*
X388802Y310045D01*
X389094Y309962D01*
X389385Y310087D01*
X389594Y310379D01*
X389677Y310712D01*
X389594Y311045D01*
X389385Y311337D01*
X389094Y311462D01*
X388802Y311379D01*
X388594Y311170D01*
X388510Y310920D01*
Y310504D01*
X388385Y310129D01*
X388135Y309879D01*
X387844Y309795D01*
X387552Y309879D01*
X387344Y310087D01*
X387219Y310420D01*
X387177Y310712D01*
G01X377650Y346500D02*
Y344000D01*
G01X378608Y346500D02*
X376692D01*
G01X375383Y344000D02*
Y346500D01*
X374383D01*
X374050Y346375D01*
X373800Y346083D01*
X373717Y345750D01*
X373800Y345417D01*
X374008Y345167D01*
X374383Y345042D01*
X375383D01*
G01X372242Y346083D02*
X371992Y346333D01*
X371700Y346458D01*
X371367Y346500D01*
X370950Y346417D01*
X370658Y346208D01*
X370575Y345958D01*
X370617Y345708D01*
X370783Y345500D01*
X371617Y345083D01*
X371992Y344792D01*
X372242Y344375D01*
X372325Y344000D01*
X370575D01*
G01X368350D02*
X368058Y344042D01*
X367725Y344167D01*
X367517Y344375D01*
X367433Y344667D01*
X367517Y344958D01*
X367767Y345208D01*
X368142Y345333D01*
X368558D01*
X368808Y345417D01*
X369017Y345625D01*
X369100Y345917D01*
X368975Y346208D01*
X368683Y346417D01*
X368350Y346500D01*
X368017Y346417D01*
X367725Y346208D01*
X367600Y345917D01*
X367683Y345625D01*
X367892Y345417D01*
X368142Y345333D01*
X368558D01*
X368933Y345208D01*
X369183Y344958D01*
X369267Y344667D01*
X369183Y344375D01*
X368975Y344167D01*
X368642Y344042D01*
X368350Y344000D01*
G01X357517Y342000D02*
Y340208D01*
X357350Y339833D01*
X357017Y339583D01*
X356600Y339500D01*
X356183Y339583D01*
X355850Y339833D01*
X355683Y340208D01*
Y342000D01*
G01X354292Y341583D02*
X354042Y341833D01*
X353750Y341958D01*
X353417Y342000D01*
X353000Y341917D01*
X352708Y341708D01*
X352625Y341458D01*
X352667Y341208D01*
X352833Y341000D01*
X353667Y340583D01*
X354042Y340292D01*
X354292Y339875D01*
X354375Y339500D01*
X352625D01*
G01X351317Y340000D02*
X351067Y339708D01*
X350733Y339542D01*
X350358Y339500D01*
X350025Y339542D01*
X349692Y339750D01*
X349483Y340000D01*
X349442Y340250D01*
X349525Y340542D01*
X349817Y340750D01*
X350108Y340833D01*
X350483D01*
G01X350108D02*
X349858Y340958D01*
X349650Y341167D01*
X349567Y341417D01*
X349650Y341667D01*
X349858Y341875D01*
X350233Y342000D01*
X350608Y341958D01*
X350983Y341792D01*
G01X360950Y325200D02*
X362550Y323600D01*
G01Y326800D02*
X360950Y325200D01*
G01X362550Y327500D02*
Y322900D01*
G01X348050Y327500D02*
X362550D01*
G01X348050Y322900D02*
Y327500D01*
G01X362550Y322900D02*
X348050D01*
G01X368517Y342000D02*
Y340208D01*
X368350Y339833D01*
X368017Y339583D01*
X367600Y339500D01*
X367183Y339583D01*
X366850Y339833D01*
X366683Y340208D01*
Y342000D01*
G01X364000Y339500D02*
Y342000D01*
X365542Y340208D01*
X363458D01*
G01X362192Y341583D02*
X361942Y341833D01*
X361650Y341958D01*
X361317Y342000D01*
X360900Y341917D01*
X360608Y341708D01*
X360525Y341458D01*
X360567Y341208D01*
X360733Y341000D01*
X361567Y340583D01*
X361942Y340292D01*
X362192Y339875D01*
X362275Y339500D01*
X360525D01*
G01X362600Y326435D02*
X362860D01*
X364295Y325000D01*
X362860Y323565D01*
G01X362600Y326435D02*
Y323565D01*
X373600D01*
G01Y326435D02*
X362600D01*
G01X373600D02*
Y323565D01*
G01X446000Y168500D02*
X443500D01*
G01X439500D02*
X437500D01*
G01X434000D02*
X431500D01*
G01X428000D02*
X425500D01*
G01X422000D02*
X420500D01*
G01X411500D02*
X410500D01*
G01X405000D02*
X403500D01*
G01X398000D02*
X396779D01*
G01X392150Y168531D02*
X390856D01*
G01X416500Y168500D02*
X415000D01*
G01X401500Y178500D02*
X404000D01*
G01X407500D02*
X410000D01*
G01X413500D02*
X416000D01*
G01X426000D02*
X428000D01*
G01X431500D02*
X434000D01*
G01X443500D02*
X446000D01*
G01X438500D02*
X440000D01*
G01X477130Y286000D02*
Y281500D01*
X478500D01*
Y274500D01*
X426500D01*
Y267000D01*
X396000D01*
Y258000D01*
X404000D01*
Y249500D01*
X415000D01*
Y222500D01*
X488000D01*
G01X420099Y178500D02*
X422000D01*
G01X390027D02*
X392000D01*
G01X396304D02*
X398000D01*
G01X404292Y232267D02*
X404417Y232017D01*
X404500Y231725D01*
Y231392D01*
X404375Y231017D01*
X404167Y230725D01*
X403917Y230517D01*
X403500Y230350D01*
X403125Y230308D01*
X402750Y230392D01*
X402500Y230517D01*
X402250Y230767D01*
X402083Y231058D01*
X402000Y231350D01*
Y231642D01*
X402083Y231933D01*
X402208Y232183D01*
X402375Y232392D01*
G01X402000Y234450D02*
X404500D01*
X404000Y233950D01*
G01X402000D02*
Y234950D01*
G01X402375Y236633D02*
X402167Y236883D01*
X402042Y237175D01*
X402000Y237550D01*
X402083Y237925D01*
X402250Y238217D01*
X402542Y238425D01*
X402875Y238467D01*
X403208Y238383D01*
X403417Y238175D01*
X403583Y237883D01*
X403625Y237592D01*
X403583Y237300D01*
X403417Y236925D01*
X404500Y237050D01*
Y238175D01*
G01X402375Y239733D02*
X402167Y239983D01*
X402042Y240275D01*
X402000Y240650D01*
X402083Y241025D01*
X402250Y241317D01*
X402542Y241525D01*
X402875Y241567D01*
X403208Y241483D01*
X403417Y241275D01*
X403583Y240983D01*
X403625Y240692D01*
X403583Y240400D01*
X403417Y240025D01*
X404500Y240150D01*
Y241275D01*
G01X408792Y225267D02*
X408917Y225017D01*
X409000Y224725D01*
Y224392D01*
X408875Y224017D01*
X408667Y223725D01*
X408417Y223517D01*
X408000Y223350D01*
X407625Y223308D01*
X407250Y223392D01*
X407000Y223517D01*
X406750Y223767D01*
X406583Y224058D01*
X406500Y224350D01*
Y224642D01*
X406583Y224933D01*
X406708Y225183D01*
X406875Y225392D01*
G01X406500Y227450D02*
X409000D01*
X408500Y226950D01*
G01X406500D02*
Y227950D01*
G01X406875Y229633D02*
X406667Y229883D01*
X406542Y230175D01*
X406500Y230550D01*
X406583Y230925D01*
X406750Y231217D01*
X407042Y231425D01*
X407375Y231467D01*
X407708Y231383D01*
X407917Y231175D01*
X408083Y230883D01*
X408125Y230592D01*
X408083Y230300D01*
X407917Y229925D01*
X409000Y230050D01*
Y231175D01*
G01X408583Y232858D02*
X408833Y233108D01*
X408958Y233400D01*
X409000Y233733D01*
X408917Y234150D01*
X408708Y234442D01*
X408458Y234525D01*
X408208Y234483D01*
X408000Y234317D01*
X407583Y233483D01*
X407292Y233108D01*
X406875Y232858D01*
X406500Y232775D01*
Y234525D01*
G01X393292Y234267D02*
X393417Y234017D01*
X393500Y233725D01*
Y233392D01*
X393375Y233017D01*
X393167Y232725D01*
X392917Y232517D01*
X392500Y232350D01*
X392125Y232308D01*
X391750Y232392D01*
X391500Y232517D01*
X391250Y232767D01*
X391083Y233058D01*
X391000Y233350D01*
Y233642D01*
X391083Y233933D01*
X391208Y234183D01*
X391375Y234392D01*
G01X391000Y236450D02*
X393500D01*
X393000Y235950D01*
G01X391000D02*
Y236950D01*
G01X391500Y238633D02*
X391208Y238883D01*
X391042Y239217D01*
X391000Y239592D01*
X391042Y239925D01*
X391250Y240258D01*
X391500Y240467D01*
X391750Y240508D01*
X392042Y240425D01*
X392250Y240133D01*
X392333Y239842D01*
Y239467D01*
G01Y239842D02*
X392458Y240092D01*
X392667Y240300D01*
X392917Y240383D01*
X393167Y240300D01*
X393375Y240092D01*
X393500Y239717D01*
X393458Y239342D01*
X393292Y238967D01*
G01X393083Y241858D02*
X393333Y242108D01*
X393458Y242400D01*
X393500Y242733D01*
X393417Y243150D01*
X393208Y243442D01*
X392958Y243525D01*
X392708Y243483D01*
X392500Y243317D01*
X392083Y242483D01*
X391792Y242108D01*
X391375Y241858D01*
X391000Y241775D01*
Y243525D01*
G01X450592Y199267D02*
X450717Y199017D01*
X450800Y198725D01*
Y198392D01*
X450675Y198017D01*
X450467Y197725D01*
X450217Y197517D01*
X449800Y197350D01*
X449425Y197308D01*
X449050Y197392D01*
X448800Y197517D01*
X448550Y197767D01*
X448383Y198058D01*
X448300Y198350D01*
Y198642D01*
X448383Y198933D01*
X448508Y199183D01*
X448675Y199392D01*
G01X450383Y200658D02*
X450633Y200908D01*
X450758Y201200D01*
X450800Y201533D01*
X450717Y201950D01*
X450508Y202242D01*
X450258Y202325D01*
X450008Y202283D01*
X449800Y202117D01*
X449383Y201283D01*
X449092Y200908D01*
X448675Y200658D01*
X448300Y200575D01*
Y202325D01*
G01X448800Y203633D02*
X448508Y203883D01*
X448342Y204217D01*
X448300Y204592D01*
X448342Y204925D01*
X448550Y205258D01*
X448800Y205467D01*
X449050Y205508D01*
X449342Y205425D01*
X449550Y205133D01*
X449633Y204842D01*
Y204467D01*
G01Y204842D02*
X449758Y205092D01*
X449967Y205300D01*
X450217Y205383D01*
X450467Y205300D01*
X450675Y205092D01*
X450800Y204717D01*
X450758Y204342D01*
X450592Y203967D01*
G01X448800Y206733D02*
X448508Y206983D01*
X448342Y207317D01*
X448300Y207692D01*
X448342Y208025D01*
X448550Y208358D01*
X448800Y208567D01*
X449050Y208608D01*
X449342Y208525D01*
X449550Y208233D01*
X449633Y207942D01*
Y207567D01*
G01Y207942D02*
X449758Y208192D01*
X449967Y208400D01*
X450217Y208483D01*
X450467Y208400D01*
X450675Y208192D01*
X450800Y207817D01*
X450758Y207442D01*
X450592Y207067D01*
G01X419933Y246233D02*
X419400Y246583D01*
X419000Y247167D01*
X418733Y247983D01*
X419000Y248683D01*
X419533Y249150D01*
X420467Y249500D01*
X424067D01*
Y242500D01*
X419667D01*
X418733Y242967D01*
X418200Y243667D01*
X417933Y244483D01*
X418200Y245300D01*
X419000Y246000D01*
X419933Y246233D01*
X424067D01*
G01X407233Y247292D02*
X407483Y247417D01*
X407775Y247500D01*
X408108D01*
X408483Y247375D01*
X408775Y247167D01*
X408983Y246917D01*
X409150Y246500D01*
X409192Y246125D01*
X409108Y245750D01*
X408983Y245500D01*
X408733Y245250D01*
X408442Y245083D01*
X408150Y245000D01*
X407858D01*
X407567Y245083D01*
X407317Y245208D01*
X407108Y245375D01*
G01X405842Y247083D02*
X405592Y247333D01*
X405300Y247458D01*
X404967Y247500D01*
X404550Y247417D01*
X404258Y247208D01*
X404175Y246958D01*
X404217Y246708D01*
X404383Y246500D01*
X405217Y246083D01*
X405592Y245792D01*
X405842Y245375D01*
X405925Y245000D01*
X404175D01*
G01X401950Y247500D02*
X402283Y247417D01*
X402533Y247208D01*
X402700Y246958D01*
X402825Y246625D01*
X402867Y246250D01*
X402825Y245875D01*
X402700Y245542D01*
X402533Y245292D01*
X402283Y245083D01*
X401950Y245000D01*
X401617Y245083D01*
X401367Y245292D01*
X401200Y245542D01*
X401075Y245875D01*
X401033Y246250D01*
X401075Y246625D01*
X401200Y246958D01*
X401367Y247208D01*
X401617Y247417D01*
X401950Y247500D01*
G01X399642Y247083D02*
X399392Y247333D01*
X399100Y247458D01*
X398767Y247500D01*
X398350Y247417D01*
X398058Y247208D01*
X397975Y246958D01*
X398017Y246708D01*
X398183Y246500D01*
X399017Y246083D01*
X399392Y245792D01*
X399642Y245375D01*
X399725Y245000D01*
X397975D01*
G01X421450Y271741D02*
X421575Y271491D01*
X421658Y271199D01*
Y270866D01*
X421533Y270491D01*
X421325Y270199D01*
X421075Y269991D01*
X420658Y269824D01*
X420283Y269782D01*
X419908Y269866D01*
X419658Y269991D01*
X419408Y270241D01*
X419241Y270532D01*
X419158Y270824D01*
Y271116D01*
X419241Y271407D01*
X419366Y271657D01*
X419533Y271866D01*
G01X419158Y273924D02*
X421658D01*
X421158Y273424D01*
G01X419158D02*
Y274424D01*
G01Y277024D02*
X419200Y277316D01*
X419325Y277649D01*
X419533Y277857D01*
X419825Y277941D01*
X420116Y277857D01*
X420366Y277607D01*
X420491Y277232D01*
Y276816D01*
X420575Y276566D01*
X420783Y276357D01*
X421075Y276274D01*
X421366Y276399D01*
X421575Y276691D01*
X421658Y277024D01*
X421575Y277357D01*
X421366Y277649D01*
X421075Y277774D01*
X420783Y277691D01*
X420575Y277482D01*
X420491Y277232D01*
Y276816D01*
X420366Y276441D01*
X420116Y276191D01*
X419825Y276107D01*
X419533Y276191D01*
X419325Y276399D01*
X419200Y276732D01*
X419158Y277024D01*
G01X419450Y279416D02*
X419241Y279707D01*
X419158Y280041D01*
X419241Y280374D01*
X419491Y280666D01*
X419866Y280874D01*
X420241Y280957D01*
X420700D01*
X421075Y280874D01*
X421408Y280666D01*
X421575Y280416D01*
X421658Y280124D01*
X421575Y279791D01*
X421408Y279541D01*
X421158Y279374D01*
X420825Y279291D01*
X420533Y279374D01*
X420241Y279582D01*
X420075Y279832D01*
X420033Y280124D01*
X420116Y280457D01*
X420325Y280707D01*
X420700Y280957D01*
G01X425292Y271767D02*
X425417Y271517D01*
X425500Y271225D01*
Y270892D01*
X425375Y270517D01*
X425167Y270225D01*
X424917Y270017D01*
X424500Y269850D01*
X424125Y269808D01*
X423750Y269892D01*
X423500Y270017D01*
X423250Y270267D01*
X423083Y270558D01*
X423000Y270850D01*
Y271142D01*
X423083Y271433D01*
X423208Y271683D01*
X423375Y271892D01*
G01X423000Y273950D02*
X425500D01*
X425000Y273450D01*
G01X423000D02*
Y274450D01*
G01Y277050D02*
X423042Y277342D01*
X423167Y277675D01*
X423375Y277883D01*
X423667Y277967D01*
X423958Y277883D01*
X424208Y277633D01*
X424333Y277258D01*
Y276842D01*
X424417Y276592D01*
X424625Y276383D01*
X424917Y276300D01*
X425208Y276425D01*
X425417Y276717D01*
X425500Y277050D01*
X425417Y277383D01*
X425208Y277675D01*
X424917Y277800D01*
X424625Y277717D01*
X424417Y277508D01*
X424333Y277258D01*
Y276842D01*
X424208Y276467D01*
X423958Y276217D01*
X423667Y276133D01*
X423375Y276217D01*
X423167Y276425D01*
X423042Y276758D01*
X423000Y277050D01*
G01Y280150D02*
X423042Y280442D01*
X423167Y280775D01*
X423375Y280983D01*
X423667Y281067D01*
X423958Y280983D01*
X424208Y280733D01*
X424333Y280358D01*
Y279942D01*
X424417Y279692D01*
X424625Y279483D01*
X424917Y279400D01*
X425208Y279525D01*
X425417Y279817D01*
X425500Y280150D01*
X425417Y280483D01*
X425208Y280775D01*
X424917Y280900D01*
X424625Y280817D01*
X424417Y280608D01*
X424333Y280358D01*
Y279942D01*
X424208Y279567D01*
X423958Y279317D01*
X423667Y279233D01*
X423375Y279317D01*
X423167Y279525D01*
X423042Y279858D01*
X423000Y280150D01*
G01X417792Y271967D02*
X417917Y271717D01*
X418000Y271425D01*
Y271092D01*
X417875Y270717D01*
X417667Y270425D01*
X417417Y270217D01*
X417000Y270050D01*
X416625Y270008D01*
X416250Y270092D01*
X416000Y270217D01*
X415750Y270467D01*
X415583Y270758D01*
X415500Y271050D01*
Y271342D01*
X415583Y271633D01*
X415708Y271883D01*
X415875Y272092D01*
G01X415500Y274150D02*
X418000D01*
X417500Y273650D01*
G01X415500D02*
Y274650D01*
G01Y277250D02*
X415542Y277542D01*
X415667Y277875D01*
X415875Y278083D01*
X416167Y278167D01*
X416458Y278083D01*
X416708Y277833D01*
X416833Y277458D01*
Y277042D01*
X416917Y276792D01*
X417125Y276583D01*
X417417Y276500D01*
X417708Y276625D01*
X417917Y276917D01*
X418000Y277250D01*
X417917Y277583D01*
X417708Y277875D01*
X417417Y278000D01*
X417125Y277917D01*
X416917Y277708D01*
X416833Y277458D01*
Y277042D01*
X416708Y276667D01*
X416458Y276417D01*
X416167Y276333D01*
X415875Y276417D01*
X415667Y276625D01*
X415542Y276958D01*
X415500Y277250D01*
G01Y280267D02*
X416042Y280350D01*
X416500Y280475D01*
X416917Y280642D01*
X417375Y280850D01*
X418000Y281183D01*
Y279517D01*
G01X440292Y288267D02*
X440417Y288017D01*
X440500Y287725D01*
Y287392D01*
X440375Y287017D01*
X440167Y286725D01*
X439917Y286517D01*
X439500Y286350D01*
X439125Y286308D01*
X438750Y286392D01*
X438500Y286517D01*
X438250Y286767D01*
X438083Y287058D01*
X438000Y287350D01*
Y287642D01*
X438083Y287933D01*
X438208Y288183D01*
X438375Y288392D01*
G01X438000Y290450D02*
X440500D01*
X440000Y289950D01*
G01X438000D02*
Y290950D01*
G01X440083Y292758D02*
X440333Y293008D01*
X440458Y293300D01*
X440500Y293633D01*
X440417Y294050D01*
X440208Y294342D01*
X439958Y294425D01*
X439708Y294383D01*
X439500Y294217D01*
X439083Y293383D01*
X438792Y293008D01*
X438375Y292758D01*
X438000Y292675D01*
Y294425D01*
G01Y296567D02*
X438542Y296650D01*
X439000Y296775D01*
X439417Y296942D01*
X439875Y297150D01*
X440500Y297483D01*
Y295817D01*
G01X415692Y284767D02*
X415817Y284517D01*
X415900Y284225D01*
Y283892D01*
X415775Y283517D01*
X415567Y283225D01*
X415317Y283017D01*
X414900Y282850D01*
X414525Y282808D01*
X414150Y282892D01*
X413900Y283017D01*
X413650Y283267D01*
X413483Y283558D01*
X413400Y283850D01*
Y284142D01*
X413483Y284433D01*
X413608Y284683D01*
X413775Y284892D01*
G01X413400Y286950D02*
X415900D01*
X415400Y286450D01*
G01X413400D02*
Y287450D01*
G01X413775Y289133D02*
X413567Y289383D01*
X413442Y289675D01*
X413400Y290050D01*
X413483Y290425D01*
X413650Y290717D01*
X413942Y290925D01*
X414275Y290967D01*
X414608Y290883D01*
X414817Y290675D01*
X414983Y290383D01*
X415025Y290092D01*
X414983Y289800D01*
X414817Y289425D01*
X415900Y289550D01*
Y290675D01*
G01Y293150D02*
X415817Y292817D01*
X415608Y292567D01*
X415358Y292400D01*
X415025Y292275D01*
X414650Y292233D01*
X414275Y292275D01*
X413942Y292400D01*
X413692Y292567D01*
X413483Y292817D01*
X413400Y293150D01*
X413483Y293483D01*
X413692Y293733D01*
X413942Y293900D01*
X414275Y294025D01*
X414650Y294067D01*
X415025Y294025D01*
X415358Y293900D01*
X415608Y293733D01*
X415817Y293483D01*
X415900Y293150D01*
G01X403592Y284767D02*
X403717Y284517D01*
X403800Y284225D01*
Y283892D01*
X403675Y283517D01*
X403467Y283225D01*
X403217Y283017D01*
X402800Y282850D01*
X402425Y282808D01*
X402050Y282892D01*
X401800Y283017D01*
X401550Y283267D01*
X401383Y283558D01*
X401300Y283850D01*
Y284142D01*
X401383Y284433D01*
X401508Y284683D01*
X401675Y284892D01*
G01X401300Y286950D02*
X403800D01*
X403300Y286450D01*
G01X401300D02*
Y287450D01*
G01Y290550D02*
X403800D01*
X402008Y289008D01*
Y291092D01*
G01X401300Y293150D02*
X401342Y293442D01*
X401467Y293775D01*
X401675Y293983D01*
X401967Y294067D01*
X402258Y293983D01*
X402508Y293733D01*
X402633Y293358D01*
Y292942D01*
X402717Y292692D01*
X402925Y292483D01*
X403217Y292400D01*
X403508Y292525D01*
X403717Y292817D01*
X403800Y293150D01*
X403717Y293483D01*
X403508Y293775D01*
X403217Y293900D01*
X402925Y293817D01*
X402717Y293608D01*
X402633Y293358D01*
Y292942D01*
X402508Y292567D01*
X402258Y292317D01*
X401967Y292233D01*
X401675Y292317D01*
X401467Y292525D01*
X401342Y292858D01*
X401300Y293150D01*
G01X436459Y288267D02*
X436584Y288017D01*
X436667Y287725D01*
Y287392D01*
X436542Y287017D01*
X436334Y286725D01*
X436084Y286517D01*
X435667Y286350D01*
X435292Y286308D01*
X434917Y286392D01*
X434667Y286517D01*
X434417Y286767D01*
X434250Y287058D01*
X434167Y287350D01*
Y287642D01*
X434250Y287933D01*
X434375Y288183D01*
X434542Y288392D01*
G01X434167Y290450D02*
X436667D01*
X436167Y289950D01*
G01X434167D02*
Y290950D01*
G01Y294050D02*
X436667D01*
X434875Y292508D01*
Y294592D01*
G01X436250Y295858D02*
X436500Y296108D01*
X436625Y296400D01*
X436667Y296733D01*
X436584Y297150D01*
X436375Y297442D01*
X436125Y297525D01*
X435875Y297483D01*
X435667Y297317D01*
X435250Y296483D01*
X434959Y296108D01*
X434542Y295858D01*
X434167Y295775D01*
Y297525D01*
G01X450733Y301792D02*
X450983Y301917D01*
X451275Y302000D01*
X451608D01*
X451983Y301875D01*
X452275Y301667D01*
X452483Y301417D01*
X452650Y301000D01*
X452692Y300625D01*
X452608Y300250D01*
X452483Y300000D01*
X452233Y299750D01*
X451942Y299583D01*
X451650Y299500D01*
X451358D01*
X451067Y299583D01*
X450817Y299708D01*
X450608Y299875D01*
G01X448550Y299500D02*
Y302000D01*
X449050Y301500D01*
G01Y299500D02*
X448050D01*
G01X444950D02*
Y302000D01*
X446492Y300208D01*
X444408D01*
G01X442350Y299500D02*
Y302000D01*
X442850Y301500D01*
G01Y299500D02*
X441850D01*
G01X396292Y247767D02*
X396417Y247517D01*
X396500Y247225D01*
Y246892D01*
X396375Y246517D01*
X396167Y246225D01*
X395917Y246017D01*
X395500Y245850D01*
X395125Y245808D01*
X394750Y245892D01*
X394500Y246017D01*
X394250Y246267D01*
X394083Y246558D01*
X394000Y246850D01*
Y247142D01*
X394083Y247433D01*
X394208Y247683D01*
X394375Y247892D01*
G01X394000Y249950D02*
X396500D01*
X396000Y249450D01*
G01X394000D02*
Y250450D01*
G01X394500Y252133D02*
X394208Y252383D01*
X394042Y252717D01*
X394000Y253092D01*
X394042Y253425D01*
X394250Y253758D01*
X394500Y253967D01*
X394750Y254008D01*
X395042Y253925D01*
X395250Y253633D01*
X395333Y253342D01*
Y252967D01*
G01Y253342D02*
X395458Y253592D01*
X395667Y253800D01*
X395917Y253883D01*
X396167Y253800D01*
X396375Y253592D01*
X396500Y253217D01*
X396458Y252842D01*
X396292Y252467D01*
G01X394292Y255442D02*
X394083Y255733D01*
X394000Y256067D01*
X394083Y256400D01*
X394333Y256692D01*
X394708Y256900D01*
X395083Y256983D01*
X395542D01*
X395917Y256900D01*
X396250Y256692D01*
X396417Y256442D01*
X396500Y256150D01*
X396417Y255817D01*
X396250Y255567D01*
X396000Y255400D01*
X395667Y255317D01*
X395375Y255400D01*
X395083Y255608D01*
X394917Y255858D01*
X394875Y256150D01*
X394958Y256483D01*
X395167Y256733D01*
X395542Y256983D01*
G01X407692Y284767D02*
X407817Y284517D01*
X407900Y284225D01*
Y283892D01*
X407775Y283517D01*
X407567Y283225D01*
X407317Y283017D01*
X406900Y282850D01*
X406525Y282808D01*
X406150Y282892D01*
X405900Y283017D01*
X405650Y283267D01*
X405483Y283558D01*
X405400Y283850D01*
Y284142D01*
X405483Y284433D01*
X405608Y284683D01*
X405775Y284892D01*
G01X405400Y286950D02*
X407900D01*
X407400Y286450D01*
G01X405400D02*
Y287450D01*
G01X405900Y289133D02*
X405608Y289383D01*
X405442Y289717D01*
X405400Y290092D01*
X405442Y290425D01*
X405650Y290758D01*
X405900Y290967D01*
X406150Y291008D01*
X406442Y290925D01*
X406650Y290633D01*
X406733Y290342D01*
Y289967D01*
G01Y290342D02*
X406858Y290592D01*
X407067Y290800D01*
X407317Y290883D01*
X407567Y290800D01*
X407775Y290592D01*
X407900Y290217D01*
X407858Y289842D01*
X407692Y289467D01*
G01X405775Y292233D02*
X405567Y292483D01*
X405442Y292775D01*
X405400Y293150D01*
X405483Y293525D01*
X405650Y293817D01*
X405942Y294025D01*
X406275Y294067D01*
X406608Y293983D01*
X406817Y293775D01*
X406983Y293483D01*
X407025Y293192D01*
X406983Y292900D01*
X406817Y292525D01*
X407900Y292650D01*
Y293775D01*
G01X451792Y287667D02*
X451917Y287417D01*
X452000Y287125D01*
Y286792D01*
X451875Y286417D01*
X451667Y286125D01*
X451417Y285917D01*
X451000Y285750D01*
X450625Y285708D01*
X450250Y285792D01*
X450000Y285917D01*
X449750Y286167D01*
X449583Y286458D01*
X449500Y286750D01*
Y287042D01*
X449583Y287333D01*
X449708Y287583D01*
X449875Y287792D01*
G01X449500Y289850D02*
X452000D01*
X451500Y289350D01*
G01X449500D02*
Y290350D01*
G01X450000Y292033D02*
X449708Y292283D01*
X449542Y292617D01*
X449500Y292992D01*
X449542Y293325D01*
X449750Y293658D01*
X450000Y293867D01*
X450250Y293908D01*
X450542Y293825D01*
X450750Y293533D01*
X450833Y293242D01*
Y292867D01*
G01Y293242D02*
X450958Y293492D01*
X451167Y293700D01*
X451417Y293783D01*
X451667Y293700D01*
X451875Y293492D01*
X452000Y293117D01*
X451958Y292742D01*
X451792Y292367D01*
G01X450000Y295133D02*
X449708Y295383D01*
X449542Y295717D01*
X449500Y296092D01*
X449542Y296425D01*
X449750Y296758D01*
X450000Y296967D01*
X450250Y297008D01*
X450542Y296925D01*
X450750Y296633D01*
X450833Y296342D01*
Y295967D01*
G01Y296342D02*
X450958Y296592D01*
X451167Y296800D01*
X451417Y296883D01*
X451667Y296800D01*
X451875Y296592D01*
X452000Y296217D01*
X451958Y295842D01*
X451792Y295467D01*
G01X411792Y284767D02*
X411917Y284517D01*
X412000Y284225D01*
Y283892D01*
X411875Y283517D01*
X411667Y283225D01*
X411417Y283017D01*
X411000Y282850D01*
X410625Y282808D01*
X410250Y282892D01*
X410000Y283017D01*
X409750Y283267D01*
X409583Y283558D01*
X409500Y283850D01*
Y284142D01*
X409583Y284433D01*
X409708Y284683D01*
X409875Y284892D01*
G01X409500Y286950D02*
X412000D01*
X411500Y286450D01*
G01X409500D02*
Y287450D01*
G01X410000Y289133D02*
X409708Y289383D01*
X409542Y289717D01*
X409500Y290092D01*
X409542Y290425D01*
X409750Y290758D01*
X410000Y290967D01*
X410250Y291008D01*
X410542Y290925D01*
X410750Y290633D01*
X410833Y290342D01*
Y289967D01*
G01Y290342D02*
X410958Y290592D01*
X411167Y290800D01*
X411417Y290883D01*
X411667Y290800D01*
X411875Y290592D01*
X412000Y290217D01*
X411958Y289842D01*
X411792Y289467D01*
G01X412000Y293150D02*
X411917Y292817D01*
X411708Y292567D01*
X411458Y292400D01*
X411125Y292275D01*
X410750Y292233D01*
X410375Y292275D01*
X410042Y292400D01*
X409792Y292567D01*
X409583Y292817D01*
X409500Y293150D01*
X409583Y293483D01*
X409792Y293733D01*
X410042Y293900D01*
X410375Y294025D01*
X410750Y294067D01*
X411125Y294025D01*
X411458Y293900D01*
X411708Y293733D01*
X411917Y293483D01*
X412000Y293150D01*
G01X399792Y284767D02*
X399917Y284517D01*
X400000Y284225D01*
Y283892D01*
X399875Y283517D01*
X399667Y283225D01*
X399417Y283017D01*
X399000Y282850D01*
X398625Y282808D01*
X398250Y282892D01*
X398000Y283017D01*
X397750Y283267D01*
X397583Y283558D01*
X397500Y283850D01*
Y284142D01*
X397583Y284433D01*
X397708Y284683D01*
X397875Y284892D01*
G01X397500Y286950D02*
X400000D01*
X399500Y286450D01*
G01X397500D02*
Y287450D01*
G01X399583Y289258D02*
X399833Y289508D01*
X399958Y289800D01*
X400000Y290133D01*
X399917Y290550D01*
X399708Y290842D01*
X399458Y290925D01*
X399208Y290883D01*
X399000Y290717D01*
X398583Y289883D01*
X398292Y289508D01*
X397875Y289258D01*
X397500Y289175D01*
Y290925D01*
G01Y293150D02*
X397542Y293442D01*
X397667Y293775D01*
X397875Y293983D01*
X398167Y294067D01*
X398458Y293983D01*
X398708Y293733D01*
X398833Y293358D01*
Y292942D01*
X398917Y292692D01*
X399125Y292483D01*
X399417Y292400D01*
X399708Y292525D01*
X399917Y292817D01*
X400000Y293150D01*
X399917Y293483D01*
X399708Y293775D01*
X399417Y293900D01*
X399125Y293817D01*
X398917Y293608D01*
X398833Y293358D01*
Y292942D01*
X398708Y292567D01*
X398458Y292317D01*
X398167Y292233D01*
X397875Y292317D01*
X397667Y292525D01*
X397542Y292858D01*
X397500Y293150D01*
G01X397792Y271867D02*
X397917Y271617D01*
X398000Y271325D01*
Y270992D01*
X397875Y270617D01*
X397667Y270325D01*
X397417Y270117D01*
X397000Y269950D01*
X396625Y269908D01*
X396250Y269992D01*
X396000Y270117D01*
X395750Y270367D01*
X395583Y270658D01*
X395500Y270950D01*
Y271242D01*
X395583Y271533D01*
X395708Y271783D01*
X395875Y271992D01*
G01X395500Y274050D02*
X398000D01*
X397500Y273550D01*
G01X395500D02*
Y274550D01*
G01Y277150D02*
X395542Y277442D01*
X395667Y277775D01*
X395875Y277983D01*
X396167Y278067D01*
X396458Y277983D01*
X396708Y277733D01*
X396833Y277358D01*
Y276942D01*
X396917Y276692D01*
X397125Y276483D01*
X397417Y276400D01*
X397708Y276525D01*
X397917Y276817D01*
X398000Y277150D01*
X397917Y277483D01*
X397708Y277775D01*
X397417Y277900D01*
X397125Y277817D01*
X396917Y277608D01*
X396833Y277358D01*
Y276942D01*
X396708Y276567D01*
X396458Y276317D01*
X396167Y276233D01*
X395875Y276317D01*
X395667Y276525D01*
X395542Y276858D01*
X395500Y277150D01*
G01X397583Y279458D02*
X397833Y279708D01*
X397958Y280000D01*
X398000Y280333D01*
X397917Y280750D01*
X397708Y281042D01*
X397458Y281125D01*
X397208Y281083D01*
X397000Y280917D01*
X396583Y280083D01*
X396292Y279708D01*
X395875Y279458D01*
X395500Y279375D01*
Y281125D01*
G01X393792Y271867D02*
X393917Y271617D01*
X394000Y271325D01*
Y270992D01*
X393875Y270617D01*
X393667Y270325D01*
X393417Y270117D01*
X393000Y269950D01*
X392625Y269908D01*
X392250Y269992D01*
X392000Y270117D01*
X391750Y270367D01*
X391583Y270658D01*
X391500Y270950D01*
Y271242D01*
X391583Y271533D01*
X391708Y271783D01*
X391875Y271992D01*
G01X391500Y274050D02*
X394000D01*
X393500Y273550D01*
G01X391500D02*
Y274550D01*
G01Y277150D02*
X391542Y277442D01*
X391667Y277775D01*
X391875Y277983D01*
X392167Y278067D01*
X392458Y277983D01*
X392708Y277733D01*
X392833Y277358D01*
Y276942D01*
X392917Y276692D01*
X393125Y276483D01*
X393417Y276400D01*
X393708Y276525D01*
X393917Y276817D01*
X394000Y277150D01*
X393917Y277483D01*
X393708Y277775D01*
X393417Y277900D01*
X393125Y277817D01*
X392917Y277608D01*
X392833Y277358D01*
Y276942D01*
X392708Y276567D01*
X392458Y276317D01*
X392167Y276233D01*
X391875Y276317D01*
X391667Y276525D01*
X391542Y276858D01*
X391500Y277150D01*
G01Y280250D02*
X394000D01*
X393500Y279750D01*
G01X391500D02*
Y280750D01*
G01X409792Y271867D02*
X409917Y271617D01*
X410000Y271325D01*
Y270992D01*
X409875Y270617D01*
X409667Y270325D01*
X409417Y270117D01*
X409000Y269950D01*
X408625Y269908D01*
X408250Y269992D01*
X408000Y270117D01*
X407750Y270367D01*
X407583Y270658D01*
X407500Y270950D01*
Y271242D01*
X407583Y271533D01*
X407708Y271783D01*
X407875Y271992D01*
G01X407500Y274050D02*
X410000D01*
X409500Y273550D01*
G01X407500D02*
Y274550D01*
G01Y277067D02*
X408042Y277150D01*
X408500Y277275D01*
X408917Y277442D01*
X409375Y277650D01*
X410000Y277983D01*
Y276317D01*
G01X408542Y279458D02*
X408833Y279750D01*
X409000Y280000D01*
X409083Y280333D01*
X409000Y280625D01*
X408833Y280833D01*
X408583Y281000D01*
X408292Y281042D01*
X408042Y281000D01*
X407792Y280833D01*
X407583Y280583D01*
X407500Y280292D01*
X407583Y279958D01*
X407833Y279667D01*
X408208Y279500D01*
X408625Y279458D01*
X409167Y279542D01*
X409458Y279667D01*
X409750Y279875D01*
X409958Y280167D01*
X410000Y280458D01*
X409917Y280750D01*
X409708Y280958D01*
G01X413792Y271767D02*
X413917Y271517D01*
X414000Y271225D01*
Y270892D01*
X413875Y270517D01*
X413667Y270225D01*
X413417Y270017D01*
X413000Y269850D01*
X412625Y269808D01*
X412250Y269892D01*
X412000Y270017D01*
X411750Y270267D01*
X411583Y270558D01*
X411500Y270850D01*
Y271142D01*
X411583Y271433D01*
X411708Y271683D01*
X411875Y271892D01*
G01X411500Y273950D02*
X414000D01*
X413500Y273450D01*
G01X411500D02*
Y274450D01*
G01Y276967D02*
X412042Y277050D01*
X412500Y277175D01*
X412917Y277342D01*
X413375Y277550D01*
X414000Y277883D01*
Y276217D01*
G01X412000Y279233D02*
X411708Y279483D01*
X411542Y279817D01*
X411500Y280192D01*
X411542Y280525D01*
X411750Y280858D01*
X412000Y281067D01*
X412250Y281108D01*
X412542Y281025D01*
X412750Y280733D01*
X412833Y280442D01*
Y280067D01*
G01Y280442D02*
X412958Y280692D01*
X413167Y280900D01*
X413417Y280983D01*
X413667Y280900D01*
X413875Y280692D01*
X414000Y280317D01*
X413958Y279942D01*
X413792Y279567D01*
G01X405792Y271867D02*
X405917Y271617D01*
X406000Y271325D01*
Y270992D01*
X405875Y270617D01*
X405667Y270325D01*
X405417Y270117D01*
X405000Y269950D01*
X404625Y269908D01*
X404250Y269992D01*
X404000Y270117D01*
X403750Y270367D01*
X403583Y270658D01*
X403500Y270950D01*
Y271242D01*
X403583Y271533D01*
X403708Y271783D01*
X403875Y271992D01*
G01X403500Y274050D02*
X406000D01*
X405500Y273550D01*
G01X403500D02*
Y274550D01*
G01Y277067D02*
X404042Y277150D01*
X404500Y277275D01*
X404917Y277442D01*
X405375Y277650D01*
X406000Y277983D01*
Y276317D01*
G01X403500Y280250D02*
X406000D01*
X405500Y279750D01*
G01X403500D02*
Y280750D01*
G01X401792Y271867D02*
X401917Y271617D01*
X402000Y271325D01*
Y270992D01*
X401875Y270617D01*
X401667Y270325D01*
X401417Y270117D01*
X401000Y269950D01*
X400625Y269908D01*
X400250Y269992D01*
X400000Y270117D01*
X399750Y270367D01*
X399583Y270658D01*
X399500Y270950D01*
Y271242D01*
X399583Y271533D01*
X399708Y271783D01*
X399875Y271992D01*
G01X399500Y274050D02*
X402000D01*
X401500Y273550D01*
G01X399500D02*
Y274550D01*
G01X400542Y276358D02*
X400833Y276650D01*
X401000Y276900D01*
X401083Y277233D01*
X401000Y277525D01*
X400833Y277733D01*
X400583Y277900D01*
X400292Y277942D01*
X400042Y277900D01*
X399792Y277733D01*
X399583Y277483D01*
X399500Y277192D01*
X399583Y276858D01*
X399833Y276567D01*
X400208Y276400D01*
X400625Y276358D01*
X401167Y276442D01*
X401458Y276567D01*
X401750Y276775D01*
X401958Y277067D01*
X402000Y277358D01*
X401917Y277650D01*
X401708Y277858D01*
G01X400000Y279333D02*
X399708Y279583D01*
X399542Y279917D01*
X399500Y280292D01*
X399542Y280625D01*
X399750Y280958D01*
X400000Y281167D01*
X400250Y281208D01*
X400542Y281125D01*
X400750Y280833D01*
X400833Y280542D01*
Y280167D01*
G01Y280542D02*
X400958Y280792D01*
X401167Y281000D01*
X401417Y281083D01*
X401667Y281000D01*
X401875Y280792D01*
X402000Y280417D01*
X401958Y280042D01*
X401792Y279667D01*
G01X397258Y260952D02*
Y264952D01*
X404658D01*
G01X427389Y265240D02*
Y269240D01*
X434789D01*
G01X425379Y265835D02*
Y261835D01*
X417979D01*
G01X395792Y284767D02*
X395917Y284517D01*
X396000Y284225D01*
Y283892D01*
X395875Y283517D01*
X395667Y283225D01*
X395417Y283017D01*
X395000Y282850D01*
X394625Y282808D01*
X394250Y282892D01*
X394000Y283017D01*
X393750Y283267D01*
X393583Y283558D01*
X393500Y283850D01*
Y284142D01*
X393583Y284433D01*
X393708Y284683D01*
X393875Y284892D01*
G01X393500Y286950D02*
X396000D01*
X395500Y286450D01*
G01X393500D02*
Y287450D01*
G01Y290050D02*
X396000D01*
X395500Y289550D01*
G01X393500D02*
Y290550D01*
G01X393792Y292442D02*
X393583Y292733D01*
X393500Y293067D01*
X393583Y293400D01*
X393833Y293692D01*
X394208Y293900D01*
X394583Y293983D01*
X395042D01*
X395417Y293900D01*
X395750Y293692D01*
X395917Y293442D01*
X396000Y293150D01*
X395917Y292817D01*
X395750Y292567D01*
X395500Y292400D01*
X395167Y292317D01*
X394875Y292400D01*
X394583Y292608D01*
X394417Y292858D01*
X394375Y293150D01*
X394458Y293483D01*
X394667Y293733D01*
X395042Y293983D01*
G01X391792Y284767D02*
X391917Y284517D01*
X392000Y284225D01*
Y283892D01*
X391875Y283517D01*
X391667Y283225D01*
X391417Y283017D01*
X391000Y282850D01*
X390625Y282808D01*
X390250Y282892D01*
X390000Y283017D01*
X389750Y283267D01*
X389583Y283558D01*
X389500Y283850D01*
Y284142D01*
X389583Y284433D01*
X389708Y284683D01*
X389875Y284892D01*
G01X389500Y286950D02*
X392000D01*
X391500Y286450D01*
G01X389500D02*
Y287450D01*
G01X391583Y289258D02*
X391833Y289508D01*
X391958Y289800D01*
X392000Y290133D01*
X391917Y290550D01*
X391708Y290842D01*
X391458Y290925D01*
X391208Y290883D01*
X391000Y290717D01*
X390583Y289883D01*
X390292Y289508D01*
X389875Y289258D01*
X389500Y289175D01*
Y290925D01*
G01X392000Y293150D02*
X391917Y292817D01*
X391708Y292567D01*
X391458Y292400D01*
X391125Y292275D01*
X390750Y292233D01*
X390375Y292275D01*
X390042Y292400D01*
X389792Y292567D01*
X389583Y292817D01*
X389500Y293150D01*
X389583Y293483D01*
X389792Y293733D01*
X390042Y293900D01*
X390375Y294025D01*
X390750Y294067D01*
X391125Y294025D01*
X391458Y293900D01*
X391708Y293733D01*
X391917Y293483D01*
X392000Y293150D01*
G01X436233Y278292D02*
X436483Y278417D01*
X436775Y278500D01*
X437108D01*
X437483Y278375D01*
X437775Y278167D01*
X437983Y277917D01*
X438150Y277500D01*
X438192Y277125D01*
X438108Y276750D01*
X437983Y276500D01*
X437733Y276250D01*
X437442Y276083D01*
X437150Y276000D01*
X436858D01*
X436567Y276083D01*
X436317Y276208D01*
X436108Y276375D01*
G01X434842Y278083D02*
X434592Y278333D01*
X434300Y278458D01*
X433967Y278500D01*
X433550Y278417D01*
X433258Y278208D01*
X433175Y277958D01*
X433217Y277708D01*
X433383Y277500D01*
X434217Y277083D01*
X434592Y276792D01*
X434842Y276375D01*
X434925Y276000D01*
X433175D01*
G01X430950D02*
Y278500D01*
X431450Y278000D01*
G01Y276000D02*
X430450D01*
G01X427350D02*
Y278500D01*
X428892Y276708D01*
X426808D01*
G01X428150Y302500D02*
Y300000D01*
G01X429108Y302500D02*
X427192D01*
G01X425883Y300000D02*
Y302500D01*
X424883D01*
X424550Y302375D01*
X424300Y302083D01*
X424217Y301750D01*
X424300Y301417D01*
X424508Y301167D01*
X424883Y301042D01*
X425883D01*
G01X421950Y300000D02*
Y302500D01*
X422450Y302000D01*
G01Y300000D02*
X421450D01*
G01X419558Y300292D02*
X419267Y300083D01*
X418933Y300000D01*
X418600Y300083D01*
X418308Y300333D01*
X418100Y300708D01*
X418017Y301083D01*
Y301542D01*
X418100Y301917D01*
X418308Y302250D01*
X418558Y302417D01*
X418850Y302500D01*
X419183Y302417D01*
X419433Y302250D01*
X419600Y302000D01*
X419683Y301667D01*
X419600Y301375D01*
X419392Y301083D01*
X419142Y300917D01*
X418850Y300875D01*
X418517Y300958D01*
X418267Y301167D01*
X418017Y301542D01*
G01X404150Y298000D02*
Y295500D01*
G01X405108Y298000D02*
X403192D01*
G01X401883Y295500D02*
Y298000D01*
X400883D01*
X400550Y297875D01*
X400300Y297583D01*
X400217Y297250D01*
X400300Y296917D01*
X400508Y296667D01*
X400883Y296542D01*
X401883D01*
G01X398867Y296000D02*
X398617Y295708D01*
X398283Y295542D01*
X397908Y295500D01*
X397575Y295542D01*
X397242Y295750D01*
X397033Y296000D01*
X396992Y296250D01*
X397075Y296542D01*
X397367Y296750D01*
X397658Y296833D01*
X398033D01*
G01X397658D02*
X397408Y296958D01*
X397200Y297167D01*
X397117Y297417D01*
X397200Y297667D01*
X397408Y297875D01*
X397783Y298000D01*
X398158Y297958D01*
X398533Y297792D01*
G01X394933Y295500D02*
X394850Y296042D01*
X394725Y296500D01*
X394558Y296917D01*
X394350Y297375D01*
X394017Y298000D01*
X395683D01*
G01X416150D02*
Y295500D01*
G01X417108Y298000D02*
X415192D01*
G01X413883Y295500D02*
Y298000D01*
X412883D01*
X412550Y297875D01*
X412300Y297583D01*
X412217Y297250D01*
X412300Y296917D01*
X412508Y296667D01*
X412883Y296542D01*
X413883D01*
G01X409450Y295500D02*
Y298000D01*
X410992Y296208D01*
X408908D01*
G01X407642Y296542D02*
X407350Y296833D01*
X407100Y297000D01*
X406767Y297083D01*
X406475Y297000D01*
X406267Y296833D01*
X406100Y296583D01*
X406058Y296292D01*
X406100Y296042D01*
X406267Y295792D01*
X406517Y295583D01*
X406808Y295500D01*
X407142Y295583D01*
X407433Y295833D01*
X407600Y296208D01*
X407642Y296625D01*
X407558Y297167D01*
X407433Y297458D01*
X407225Y297750D01*
X406933Y297958D01*
X406642Y298000D01*
X406350Y297917D01*
X406142Y297708D01*
G01X415200Y302800D02*
Y300300D01*
G01X416158Y302800D02*
X414242D01*
G01X412933Y300300D02*
Y302800D01*
X411933D01*
X411600Y302675D01*
X411350Y302383D01*
X411267Y302050D01*
X411350Y301717D01*
X411558Y301467D01*
X411933Y301342D01*
X412933D01*
G01X409000Y300300D02*
Y302800D01*
X409500Y302300D01*
G01Y300300D02*
X408500D01*
G01X406692Y301342D02*
X406400Y301633D01*
X406150Y301800D01*
X405817Y301883D01*
X405525Y301800D01*
X405317Y301633D01*
X405150Y301383D01*
X405108Y301092D01*
X405150Y300842D01*
X405317Y300592D01*
X405567Y300383D01*
X405858Y300300D01*
X406192Y300383D01*
X406483Y300633D01*
X406650Y301008D01*
X406692Y301425D01*
X406608Y301967D01*
X406483Y302258D01*
X406275Y302550D01*
X405983Y302758D01*
X405692Y302800D01*
X405400Y302717D01*
X405192Y302508D01*
G01X403717Y300800D02*
X403467Y300508D01*
X403133Y300342D01*
X402758Y300300D01*
X402425Y300342D01*
X402092Y300550D01*
X401883Y300800D01*
X401842Y301050D01*
X401925Y301342D01*
X402217Y301550D01*
X402508Y301633D01*
X402883D01*
G01X402508D02*
X402258Y301758D01*
X402050Y301967D01*
X401967Y302217D01*
X402050Y302467D01*
X402258Y302675D01*
X402633Y302800D01*
X403008Y302758D01*
X403383Y302592D01*
G01X413292Y311267D02*
X413417Y311017D01*
X413500Y310725D01*
Y310392D01*
X413375Y310017D01*
X413167Y309725D01*
X412917Y309517D01*
X412500Y309350D01*
X412125Y309308D01*
X411750Y309392D01*
X411500Y309517D01*
X411250Y309767D01*
X411083Y310058D01*
X411000Y310350D01*
Y310642D01*
X411083Y310933D01*
X411208Y311183D01*
X411375Y311392D01*
G01X411000Y313450D02*
X413500D01*
X413000Y312950D01*
G01X411000D02*
Y313950D01*
G01X411375Y315633D02*
X411167Y315883D01*
X411042Y316175D01*
X411000Y316550D01*
X411083Y316925D01*
X411250Y317217D01*
X411542Y317425D01*
X411875Y317467D01*
X412208Y317383D01*
X412417Y317175D01*
X412583Y316883D01*
X412625Y316592D01*
X412583Y316300D01*
X412417Y315925D01*
X413500Y316050D01*
Y317175D01*
G01X412042Y318858D02*
X412333Y319150D01*
X412500Y319400D01*
X412583Y319733D01*
X412500Y320025D01*
X412333Y320233D01*
X412083Y320400D01*
X411792Y320442D01*
X411542Y320400D01*
X411292Y320233D01*
X411083Y319983D01*
X411000Y319692D01*
X411083Y319358D01*
X411333Y319067D01*
X411708Y318900D01*
X412125Y318858D01*
X412667Y318942D01*
X412958Y319067D01*
X413250Y319275D01*
X413458Y319567D01*
X413500Y319858D01*
X413417Y320150D01*
X413208Y320358D01*
G01X448292Y310767D02*
X448417Y310517D01*
X448500Y310225D01*
Y309892D01*
X448375Y309517D01*
X448167Y309225D01*
X447917Y309017D01*
X447500Y308850D01*
X447125Y308808D01*
X446750Y308892D01*
X446500Y309017D01*
X446250Y309267D01*
X446083Y309558D01*
X446000Y309850D01*
Y310142D01*
X446083Y310433D01*
X446208Y310683D01*
X446375Y310892D01*
G01X446000Y312950D02*
X448500D01*
X448000Y312450D01*
G01X446000D02*
Y313450D01*
G01Y316550D02*
X448500D01*
X446708Y315008D01*
Y317092D01*
G01X446375Y318233D02*
X446167Y318483D01*
X446042Y318775D01*
X446000Y319150D01*
X446083Y319525D01*
X446250Y319817D01*
X446542Y320025D01*
X446875Y320067D01*
X447208Y319983D01*
X447417Y319775D01*
X447583Y319483D01*
X447625Y319192D01*
X447583Y318900D01*
X447417Y318525D01*
X448500Y318650D01*
Y319775D01*
G01X398983Y347500D02*
Y350000D01*
X397942D01*
X397608Y349875D01*
X397400Y349708D01*
X397317Y349375D01*
X397400Y349042D01*
X397650Y348833D01*
X397942Y348708D01*
X398983D01*
G01X397942D02*
X397317Y347500D01*
G01X395967Y347875D02*
X395717Y347667D01*
X395425Y347542D01*
X395050Y347500D01*
X394675Y347583D01*
X394383Y347750D01*
X394175Y348042D01*
X394133Y348375D01*
X394217Y348708D01*
X394425Y348917D01*
X394717Y349083D01*
X395008Y349125D01*
X395300Y349083D01*
X395675Y348917D01*
X395550Y350000D01*
X394425D01*
G01X392742Y348542D02*
X392450Y348833D01*
X392200Y349000D01*
X391867Y349083D01*
X391575Y349000D01*
X391367Y348833D01*
X391200Y348583D01*
X391158Y348292D01*
X391200Y348042D01*
X391367Y347792D01*
X391617Y347583D01*
X391908Y347500D01*
X392242Y347583D01*
X392533Y347833D01*
X392700Y348208D01*
X392742Y348625D01*
X392658Y349167D01*
X392533Y349458D01*
X392325Y349750D01*
X392033Y349958D01*
X391742Y350000D01*
X391450Y349917D01*
X391242Y349708D01*
G01X389642Y348542D02*
X389350Y348833D01*
X389100Y349000D01*
X388767Y349083D01*
X388475Y349000D01*
X388267Y348833D01*
X388100Y348583D01*
X388058Y348292D01*
X388100Y348042D01*
X388267Y347792D01*
X388517Y347583D01*
X388808Y347500D01*
X389142Y347583D01*
X389433Y347833D01*
X389600Y348208D01*
X389642Y348625D01*
X389558Y349167D01*
X389433Y349458D01*
X389225Y349750D01*
X388933Y349958D01*
X388642Y350000D01*
X388350Y349917D01*
X388142Y349708D01*
G01X403630Y333430D02*
Y329430D01*
X396230D01*
G01X411100Y338600D02*
X407100D01*
Y346000D01*
G01X410933Y349000D02*
Y351500D01*
X409892D01*
X409558Y351375D01*
X409350Y351208D01*
X409267Y350875D01*
X409350Y350542D01*
X409600Y350333D01*
X409892Y350208D01*
X410933D01*
G01X409892D02*
X409267Y349000D01*
G01X407917Y349500D02*
X407667Y349208D01*
X407333Y349042D01*
X406958Y349000D01*
X406625Y349042D01*
X406292Y349250D01*
X406083Y349500D01*
X406042Y349750D01*
X406125Y350042D01*
X406417Y350250D01*
X406708Y350333D01*
X407083D01*
G01X406708D02*
X406458Y350458D01*
X406250Y350667D01*
X406167Y350917D01*
X406250Y351167D01*
X406458Y351375D01*
X406833Y351500D01*
X407208Y351458D01*
X407583Y351292D01*
G01X404817Y349375D02*
X404567Y349167D01*
X404275Y349042D01*
X403900Y349000D01*
X403525Y349083D01*
X403233Y349250D01*
X403025Y349542D01*
X402983Y349875D01*
X403067Y350208D01*
X403275Y350417D01*
X403567Y350583D01*
X403858Y350625D01*
X404150Y350583D01*
X404525Y350417D01*
X404400Y351500D01*
X403275D01*
G01X407550Y328250D02*
Y332250D01*
X414950D01*
G01X411400Y346000D02*
X415400D01*
Y338600D01*
G01Y346000D02*
X419400D01*
Y338600D01*
G01X431000Y349517D02*
X433500D01*
Y350558D01*
X433375Y350892D01*
X433208Y351100D01*
X432875Y351183D01*
X432542Y351100D01*
X432333Y350850D01*
X432208Y350558D01*
Y349517D01*
G01Y350558D02*
X431000Y351183D01*
G01Y353450D02*
X433500D01*
X433000Y352950D01*
G01X431000D02*
Y353950D01*
G01Y357050D02*
X433500D01*
X431708Y355508D01*
Y357592D01*
G01X433500Y359650D02*
X433417Y359317D01*
X433208Y359067D01*
X432958Y358900D01*
X432625Y358775D01*
X432250Y358733D01*
X431875Y358775D01*
X431542Y358900D01*
X431292Y359067D01*
X431083Y359317D01*
X431000Y359650D01*
X431083Y359983D01*
X431292Y360233D01*
X431542Y360400D01*
X431875Y360525D01*
X432250Y360567D01*
X432625Y360525D01*
X432958Y360400D01*
X433208Y360233D01*
X433417Y359983D01*
X433500Y359650D01*
G01X447400Y336200D02*
X451400D01*
Y328800D01*
G01X456241Y353640D02*
Y349640D01*
X448841D01*
G01X448200Y327600D02*
X452200D01*
Y320200D01*
G01X423500Y339100D02*
X419500D01*
Y346500D01*
G01X442740Y339244D02*
X438740D01*
Y346644D01*
G01X423000Y349517D02*
X425500D01*
Y350558D01*
X425375Y350892D01*
X425208Y351100D01*
X424875Y351183D01*
X424542Y351100D01*
X424333Y350850D01*
X424208Y350558D01*
Y349517D01*
G01Y350558D02*
X423000Y351183D01*
G01Y353450D02*
X425500D01*
X425000Y352950D01*
G01X423000D02*
Y353950D01*
G01X423500Y355633D02*
X423208Y355883D01*
X423042Y356217D01*
X423000Y356592D01*
X423042Y356925D01*
X423250Y357258D01*
X423500Y357467D01*
X423750Y357508D01*
X424042Y357425D01*
X424250Y357133D01*
X424333Y356842D01*
Y356467D01*
G01Y356842D02*
X424458Y357092D01*
X424667Y357300D01*
X424917Y357383D01*
X425167Y357300D01*
X425375Y357092D01*
X425500Y356717D01*
X425458Y356342D01*
X425292Y355967D01*
G01X423000Y359567D02*
X423542Y359650D01*
X424000Y359775D01*
X424417Y359942D01*
X424875Y360150D01*
X425500Y360483D01*
Y358817D01*
G01X437200Y328600D02*
X433200D01*
Y336000D01*
G01X425500Y346000D02*
X429500D01*
Y338600D01*
G01X418500Y349517D02*
X421000D01*
Y350558D01*
X420875Y350892D01*
X420708Y351100D01*
X420375Y351183D01*
X420042Y351100D01*
X419833Y350850D01*
X419708Y350558D01*
Y349517D01*
G01Y350558D02*
X418500Y351183D01*
G01Y353450D02*
X421000D01*
X420500Y352950D01*
G01X418500D02*
Y353950D01*
G01Y356550D02*
X421000D01*
X420500Y356050D01*
G01X418500D02*
Y357050D01*
G01Y359650D02*
X421000D01*
X420500Y359150D01*
G01X418500D02*
Y360150D01*
G01X429500Y328700D02*
X425500D01*
Y336100D01*
G01X434786Y349341D02*
Y353341D01*
X442186D01*
G01X414000Y349517D02*
X416500D01*
Y350558D01*
X416375Y350892D01*
X416208Y351100D01*
X415875Y351183D01*
X415542Y351100D01*
X415333Y350850D01*
X415208Y350558D01*
Y349517D01*
G01Y350558D02*
X414000Y351183D01*
G01Y353450D02*
X416500D01*
X416000Y352950D01*
G01X414000D02*
Y353950D01*
G01X416500Y356550D02*
X416417Y356217D01*
X416208Y355967D01*
X415958Y355800D01*
X415625Y355675D01*
X415250Y355633D01*
X414875Y355675D01*
X414542Y355800D01*
X414292Y355967D01*
X414083Y356217D01*
X414000Y356550D01*
X414083Y356883D01*
X414292Y357133D01*
X414542Y357300D01*
X414875Y357425D01*
X415250Y357467D01*
X415625Y357425D01*
X415958Y357300D01*
X416208Y357133D01*
X416417Y356883D01*
X416500Y356550D01*
G01X414000Y359567D02*
X414542Y359650D01*
X415000Y359775D01*
X415417Y359942D01*
X415875Y360150D01*
X416500Y360483D01*
Y358817D01*
G01X423500Y328800D02*
X419500D01*
Y336200D01*
G01X430900Y346300D02*
X434900D01*
Y338900D01*
G01X427000Y349517D02*
X429500D01*
Y350558D01*
X429375Y350892D01*
X429208Y351100D01*
X428875Y351183D01*
X428542Y351100D01*
X428333Y350850D01*
X428208Y350558D01*
Y349517D01*
G01Y350558D02*
X427000Y351183D01*
G01Y353450D02*
X429500D01*
X429000Y352950D01*
G01X427000D02*
Y353950D01*
G01X427500Y355633D02*
X427208Y355883D01*
X427042Y356217D01*
X427000Y356592D01*
X427042Y356925D01*
X427250Y357258D01*
X427500Y357467D01*
X427750Y357508D01*
X428042Y357425D01*
X428250Y357133D01*
X428333Y356842D01*
Y356467D01*
G01Y356842D02*
X428458Y357092D01*
X428667Y357300D01*
X428917Y357383D01*
X429167Y357300D01*
X429375Y357092D01*
X429500Y356717D01*
X429458Y356342D01*
X429292Y355967D01*
G01X427292Y358942D02*
X427083Y359233D01*
X427000Y359567D01*
X427083Y359900D01*
X427333Y360192D01*
X427708Y360400D01*
X428083Y360483D01*
X428542D01*
X428917Y360400D01*
X429250Y360192D01*
X429417Y359942D01*
X429500Y359650D01*
X429417Y359317D01*
X429250Y359067D01*
X429000Y358900D01*
X428667Y358817D01*
X428375Y358900D01*
X428083Y359108D01*
X427917Y359358D01*
X427875Y359650D01*
X427958Y359983D01*
X428167Y360233D01*
X428542Y360483D01*
G01X443400Y336200D02*
X447400D01*
Y328800D01*
G01X445300Y346300D02*
X449300D01*
Y338900D01*
G01X410983Y353000D02*
Y355500D01*
X409942D01*
X409608Y355375D01*
X409400Y355208D01*
X409317Y354875D01*
X409400Y354542D01*
X409650Y354333D01*
X409942Y354208D01*
X410983D01*
G01X409942D02*
X409317Y353000D01*
G01X407967Y353375D02*
X407717Y353167D01*
X407425Y353042D01*
X407050Y353000D01*
X406675Y353083D01*
X406383Y353250D01*
X406175Y353542D01*
X406133Y353875D01*
X406217Y354208D01*
X406425Y354417D01*
X406717Y354583D01*
X407008Y354625D01*
X407300Y354583D01*
X407675Y354417D01*
X407550Y355500D01*
X406425D01*
G01X404742Y354042D02*
X404450Y354333D01*
X404200Y354500D01*
X403867Y354583D01*
X403575Y354500D01*
X403367Y354333D01*
X403200Y354083D01*
X403158Y353792D01*
X403200Y353542D01*
X403367Y353292D01*
X403617Y353083D01*
X403908Y353000D01*
X404242Y353083D01*
X404533Y353333D01*
X404700Y353708D01*
X404742Y354125D01*
X404658Y354667D01*
X404533Y354958D01*
X404325Y355250D01*
X404033Y355458D01*
X403742Y355500D01*
X403450Y355417D01*
X403242Y355208D01*
G01X401558Y353292D02*
X401267Y353083D01*
X400933Y353000D01*
X400600Y353083D01*
X400308Y353333D01*
X400100Y353708D01*
X400017Y354083D01*
Y354542D01*
X400100Y354917D01*
X400308Y355250D01*
X400558Y355417D01*
X400850Y355500D01*
X401183Y355417D01*
X401433Y355250D01*
X401600Y355000D01*
X401683Y354667D01*
X401600Y354375D01*
X401392Y354083D01*
X401142Y353917D01*
X400850Y353875D01*
X400517Y353958D01*
X400267Y354167D01*
X400017Y354542D01*
G01X406020Y333630D02*
Y337630D01*
X413420D01*
G01X388000Y352067D02*
X390500D01*
Y353108D01*
X390375Y353442D01*
X390208Y353650D01*
X389875Y353733D01*
X389542Y353650D01*
X389333Y353400D01*
X389208Y353108D01*
Y352067D01*
G01Y353108D02*
X388000Y353733D01*
G01Y355917D02*
X388542Y356000D01*
X389000Y356125D01*
X389417Y356292D01*
X389875Y356500D01*
X390500Y356833D01*
Y355167D01*
G01X388292Y358392D02*
X388083Y358683D01*
X388000Y359017D01*
X388083Y359350D01*
X388333Y359642D01*
X388708Y359850D01*
X389083Y359933D01*
X389542D01*
X389917Y359850D01*
X390250Y359642D01*
X390417Y359392D01*
X390500Y359100D01*
X390417Y358767D01*
X390250Y358517D01*
X390000Y358350D01*
X389667Y358267D01*
X389375Y358350D01*
X389083Y358558D01*
X388917Y358808D01*
X388875Y359100D01*
X388958Y359433D01*
X389167Y359683D01*
X389542Y359933D01*
G01X389900Y346100D02*
X393900D01*
Y338700D01*
G01X392000Y352067D02*
X394500D01*
Y353108D01*
X394375Y353442D01*
X394208Y353650D01*
X393875Y353733D01*
X393542Y353650D01*
X393333Y353400D01*
X393208Y353108D01*
Y352067D01*
G01Y353108D02*
X392000Y353733D01*
G01Y355917D02*
X392542Y356000D01*
X393000Y356125D01*
X393417Y356292D01*
X393875Y356500D01*
X394500Y356833D01*
Y355167D01*
G01X394083Y358308D02*
X394333Y358558D01*
X394458Y358850D01*
X394500Y359183D01*
X394417Y359600D01*
X394208Y359892D01*
X393958Y359975D01*
X393708Y359933D01*
X393500Y359767D01*
X393083Y358933D01*
X392792Y358558D01*
X392375Y358308D01*
X392000Y358225D01*
Y359975D01*
G01X398000Y338700D02*
X394000D01*
Y346100D01*
G01X393292Y302267D02*
X393417Y302017D01*
X393500Y301725D01*
Y301392D01*
X393375Y301017D01*
X393167Y300725D01*
X392917Y300517D01*
X392500Y300350D01*
X392125Y300308D01*
X391750Y300392D01*
X391500Y300517D01*
X391250Y300767D01*
X391083Y301058D01*
X391000Y301350D01*
Y301642D01*
X391083Y301933D01*
X391208Y302183D01*
X391375Y302392D01*
G01X393083Y303658D02*
X393333Y303908D01*
X393458Y304200D01*
X393500Y304533D01*
X393417Y304950D01*
X393208Y305242D01*
X392958Y305325D01*
X392708Y305283D01*
X392500Y305117D01*
X392083Y304283D01*
X391792Y303908D01*
X391375Y303658D01*
X391000Y303575D01*
Y305325D01*
G01X393500Y307550D02*
X393417Y307217D01*
X393208Y306967D01*
X392958Y306800D01*
X392625Y306675D01*
X392250Y306633D01*
X391875Y306675D01*
X391542Y306800D01*
X391292Y306967D01*
X391083Y307217D01*
X391000Y307550D01*
X391083Y307883D01*
X391292Y308133D01*
X391542Y308300D01*
X391875Y308425D01*
X392250Y308467D01*
X392625Y308425D01*
X392958Y308300D01*
X393208Y308133D01*
X393417Y307883D01*
X393500Y307550D01*
G01X391292Y309942D02*
X391083Y310233D01*
X391000Y310567D01*
X391083Y310900D01*
X391333Y311192D01*
X391708Y311400D01*
X392083Y311483D01*
X392542D01*
X392917Y311400D01*
X393250Y311192D01*
X393417Y310942D01*
X393500Y310650D01*
X393417Y310317D01*
X393250Y310067D01*
X393000Y309900D01*
X392667Y309817D01*
X392375Y309900D01*
X392083Y310108D01*
X391917Y310358D01*
X391875Y310650D01*
X391958Y310983D01*
X392167Y311233D01*
X392542Y311483D01*
G01X424500Y307950D02*
X422000D01*
G01X424500Y306992D02*
Y308908D01*
G01X422000Y310217D02*
X424500D01*
Y311217D01*
X424375Y311550D01*
X424083Y311800D01*
X423750Y311883D01*
X423417Y311800D01*
X423167Y311592D01*
X423042Y311217D01*
Y310217D01*
G01X424083Y313358D02*
X424333Y313608D01*
X424458Y313900D01*
X424500Y314233D01*
X424417Y314650D01*
X424208Y314942D01*
X423958Y315025D01*
X423708Y314983D01*
X423500Y314817D01*
X423083Y313983D01*
X422792Y313608D01*
X422375Y313358D01*
X422000Y313275D01*
Y315025D01*
G01X423042Y316458D02*
X423333Y316750D01*
X423500Y317000D01*
X423583Y317333D01*
X423500Y317625D01*
X423333Y317833D01*
X423083Y318000D01*
X422792Y318042D01*
X422542Y318000D01*
X422292Y317833D01*
X422083Y317583D01*
X422000Y317292D01*
X422083Y316958D01*
X422333Y316667D01*
X422708Y316500D01*
X423125Y316458D01*
X423667Y316542D01*
X423958Y316667D01*
X424250Y316875D01*
X424458Y317167D01*
X424500Y317458D01*
X424417Y317750D01*
X424208Y317958D01*
G01X406150Y306500D02*
Y304000D01*
G01X407108Y306500D02*
X405192D01*
G01X403883Y304000D02*
Y306500D01*
X402883D01*
X402550Y306375D01*
X402300Y306083D01*
X402217Y305750D01*
X402300Y305417D01*
X402508Y305167D01*
X402883Y305042D01*
X403883D01*
G01X400867Y304500D02*
X400617Y304208D01*
X400283Y304042D01*
X399908Y304000D01*
X399575Y304042D01*
X399242Y304250D01*
X399033Y304500D01*
X398992Y304750D01*
X399075Y305042D01*
X399367Y305250D01*
X399658Y305333D01*
X400033D01*
G01X399658D02*
X399408Y305458D01*
X399200Y305667D01*
X399117Y305917D01*
X399200Y306167D01*
X399408Y306375D01*
X399783Y306500D01*
X400158Y306458D01*
X400533Y306292D01*
G01X396850Y304000D02*
X396558Y304042D01*
X396225Y304167D01*
X396017Y304375D01*
X395933Y304667D01*
X396017Y304958D01*
X396267Y305208D01*
X396642Y305333D01*
X397058D01*
X397308Y305417D01*
X397517Y305625D01*
X397600Y305917D01*
X397475Y306208D01*
X397183Y306417D01*
X396850Y306500D01*
X396517Y306417D01*
X396225Y306208D01*
X396100Y305917D01*
X396183Y305625D01*
X396392Y305417D01*
X396642Y305333D01*
X397058D01*
X397433Y305208D01*
X397683Y304958D01*
X397767Y304667D01*
X397683Y304375D01*
X397475Y304167D01*
X397142Y304042D01*
X396850Y304000D01*
G01X423650Y327500D02*
Y325000D01*
G01X424608Y327500D02*
X422692D01*
G01X421383Y325000D02*
Y327500D01*
X420383D01*
X420050Y327375D01*
X419800Y327083D01*
X419717Y326750D01*
X419800Y326417D01*
X420008Y326167D01*
X420383Y326042D01*
X421383D01*
G01X416950Y325000D02*
Y327500D01*
X418492Y325708D01*
X416408D01*
G01X414350Y325000D02*
Y327500D01*
X414850Y327000D01*
G01Y325000D02*
X413850D01*
G01X431000Y312850D02*
X428500D01*
G01X431000Y311892D02*
Y313808D01*
G01X428500Y315117D02*
X431000D01*
Y316117D01*
X430875Y316450D01*
X430583Y316700D01*
X430250Y316783D01*
X429917Y316700D01*
X429667Y316492D01*
X429542Y316117D01*
Y315117D01*
G01X428500Y319550D02*
X431000D01*
X429208Y318008D01*
Y320092D01*
G01X430583Y321358D02*
X430833Y321608D01*
X430958Y321900D01*
X431000Y322233D01*
X430917Y322650D01*
X430708Y322942D01*
X430458Y323025D01*
X430208Y322983D01*
X430000Y322817D01*
X429583Y321983D01*
X429292Y321608D01*
X428875Y321358D01*
X428500Y321275D01*
Y323025D01*
G01X420000Y312850D02*
X417500D01*
G01X420000Y311892D02*
Y313808D01*
G01X417500Y315117D02*
X420000D01*
Y316117D01*
X419875Y316450D01*
X419583Y316700D01*
X419250Y316783D01*
X418917Y316700D01*
X418667Y316492D01*
X418542Y316117D01*
Y315117D01*
G01X417500Y319550D02*
X420000D01*
X418208Y318008D01*
Y320092D01*
G01X418000Y321233D02*
X417708Y321483D01*
X417542Y321817D01*
X417500Y322192D01*
X417542Y322525D01*
X417750Y322858D01*
X418000Y323067D01*
X418250Y323108D01*
X418542Y323025D01*
X418750Y322733D01*
X418833Y322442D01*
Y322067D01*
G01Y322442D02*
X418958Y322692D01*
X419167Y322900D01*
X419417Y322983D01*
X419667Y322900D01*
X419875Y322692D01*
X420000Y322317D01*
X419958Y321942D01*
X419792Y321567D01*
G01X443500Y308350D02*
X441000D01*
G01X443500Y307392D02*
Y309308D01*
G01X441000Y310617D02*
X443500D01*
Y311617D01*
X443375Y311950D01*
X443083Y312200D01*
X442750Y312283D01*
X442417Y312200D01*
X442167Y311992D01*
X442042Y311617D01*
Y310617D01*
G01X441000Y315050D02*
X443500D01*
X441708Y313508D01*
Y315592D01*
G01X441000Y317567D02*
X441542Y317650D01*
X442000Y317775D01*
X442417Y317942D01*
X442875Y318150D01*
X443500Y318483D01*
Y316817D01*
G01X418650Y306500D02*
Y304000D01*
G01X419608Y306500D02*
X417692D01*
G01X416383Y304000D02*
Y306500D01*
X415383D01*
X415050Y306375D01*
X414800Y306083D01*
X414717Y305750D01*
X414800Y305417D01*
X415008Y305167D01*
X415383Y305042D01*
X416383D01*
G01X411950Y304000D02*
Y306500D01*
X413492Y304708D01*
X411408D01*
G01X409350Y304000D02*
X409058Y304042D01*
X408725Y304167D01*
X408517Y304375D01*
X408433Y304667D01*
X408517Y304958D01*
X408767Y305208D01*
X409142Y305333D01*
X409558D01*
X409808Y305417D01*
X410017Y305625D01*
X410100Y305917D01*
X409975Y306208D01*
X409683Y306417D01*
X409350Y306500D01*
X409017Y306417D01*
X408725Y306208D01*
X408600Y305917D01*
X408683Y305625D01*
X408892Y305417D01*
X409142Y305333D01*
X409558D01*
X409933Y305208D01*
X410183Y304958D01*
X410267Y304667D01*
X410183Y304375D01*
X409975Y304167D01*
X409642Y304042D01*
X409350Y304000D01*
G01X440000Y312350D02*
X437500D01*
G01X440000Y311392D02*
Y313308D01*
G01X437500Y314617D02*
X440000D01*
Y315617D01*
X439875Y315950D01*
X439583Y316200D01*
X439250Y316283D01*
X438917Y316200D01*
X438667Y315992D01*
X438542Y315617D01*
Y314617D01*
G01X437500Y319050D02*
X440000D01*
X438208Y317508D01*
Y319592D01*
G01X437792Y320942D02*
X437583Y321233D01*
X437500Y321567D01*
X437583Y321900D01*
X437833Y322192D01*
X438208Y322400D01*
X438583Y322483D01*
X439042D01*
X439417Y322400D01*
X439750Y322192D01*
X439917Y321942D01*
X440000Y321650D01*
X439917Y321317D01*
X439750Y321067D01*
X439500Y320900D01*
X439167Y320817D01*
X438875Y320900D01*
X438583Y321108D01*
X438417Y321358D01*
X438375Y321650D01*
X438458Y321983D01*
X438667Y322233D01*
X439042Y322483D01*
G01X442650Y327667D02*
Y325167D01*
G01X443608Y327667D02*
X441692D01*
G01X440383Y325167D02*
Y327667D01*
X439383D01*
X439050Y327542D01*
X438800Y327250D01*
X438717Y326917D01*
X438800Y326584D01*
X439008Y326334D01*
X439383Y326209D01*
X440383D01*
G01X437367Y325542D02*
X437117Y325334D01*
X436825Y325209D01*
X436450Y325167D01*
X436075Y325250D01*
X435783Y325417D01*
X435575Y325709D01*
X435533Y326042D01*
X435617Y326375D01*
X435825Y326584D01*
X436117Y326750D01*
X436408Y326792D01*
X436700Y326750D01*
X437075Y326584D01*
X436950Y327667D01*
X435825D01*
G01X433350Y325167D02*
Y327667D01*
X433850Y327167D01*
G01Y325167D02*
X432850D01*
G01X448478Y375885D02*
X450978D01*
Y376926D01*
X450853Y377260D01*
X450686Y377468D01*
X450353Y377551D01*
X450020Y377468D01*
X449811Y377218D01*
X449686Y376926D01*
Y375885D01*
G01Y376926D02*
X448478Y377551D01*
G01X448853Y378901D02*
X448645Y379151D01*
X448520Y379443D01*
X448478Y379818D01*
X448561Y380193D01*
X448728Y380485D01*
X449020Y380693D01*
X449353Y380735D01*
X449686Y380651D01*
X449895Y380443D01*
X450061Y380151D01*
X450103Y379860D01*
X450061Y379568D01*
X449895Y379193D01*
X450978Y379318D01*
Y380443D01*
G01X449520Y382126D02*
X449811Y382418D01*
X449978Y382668D01*
X450061Y383001D01*
X449978Y383293D01*
X449811Y383501D01*
X449561Y383668D01*
X449270Y383710D01*
X449020Y383668D01*
X448770Y383501D01*
X448561Y383251D01*
X448478Y382960D01*
X448561Y382626D01*
X448811Y382335D01*
X449186Y382168D01*
X449603Y382126D01*
X450145Y382210D01*
X450436Y382335D01*
X450728Y382543D01*
X450936Y382835D01*
X450978Y383126D01*
X450895Y383418D01*
X450686Y383626D01*
G01X448853Y385101D02*
X448645Y385351D01*
X448520Y385643D01*
X448478Y386018D01*
X448561Y386393D01*
X448728Y386685D01*
X449020Y386893D01*
X449353Y386935D01*
X449686Y386851D01*
X449895Y386643D01*
X450061Y386351D01*
X450103Y386060D01*
X450061Y385768D01*
X449895Y385393D01*
X450978Y385518D01*
Y386643D01*
G01X398500Y362517D02*
X401000D01*
Y363558D01*
X400875Y363892D01*
X400708Y364100D01*
X400375Y364183D01*
X400042Y364100D01*
X399833Y363850D01*
X399708Y363558D01*
Y362517D01*
G01Y363558D02*
X398500Y364183D01*
G01X398875Y365533D02*
X398667Y365783D01*
X398542Y366075D01*
X398500Y366450D01*
X398583Y366825D01*
X398750Y367117D01*
X399042Y367325D01*
X399375Y367367D01*
X399708Y367283D01*
X399917Y367075D01*
X400083Y366783D01*
X400125Y366492D01*
X400083Y366200D01*
X399917Y365825D01*
X401000Y365950D01*
Y367075D01*
G01X399542Y368758D02*
X399833Y369050D01*
X400000Y369300D01*
X400083Y369633D01*
X400000Y369925D01*
X399833Y370133D01*
X399583Y370300D01*
X399292Y370342D01*
X399042Y370300D01*
X398792Y370133D01*
X398583Y369883D01*
X398500Y369592D01*
X398583Y369258D01*
X398833Y368967D01*
X399208Y368800D01*
X399625Y368758D01*
X400167Y368842D01*
X400458Y368967D01*
X400750Y369175D01*
X400958Y369467D01*
X401000Y369758D01*
X400917Y370050D01*
X400708Y370258D01*
G01X398500Y372567D02*
X399042Y372650D01*
X399500Y372775D01*
X399917Y372942D01*
X400375Y373150D01*
X401000Y373483D01*
Y371817D01*
G01X402500Y362567D02*
X405000D01*
Y363608D01*
X404875Y363942D01*
X404708Y364150D01*
X404375Y364233D01*
X404042Y364150D01*
X403833Y363900D01*
X403708Y363608D01*
Y362567D01*
G01Y363608D02*
X402500Y364233D01*
G01Y366500D02*
X402542Y366792D01*
X402667Y367125D01*
X402875Y367333D01*
X403167Y367417D01*
X403458Y367333D01*
X403708Y367083D01*
X403833Y366708D01*
Y366292D01*
X403917Y366042D01*
X404125Y365833D01*
X404417Y365750D01*
X404708Y365875D01*
X404917Y366167D01*
X405000Y366500D01*
X404917Y366833D01*
X404708Y367125D01*
X404417Y367250D01*
X404125Y367167D01*
X403917Y366958D01*
X403833Y366708D01*
Y366292D01*
X403708Y365917D01*
X403458Y365667D01*
X403167Y365583D01*
X402875Y365667D01*
X402667Y365875D01*
X402542Y366208D01*
X402500Y366500D01*
G01X402875Y368683D02*
X402667Y368933D01*
X402542Y369225D01*
X402500Y369600D01*
X402583Y369975D01*
X402750Y370267D01*
X403042Y370475D01*
X403375Y370517D01*
X403708Y370433D01*
X403917Y370225D01*
X404083Y369933D01*
X404125Y369642D01*
X404083Y369350D01*
X403917Y368975D01*
X405000Y369100D01*
Y370225D01*
G01X406500Y362567D02*
X409000D01*
Y363608D01*
X408875Y363942D01*
X408708Y364150D01*
X408375Y364233D01*
X408042Y364150D01*
X407833Y363900D01*
X407708Y363608D01*
Y362567D01*
G01Y363608D02*
X406500Y364233D01*
G01Y366500D02*
X406542Y366792D01*
X406667Y367125D01*
X406875Y367333D01*
X407167Y367417D01*
X407458Y367333D01*
X407708Y367083D01*
X407833Y366708D01*
Y366292D01*
X407917Y366042D01*
X408125Y365833D01*
X408417Y365750D01*
X408708Y365875D01*
X408917Y366167D01*
X409000Y366500D01*
X408917Y366833D01*
X408708Y367125D01*
X408417Y367250D01*
X408125Y367167D01*
X407917Y366958D01*
X407833Y366708D01*
Y366292D01*
X407708Y365917D01*
X407458Y365667D01*
X407167Y365583D01*
X406875Y365667D01*
X406667Y365875D01*
X406542Y366208D01*
X406500Y366500D01*
G01X407542Y368808D02*
X407833Y369100D01*
X408000Y369350D01*
X408083Y369683D01*
X408000Y369975D01*
X407833Y370183D01*
X407583Y370350D01*
X407292Y370392D01*
X407042Y370350D01*
X406792Y370183D01*
X406583Y369933D01*
X406500Y369642D01*
X406583Y369308D01*
X406833Y369017D01*
X407208Y368850D01*
X407625Y368808D01*
X408167Y368892D01*
X408458Y369017D01*
X408750Y369225D01*
X408958Y369517D01*
X409000Y369808D01*
X408917Y370100D01*
X408708Y370308D01*
G01X437933Y374500D02*
Y377000D01*
X436892D01*
X436558Y376875D01*
X436350Y376708D01*
X436267Y376375D01*
X436350Y376042D01*
X436600Y375833D01*
X436892Y375708D01*
X437933D01*
G01X436892D02*
X436267Y374500D01*
G01X433500D02*
Y377000D01*
X435042Y375208D01*
X432958D01*
G01X431817Y374875D02*
X431567Y374667D01*
X431275Y374542D01*
X430900Y374500D01*
X430525Y374583D01*
X430233Y374750D01*
X430025Y375042D01*
X429983Y375375D01*
X430067Y375708D01*
X430275Y375917D01*
X430567Y376083D01*
X430858Y376125D01*
X431150Y376083D01*
X431525Y375917D01*
X431400Y377000D01*
X430275D01*
G01X439433Y378500D02*
Y381000D01*
X438392D01*
X438058Y380875D01*
X437850Y380708D01*
X437767Y380375D01*
X437850Y380042D01*
X438100Y379833D01*
X438392Y379708D01*
X439433D01*
G01X438392D02*
X437767Y378500D01*
G01X436417Y379000D02*
X436167Y378708D01*
X435833Y378542D01*
X435458Y378500D01*
X435125Y378542D01*
X434792Y378750D01*
X434583Y379000D01*
X434542Y379250D01*
X434625Y379542D01*
X434917Y379750D01*
X435208Y379833D01*
X435583D01*
G01X435208D02*
X434958Y379958D01*
X434750Y380167D01*
X434667Y380417D01*
X434750Y380667D01*
X434958Y380875D01*
X435333Y381000D01*
X435708Y380958D01*
X436083Y380792D01*
G01X432483Y378500D02*
X432400Y379042D01*
X432275Y379500D01*
X432108Y379917D01*
X431900Y380375D01*
X431567Y381000D01*
X433233D01*
G01X442700Y362567D02*
X445200D01*
Y363608D01*
X445075Y363942D01*
X444908Y364150D01*
X444575Y364233D01*
X444242Y364150D01*
X444033Y363900D01*
X443908Y363608D01*
Y362567D01*
G01Y363608D02*
X442700Y364233D01*
G01Y366500D02*
X445200D01*
X444700Y366000D01*
G01X442700D02*
Y367000D01*
G01Y370100D02*
X445200D01*
X443408Y368558D01*
Y370642D01*
G01X443742Y371908D02*
X444033Y372200D01*
X444200Y372450D01*
X444283Y372783D01*
X444200Y373075D01*
X444033Y373283D01*
X443783Y373450D01*
X443492Y373492D01*
X443242Y373450D01*
X442992Y373283D01*
X442783Y373033D01*
X442700Y372742D01*
X442783Y372408D01*
X443033Y372117D01*
X443408Y371950D01*
X443825Y371908D01*
X444367Y371992D01*
X444658Y372117D01*
X444950Y372325D01*
X445158Y372617D01*
X445200Y372908D01*
X445117Y373200D01*
X444908Y373408D01*
G01X438700Y362567D02*
X441200D01*
Y363608D01*
X441075Y363942D01*
X440908Y364150D01*
X440575Y364233D01*
X440242Y364150D01*
X440033Y363900D01*
X439908Y363608D01*
Y362567D01*
G01Y363608D02*
X438700Y364233D01*
G01Y366500D02*
X441200D01*
X440700Y366000D01*
G01X438700D02*
Y367000D01*
G01Y370100D02*
X441200D01*
X439408Y368558D01*
Y370642D01*
G01X439200Y371783D02*
X438908Y372033D01*
X438742Y372367D01*
X438700Y372742D01*
X438742Y373075D01*
X438950Y373408D01*
X439200Y373617D01*
X439450Y373658D01*
X439742Y373575D01*
X439950Y373283D01*
X440033Y372992D01*
Y372617D01*
G01Y372992D02*
X440158Y373242D01*
X440367Y373450D01*
X440617Y373533D01*
X440867Y373450D01*
X441075Y373242D01*
X441200Y372867D01*
X441158Y372492D01*
X440992Y372117D01*
G01X431000Y362667D02*
X433500D01*
Y363708D01*
X433375Y364042D01*
X433208Y364250D01*
X432875Y364333D01*
X432542Y364250D01*
X432333Y364000D01*
X432208Y363708D01*
Y362667D01*
G01Y363708D02*
X431000Y364333D01*
G01Y366600D02*
X433500D01*
X433000Y366100D01*
G01X431000D02*
Y367100D01*
G01Y370200D02*
X433500D01*
X431708Y368658D01*
Y370742D01*
G01X431000Y372800D02*
X433500D01*
X433000Y372300D01*
G01X431000D02*
Y373300D01*
G01X410500Y362567D02*
X413000D01*
Y363608D01*
X412875Y363942D01*
X412708Y364150D01*
X412375Y364233D01*
X412042Y364150D01*
X411833Y363900D01*
X411708Y363608D01*
Y362567D01*
G01Y363608D02*
X410500Y364233D01*
G01Y367000D02*
X413000D01*
X411208Y365458D01*
Y367542D01*
G01X410500Y369517D02*
X411042Y369600D01*
X411500Y369725D01*
X411917Y369892D01*
X412375Y370100D01*
X413000Y370433D01*
Y368767D01*
G01X422500Y362517D02*
X425000D01*
Y363558D01*
X424875Y363892D01*
X424708Y364100D01*
X424375Y364183D01*
X424042Y364100D01*
X423833Y363850D01*
X423708Y363558D01*
Y362517D01*
G01Y363558D02*
X422500Y364183D01*
G01Y366450D02*
X425000D01*
X424500Y365950D01*
G01X422500D02*
Y366950D01*
G01X423000Y368633D02*
X422708Y368883D01*
X422542Y369217D01*
X422500Y369592D01*
X422542Y369925D01*
X422750Y370258D01*
X423000Y370467D01*
X423250Y370508D01*
X423542Y370425D01*
X423750Y370133D01*
X423833Y369842D01*
Y369467D01*
G01Y369842D02*
X423958Y370092D01*
X424167Y370300D01*
X424417Y370383D01*
X424667Y370300D01*
X424875Y370092D01*
X425000Y369717D01*
X424958Y369342D01*
X424792Y368967D01*
G01X422500Y372650D02*
X422542Y372942D01*
X422667Y373275D01*
X422875Y373483D01*
X423167Y373567D01*
X423458Y373483D01*
X423708Y373233D01*
X423833Y372858D01*
Y372442D01*
X423917Y372192D01*
X424125Y371983D01*
X424417Y371900D01*
X424708Y372025D01*
X424917Y372317D01*
X425000Y372650D01*
X424917Y372983D01*
X424708Y373275D01*
X424417Y373400D01*
X424125Y373317D01*
X423917Y373108D01*
X423833Y372858D01*
Y372442D01*
X423708Y372067D01*
X423458Y371817D01*
X423167Y371733D01*
X422875Y371817D01*
X422667Y372025D01*
X422542Y372358D01*
X422500Y372650D01*
G01X414500Y362517D02*
X417000D01*
Y363558D01*
X416875Y363892D01*
X416708Y364100D01*
X416375Y364183D01*
X416042Y364100D01*
X415833Y363850D01*
X415708Y363558D01*
Y362517D01*
G01Y363558D02*
X414500Y364183D01*
G01Y366450D02*
X417000D01*
X416500Y365950D01*
G01X414500D02*
Y366950D01*
G01Y369550D02*
X417000D01*
X416500Y369050D01*
G01X414500D02*
Y370050D01*
G01Y373150D02*
X417000D01*
X415208Y371608D01*
Y373692D01*
G01X423483Y376500D02*
Y379000D01*
X422442D01*
X422108Y378875D01*
X421900Y378708D01*
X421817Y378375D01*
X421900Y378042D01*
X422150Y377833D01*
X422442Y377708D01*
X423483D01*
G01X422442D02*
X421817Y376500D01*
G01X419550D02*
Y379000D01*
X420050Y378500D01*
G01Y376500D02*
X419050D01*
G01X416450Y379000D02*
X416783Y378917D01*
X417033Y378708D01*
X417200Y378458D01*
X417325Y378125D01*
X417367Y377750D01*
X417325Y377375D01*
X417200Y377042D01*
X417033Y376792D01*
X416783Y376583D01*
X416450Y376500D01*
X416117Y376583D01*
X415867Y376792D01*
X415700Y377042D01*
X415575Y377375D01*
X415533Y377750D01*
X415575Y378125D01*
X415700Y378458D01*
X415867Y378708D01*
X416117Y378917D01*
X416450Y379000D01*
G01X414058Y376792D02*
X413767Y376583D01*
X413433Y376500D01*
X413100Y376583D01*
X412808Y376833D01*
X412600Y377208D01*
X412517Y377583D01*
Y378042D01*
X412600Y378417D01*
X412808Y378750D01*
X413058Y378917D01*
X413350Y379000D01*
X413683Y378917D01*
X413933Y378750D01*
X414100Y378500D01*
X414183Y378167D01*
X414100Y377875D01*
X413892Y377583D01*
X413642Y377417D01*
X413350Y377375D01*
X413017Y377458D01*
X412767Y377667D01*
X412517Y378042D01*
G01X418500Y362517D02*
X421000D01*
Y363558D01*
X420875Y363892D01*
X420708Y364100D01*
X420375Y364183D01*
X420042Y364100D01*
X419833Y363850D01*
X419708Y363558D01*
Y362517D01*
G01Y363558D02*
X418500Y364183D01*
G01Y366450D02*
X421000D01*
X420500Y365950D01*
G01X418500D02*
Y366950D01*
G01X421000Y369550D02*
X420917Y369217D01*
X420708Y368967D01*
X420458Y368800D01*
X420125Y368675D01*
X419750Y368633D01*
X419375Y368675D01*
X419042Y368800D01*
X418792Y368967D01*
X418583Y369217D01*
X418500Y369550D01*
X418583Y369883D01*
X418792Y370133D01*
X419042Y370300D01*
X419375Y370425D01*
X419750Y370467D01*
X420125Y370425D01*
X420458Y370300D01*
X420708Y370133D01*
X420917Y369883D01*
X421000Y369550D01*
G01X418500Y373150D02*
X421000D01*
X419208Y371608D01*
Y373692D01*
G01X446500Y362567D02*
X449000D01*
Y363608D01*
X448875Y363942D01*
X448708Y364150D01*
X448375Y364233D01*
X448042Y364150D01*
X447833Y363900D01*
X447708Y363608D01*
Y362567D01*
G01Y363608D02*
X446500Y364233D01*
G01X448583Y365708D02*
X448833Y365958D01*
X448958Y366250D01*
X449000Y366583D01*
X448917Y367000D01*
X448708Y367292D01*
X448458Y367375D01*
X448208Y367333D01*
X448000Y367167D01*
X447583Y366333D01*
X447292Y365958D01*
X446875Y365708D01*
X446500Y365625D01*
Y367375D01*
G01Y369600D02*
X449000D01*
X448500Y369100D01*
G01X446500D02*
Y370100D01*
G01X449000Y372700D02*
X448917Y372367D01*
X448708Y372117D01*
X448458Y371950D01*
X448125Y371825D01*
X447750Y371783D01*
X447375Y371825D01*
X447042Y371950D01*
X446792Y372117D01*
X446583Y372367D01*
X446500Y372700D01*
X446583Y373033D01*
X446792Y373283D01*
X447042Y373450D01*
X447375Y373575D01*
X447750Y373617D01*
X448125Y373575D01*
X448458Y373450D01*
X448708Y373283D01*
X448917Y373033D01*
X449000Y372700D01*
G01X427000Y362517D02*
X429500D01*
Y363558D01*
X429375Y363892D01*
X429208Y364100D01*
X428875Y364183D01*
X428542Y364100D01*
X428333Y363850D01*
X428208Y363558D01*
Y362517D01*
G01Y363558D02*
X427000Y364183D01*
G01Y366950D02*
X429500D01*
X427708Y365408D01*
Y367492D01*
G01X429500Y369550D02*
X429417Y369217D01*
X429208Y368967D01*
X428958Y368800D01*
X428625Y368675D01*
X428250Y368633D01*
X427875Y368675D01*
X427542Y368800D01*
X427292Y368967D01*
X427083Y369217D01*
X427000Y369550D01*
X427083Y369883D01*
X427292Y370133D01*
X427542Y370300D01*
X427875Y370425D01*
X428250Y370467D01*
X428625Y370425D01*
X428958Y370300D01*
X429208Y370133D01*
X429417Y369883D01*
X429500Y369550D01*
G01X427375Y371733D02*
X427167Y371983D01*
X427042Y372275D01*
X427000Y372650D01*
X427083Y373025D01*
X427250Y373317D01*
X427542Y373525D01*
X427875Y373567D01*
X428208Y373483D01*
X428417Y373275D01*
X428583Y372983D01*
X428625Y372692D01*
X428583Y372400D01*
X428417Y372025D01*
X429500Y372150D01*
Y373275D01*
G01X435000Y362517D02*
X437500D01*
Y363558D01*
X437375Y363892D01*
X437208Y364100D01*
X436875Y364183D01*
X436542Y364100D01*
X436333Y363850D01*
X436208Y363558D01*
Y362517D01*
G01Y363558D02*
X435000Y364183D01*
G01X435500Y365533D02*
X435208Y365783D01*
X435042Y366117D01*
X435000Y366492D01*
X435042Y366825D01*
X435250Y367158D01*
X435500Y367367D01*
X435750Y367408D01*
X436042Y367325D01*
X436250Y367033D01*
X436333Y366742D01*
Y366367D01*
G01Y366742D02*
X436458Y366992D01*
X436667Y367200D01*
X436917Y367283D01*
X437167Y367200D01*
X437375Y366992D01*
X437500Y366617D01*
X437458Y366242D01*
X437292Y365867D01*
G01X435292Y368842D02*
X435083Y369133D01*
X435000Y369467D01*
X435083Y369800D01*
X435333Y370092D01*
X435708Y370300D01*
X436083Y370383D01*
X436542D01*
X436917Y370300D01*
X437250Y370092D01*
X437417Y369842D01*
X437500Y369550D01*
X437417Y369217D01*
X437250Y368967D01*
X437000Y368800D01*
X436667Y368717D01*
X436375Y368800D01*
X436083Y369008D01*
X435917Y369258D01*
X435875Y369550D01*
X435958Y369883D01*
X436167Y370133D01*
X436542Y370383D01*
G01X435500Y371733D02*
X435208Y371983D01*
X435042Y372317D01*
X435000Y372692D01*
X435042Y373025D01*
X435250Y373358D01*
X435500Y373567D01*
X435750Y373608D01*
X436042Y373525D01*
X436250Y373233D01*
X436333Y372942D01*
Y372567D01*
G01Y372942D02*
X436458Y373192D01*
X436667Y373400D01*
X436917Y373483D01*
X437167Y373400D01*
X437375Y373192D01*
X437500Y372817D01*
X437458Y372442D01*
X437292Y372067D01*
G01X474000Y178500D02*
X475000D01*
Y168500D01*
X473500D01*
G01X464100D02*
X461546D01*
G01X458000D02*
X455500D01*
G01X452000D02*
X449500D01*
G01X469390D02*
X467100D01*
G01X503792Y165817D02*
X503917Y165567D01*
X504000Y165275D01*
Y164942D01*
X503875Y164567D01*
X503667Y164275D01*
X503417Y164067D01*
X503000Y163900D01*
X502625Y163858D01*
X502250Y163942D01*
X502000Y164067D01*
X501750Y164317D01*
X501583Y164608D01*
X501500Y164900D01*
Y165192D01*
X501583Y165483D01*
X501708Y165733D01*
X501875Y165942D01*
G01X502000Y167083D02*
X501708Y167333D01*
X501542Y167667D01*
X501500Y168042D01*
X501542Y168375D01*
X501750Y168708D01*
X502000Y168917D01*
X502250Y168958D01*
X502542Y168875D01*
X502750Y168583D01*
X502833Y168292D01*
Y167917D01*
G01Y168292D02*
X502958Y168542D01*
X503167Y168750D01*
X503417Y168833D01*
X503667Y168750D01*
X503875Y168542D01*
X504000Y168167D01*
X503958Y167792D01*
X503792Y167417D01*
G01X503583Y170308D02*
X503833Y170558D01*
X503958Y170850D01*
X504000Y171183D01*
X503917Y171600D01*
X503708Y171892D01*
X503458Y171975D01*
X503208Y171933D01*
X503000Y171767D01*
X502583Y170933D01*
X502292Y170558D01*
X501875Y170308D01*
X501500Y170225D01*
Y171975D01*
G01X512292Y157817D02*
X512417Y157567D01*
X512500Y157275D01*
Y156942D01*
X512375Y156567D01*
X512167Y156275D01*
X511917Y156067D01*
X511500Y155900D01*
X511125Y155858D01*
X510750Y155942D01*
X510500Y156067D01*
X510250Y156317D01*
X510083Y156608D01*
X510000Y156900D01*
Y157192D01*
X510083Y157483D01*
X510208Y157733D01*
X510375Y157942D01*
G01X510500Y159083D02*
X510208Y159333D01*
X510042Y159667D01*
X510000Y160042D01*
X510042Y160375D01*
X510250Y160708D01*
X510500Y160917D01*
X510750Y160958D01*
X511042Y160875D01*
X511250Y160583D01*
X511333Y160292D01*
Y159917D01*
G01Y160292D02*
X511458Y160542D01*
X511667Y160750D01*
X511917Y160833D01*
X512167Y160750D01*
X512375Y160542D01*
X512500Y160167D01*
X512458Y159792D01*
X512292Y159417D01*
G01X510000Y163100D02*
X512500D01*
X512000Y162600D01*
G01X510000D02*
Y163600D01*
G01X513292Y171817D02*
X513417Y171567D01*
X513500Y171275D01*
Y170942D01*
X513375Y170567D01*
X513167Y170275D01*
X512917Y170067D01*
X512500Y169900D01*
X512125Y169858D01*
X511750Y169942D01*
X511500Y170067D01*
X511250Y170317D01*
X511083Y170608D01*
X511000Y170900D01*
Y171192D01*
X511083Y171483D01*
X511208Y171733D01*
X511375Y171942D01*
G01X511500Y173083D02*
X511208Y173333D01*
X511042Y173667D01*
X511000Y174042D01*
X511042Y174375D01*
X511250Y174708D01*
X511500Y174917D01*
X511750Y174958D01*
X512042Y174875D01*
X512250Y174583D01*
X512333Y174292D01*
Y173917D01*
G01Y174292D02*
X512458Y174542D01*
X512667Y174750D01*
X512917Y174833D01*
X513167Y174750D01*
X513375Y174542D01*
X513500Y174167D01*
X513458Y173792D01*
X513292Y173417D01*
G01X513500Y177100D02*
X513417Y176767D01*
X513208Y176517D01*
X512958Y176350D01*
X512625Y176225D01*
X512250Y176183D01*
X511875Y176225D01*
X511542Y176350D01*
X511292Y176517D01*
X511083Y176767D01*
X511000Y177100D01*
X511083Y177433D01*
X511292Y177683D01*
X511542Y177850D01*
X511875Y177975D01*
X512250Y178017D01*
X512625Y177975D01*
X512958Y177850D01*
X513208Y177683D01*
X513417Y177433D01*
X513500Y177100D01*
G01X493000Y222500D02*
X493500D01*
Y208000D01*
X505000D01*
G01X468673Y178500D02*
X470000D01*
G01X462132D02*
X464000D01*
G01X456520D02*
X458000D01*
G01X450485D02*
X452000D01*
G01X512500Y210500D02*
Y235677D01*
X493600D01*
G02X493500Y235777I0J100D01*
G01Y259000D01*
G01X491492Y214267D02*
X491617Y214017D01*
X491700Y213725D01*
Y213392D01*
X491575Y213017D01*
X491367Y212725D01*
X491117Y212517D01*
X490700Y212350D01*
X490325Y212308D01*
X489950Y212392D01*
X489700Y212517D01*
X489450Y212767D01*
X489283Y213058D01*
X489200Y213350D01*
Y213642D01*
X489283Y213933D01*
X489408Y214183D01*
X489575Y214392D01*
G01X491283Y215658D02*
X491533Y215908D01*
X491658Y216200D01*
X491700Y216533D01*
X491617Y216950D01*
X491408Y217242D01*
X491158Y217325D01*
X490908Y217283D01*
X490700Y217117D01*
X490283Y216283D01*
X489992Y215908D01*
X489575Y215658D01*
X489200Y215575D01*
Y217325D01*
G01Y219550D02*
X489242Y219842D01*
X489367Y220175D01*
X489575Y220383D01*
X489867Y220467D01*
X490158Y220383D01*
X490408Y220133D01*
X490533Y219758D01*
Y219342D01*
X490617Y219092D01*
X490825Y218883D01*
X491117Y218800D01*
X491408Y218925D01*
X491617Y219217D01*
X491700Y219550D01*
X491617Y219883D01*
X491408Y220175D01*
X491117Y220300D01*
X490825Y220217D01*
X490617Y220008D01*
X490533Y219758D01*
Y219342D01*
X490408Y218967D01*
X490158Y218717D01*
X489867Y218633D01*
X489575Y218717D01*
X489367Y218925D01*
X489242Y219258D01*
X489200Y219550D01*
G01Y222650D02*
X491700D01*
X491200Y222150D01*
G01X489200D02*
Y223150D01*
G01X491792Y199967D02*
X491917Y199717D01*
X492000Y199425D01*
Y199092D01*
X491875Y198717D01*
X491667Y198425D01*
X491417Y198217D01*
X491000Y198050D01*
X490625Y198008D01*
X490250Y198092D01*
X490000Y198217D01*
X489750Y198467D01*
X489583Y198758D01*
X489500Y199050D01*
Y199342D01*
X489583Y199633D01*
X489708Y199883D01*
X489875Y200092D01*
G01X491583Y201358D02*
X491833Y201608D01*
X491958Y201900D01*
X492000Y202233D01*
X491917Y202650D01*
X491708Y202942D01*
X491458Y203025D01*
X491208Y202983D01*
X491000Y202817D01*
X490583Y201983D01*
X490292Y201608D01*
X489875Y201358D01*
X489500Y201275D01*
Y203025D01*
G01Y205250D02*
X489542Y205542D01*
X489667Y205875D01*
X489875Y206083D01*
X490167Y206167D01*
X490458Y206083D01*
X490708Y205833D01*
X490833Y205458D01*
Y205042D01*
X490917Y204792D01*
X491125Y204583D01*
X491417Y204500D01*
X491708Y204625D01*
X491917Y204917D01*
X492000Y205250D01*
X491917Y205583D01*
X491708Y205875D01*
X491417Y206000D01*
X491125Y205917D01*
X490917Y205708D01*
X490833Y205458D01*
Y205042D01*
X490708Y204667D01*
X490458Y204417D01*
X490167Y204333D01*
X489875Y204417D01*
X489667Y204625D01*
X489542Y204958D01*
X489500Y205250D01*
G01X489792Y207642D02*
X489583Y207933D01*
X489500Y208267D01*
X489583Y208600D01*
X489833Y208892D01*
X490208Y209100D01*
X490583Y209183D01*
X491042D01*
X491417Y209100D01*
X491750Y208892D01*
X491917Y208642D01*
X492000Y208350D01*
X491917Y208017D01*
X491750Y207767D01*
X491500Y207600D01*
X491167Y207517D01*
X490875Y207600D01*
X490583Y207808D01*
X490417Y208058D01*
X490375Y208350D01*
X490458Y208683D01*
X490667Y208933D01*
X491042Y209183D01*
G01X508983Y202000D02*
Y204500D01*
X507942D01*
X507608Y204375D01*
X507400Y204208D01*
X507317Y203875D01*
X507400Y203542D01*
X507650Y203333D01*
X507942Y203208D01*
X508983D01*
G01X507942D02*
X507317Y202000D01*
G01X505050D02*
Y204500D01*
X505550Y204000D01*
G01Y202000D02*
X504550D01*
G01X501950D02*
Y204500D01*
X502450Y204000D01*
G01Y202000D02*
X501450D01*
G01X499767Y202375D02*
X499517Y202167D01*
X499225Y202042D01*
X498850Y202000D01*
X498475Y202083D01*
X498183Y202250D01*
X497975Y202542D01*
X497933Y202875D01*
X498017Y203208D01*
X498225Y203417D01*
X498517Y203583D01*
X498808Y203625D01*
X499100Y203583D01*
X499475Y203417D01*
X499350Y204500D01*
X498225D01*
G01X496500Y192800D02*
Y196800D01*
X503900D01*
G01X493500Y264500D02*
Y287670D01*
X494670D01*
G01X495220Y293390D02*
X483000D01*
Y289000D01*
X479100D01*
Y287500D01*
G01X481892Y292267D02*
X482017Y292017D01*
X482100Y291725D01*
Y291392D01*
X481975Y291017D01*
X481767Y290725D01*
X481517Y290517D01*
X481100Y290350D01*
X480725Y290308D01*
X480350Y290392D01*
X480100Y290517D01*
X479850Y290767D01*
X479683Y291058D01*
X479600Y291350D01*
Y291642D01*
X479683Y291933D01*
X479808Y292183D01*
X479975Y292392D01*
G01X479600Y294450D02*
X482100D01*
X481600Y293950D01*
G01X479600D02*
Y294950D01*
G01X481683Y296758D02*
X481933Y297008D01*
X482058Y297300D01*
X482100Y297633D01*
X482017Y298050D01*
X481808Y298342D01*
X481558Y298425D01*
X481308Y298383D01*
X481100Y298217D01*
X480683Y297383D01*
X480392Y297008D01*
X479975Y296758D01*
X479600Y296675D01*
Y298425D01*
G01Y301150D02*
X482100D01*
X480308Y299608D01*
Y301692D01*
G01X478092Y289767D02*
X478217Y289517D01*
X478300Y289225D01*
Y288892D01*
X478175Y288517D01*
X477967Y288225D01*
X477717Y288017D01*
X477300Y287850D01*
X476925Y287808D01*
X476550Y287892D01*
X476300Y288017D01*
X476050Y288267D01*
X475883Y288558D01*
X475800Y288850D01*
Y289142D01*
X475883Y289433D01*
X476008Y289683D01*
X476175Y289892D01*
G01X475800Y291950D02*
X478300D01*
X477800Y291450D01*
G01X475800D02*
Y292450D01*
G01X477883Y294258D02*
X478133Y294508D01*
X478258Y294800D01*
X478300Y295133D01*
X478217Y295550D01*
X478008Y295842D01*
X477758Y295925D01*
X477508Y295883D01*
X477300Y295717D01*
X476883Y294883D01*
X476592Y294508D01*
X476175Y294258D01*
X475800Y294175D01*
Y295925D01*
G01X476300Y297233D02*
X476008Y297483D01*
X475842Y297817D01*
X475800Y298192D01*
X475842Y298525D01*
X476050Y298858D01*
X476300Y299067D01*
X476550Y299108D01*
X476842Y299025D01*
X477050Y298733D01*
X477133Y298442D01*
Y298067D01*
G01Y298442D02*
X477258Y298692D01*
X477467Y298900D01*
X477717Y298983D01*
X477967Y298900D01*
X478175Y298692D01*
X478300Y298317D01*
X478258Y297942D01*
X478092Y297567D01*
G01X459292Y287567D02*
X459417Y287317D01*
X459500Y287025D01*
Y286692D01*
X459375Y286317D01*
X459167Y286025D01*
X458917Y285817D01*
X458500Y285650D01*
X458125Y285608D01*
X457750Y285692D01*
X457500Y285817D01*
X457250Y286067D01*
X457083Y286358D01*
X457000Y286650D01*
Y286942D01*
X457083Y287233D01*
X457208Y287483D01*
X457375Y287692D01*
G01X457000Y289750D02*
X459500D01*
X459000Y289250D01*
G01X457000D02*
Y290250D01*
G01X457375Y291933D02*
X457167Y292183D01*
X457042Y292475D01*
X457000Y292850D01*
X457083Y293225D01*
X457250Y293517D01*
X457542Y293725D01*
X457875Y293767D01*
X458208Y293683D01*
X458417Y293475D01*
X458583Y293183D01*
X458625Y292892D01*
X458583Y292600D01*
X458417Y292225D01*
X459500Y292350D01*
Y293475D01*
G01X457500Y295033D02*
X457208Y295283D01*
X457042Y295617D01*
X457000Y295992D01*
X457042Y296325D01*
X457250Y296658D01*
X457500Y296867D01*
X457750Y296908D01*
X458042Y296825D01*
X458250Y296533D01*
X458333Y296242D01*
Y295867D01*
G01Y296242D02*
X458458Y296492D01*
X458667Y296700D01*
X458917Y296783D01*
X459167Y296700D01*
X459375Y296492D01*
X459500Y296117D01*
X459458Y295742D01*
X459292Y295367D01*
G01X474592Y289267D02*
X474717Y289017D01*
X474800Y288725D01*
Y288392D01*
X474675Y288017D01*
X474467Y287725D01*
X474217Y287517D01*
X473800Y287350D01*
X473425Y287308D01*
X473050Y287392D01*
X472800Y287517D01*
X472550Y287767D01*
X472383Y288058D01*
X472300Y288350D01*
Y288642D01*
X472383Y288933D01*
X472508Y289183D01*
X472675Y289392D01*
G01X472300Y291450D02*
X474800D01*
X474300Y290950D01*
G01X472300D02*
Y291950D01*
G01Y295050D02*
X474800D01*
X473008Y293508D01*
Y295592D01*
G01X472800Y296733D02*
X472508Y296983D01*
X472342Y297317D01*
X472300Y297692D01*
X472342Y298025D01*
X472550Y298358D01*
X472800Y298567D01*
X473050Y298608D01*
X473342Y298525D01*
X473550Y298233D01*
X473633Y297942D01*
Y297567D01*
G01Y297942D02*
X473758Y298192D01*
X473967Y298400D01*
X474217Y298483D01*
X474467Y298400D01*
X474675Y298192D01*
X474800Y297817D01*
X474758Y297442D01*
X474592Y297067D01*
G01X463292Y287667D02*
X463417Y287417D01*
X463500Y287125D01*
Y286792D01*
X463375Y286417D01*
X463167Y286125D01*
X462917Y285917D01*
X462500Y285750D01*
X462125Y285708D01*
X461750Y285792D01*
X461500Y285917D01*
X461250Y286167D01*
X461083Y286458D01*
X461000Y286750D01*
Y287042D01*
X461083Y287333D01*
X461208Y287583D01*
X461375Y287792D01*
G01X461000Y289850D02*
X463500D01*
X463000Y289350D01*
G01X461000D02*
Y290350D01*
G01Y293450D02*
X463500D01*
X461708Y291908D01*
Y293992D01*
G01X463500Y296050D02*
X463417Y295717D01*
X463208Y295467D01*
X462958Y295300D01*
X462625Y295175D01*
X462250Y295133D01*
X461875Y295175D01*
X461542Y295300D01*
X461292Y295467D01*
X461083Y295717D01*
X461000Y296050D01*
X461083Y296383D01*
X461292Y296633D01*
X461542Y296800D01*
X461875Y296925D01*
X462250Y296967D01*
X462625Y296925D01*
X462958Y296800D01*
X463208Y296633D01*
X463417Y296383D01*
X463500Y296050D01*
G01X455792Y287667D02*
X455917Y287417D01*
X456000Y287125D01*
Y286792D01*
X455875Y286417D01*
X455667Y286125D01*
X455417Y285917D01*
X455000Y285750D01*
X454625Y285708D01*
X454250Y285792D01*
X454000Y285917D01*
X453750Y286167D01*
X453583Y286458D01*
X453500Y286750D01*
Y287042D01*
X453583Y287333D01*
X453708Y287583D01*
X453875Y287792D01*
G01X453500Y289850D02*
X456000D01*
X455500Y289350D01*
G01X453500D02*
Y290350D01*
G01X454000Y292033D02*
X453708Y292283D01*
X453542Y292617D01*
X453500Y292992D01*
X453542Y293325D01*
X453750Y293658D01*
X454000Y293867D01*
X454250Y293908D01*
X454542Y293825D01*
X454750Y293533D01*
X454833Y293242D01*
Y292867D01*
G01Y293242D02*
X454958Y293492D01*
X455167Y293700D01*
X455417Y293783D01*
X455667Y293700D01*
X455875Y293492D01*
X456000Y293117D01*
X455958Y292742D01*
X455792Y292367D01*
G01X453500Y296550D02*
X456000D01*
X454208Y295008D01*
Y297092D01*
G01X519233Y289292D02*
X519483Y289417D01*
X519775Y289500D01*
X520108D01*
X520483Y289375D01*
X520775Y289167D01*
X520983Y288917D01*
X521150Y288500D01*
X521192Y288125D01*
X521108Y287750D01*
X520983Y287500D01*
X520733Y287250D01*
X520442Y287083D01*
X520150Y287000D01*
X519858D01*
X519567Y287083D01*
X519317Y287208D01*
X519108Y287375D01*
G01X517967Y287500D02*
X517717Y287208D01*
X517383Y287042D01*
X517008Y287000D01*
X516675Y287042D01*
X516342Y287250D01*
X516133Y287500D01*
X516092Y287750D01*
X516175Y288042D01*
X516467Y288250D01*
X516758Y288333D01*
X517133D01*
G01X516758D02*
X516508Y288458D01*
X516300Y288667D01*
X516217Y288917D01*
X516300Y289167D01*
X516508Y289375D01*
X516883Y289500D01*
X517258Y289458D01*
X517633Y289292D01*
G01X513950Y289500D02*
X514283Y289417D01*
X514533Y289208D01*
X514700Y288958D01*
X514825Y288625D01*
X514867Y288250D01*
X514825Y287875D01*
X514700Y287542D01*
X514533Y287292D01*
X514283Y287083D01*
X513950Y287000D01*
X513617Y287083D01*
X513367Y287292D01*
X513200Y287542D01*
X513075Y287875D01*
X513033Y288250D01*
X513075Y288625D01*
X513200Y288958D01*
X513367Y289208D01*
X513617Y289417D01*
X513950Y289500D01*
G01X510850Y287000D02*
X510558Y287042D01*
X510225Y287167D01*
X510017Y287375D01*
X509933Y287667D01*
X510017Y287958D01*
X510267Y288208D01*
X510642Y288333D01*
X511058D01*
X511308Y288417D01*
X511517Y288625D01*
X511600Y288917D01*
X511475Y289208D01*
X511183Y289417D01*
X510850Y289500D01*
X510517Y289417D01*
X510225Y289208D01*
X510100Y288917D01*
X510183Y288625D01*
X510392Y288417D01*
X510642Y288333D01*
X511058D01*
X511433Y288208D01*
X511683Y287958D01*
X511767Y287667D01*
X511683Y287375D01*
X511475Y287167D01*
X511142Y287042D01*
X510850Y287000D01*
G01X501233Y263292D02*
X501483Y263417D01*
X501775Y263500D01*
X502108D01*
X502483Y263375D01*
X502775Y263167D01*
X502983Y262917D01*
X503150Y262500D01*
X503192Y262125D01*
X503108Y261750D01*
X502983Y261500D01*
X502733Y261250D01*
X502442Y261083D01*
X502150Y261000D01*
X501858D01*
X501567Y261083D01*
X501317Y261208D01*
X501108Y261375D01*
G01X499842Y263083D02*
X499592Y263333D01*
X499300Y263458D01*
X498967Y263500D01*
X498550Y263417D01*
X498258Y263208D01*
X498175Y262958D01*
X498217Y262708D01*
X498383Y262500D01*
X499217Y262083D01*
X499592Y261792D01*
X499842Y261375D01*
X499925Y261000D01*
X498175D01*
G01X496658Y261292D02*
X496367Y261083D01*
X496033Y261000D01*
X495700Y261083D01*
X495408Y261333D01*
X495200Y261708D01*
X495117Y262083D01*
Y262542D01*
X495200Y262917D01*
X495408Y263250D01*
X495658Y263417D01*
X495950Y263500D01*
X496283Y263417D01*
X496533Y263250D01*
X496700Y263000D01*
X496783Y262667D01*
X496700Y262375D01*
X496492Y262083D01*
X496242Y261917D01*
X495950Y261875D01*
X495617Y261958D01*
X495367Y262167D01*
X495117Y262542D01*
G01X493642Y263083D02*
X493392Y263333D01*
X493100Y263458D01*
X492767Y263500D01*
X492350Y263417D01*
X492058Y263208D01*
X491975Y262958D01*
X492017Y262708D01*
X492183Y262500D01*
X493017Y262083D01*
X493392Y261792D01*
X493642Y261375D01*
X493725Y261000D01*
X491975D01*
G01X471292Y299767D02*
X471417Y299517D01*
X471500Y299225D01*
Y298892D01*
X471375Y298517D01*
X471167Y298225D01*
X470917Y298017D01*
X470500Y297850D01*
X470125Y297808D01*
X469750Y297892D01*
X469500Y298017D01*
X469250Y298267D01*
X469083Y298558D01*
X469000Y298850D01*
Y299142D01*
X469083Y299433D01*
X469208Y299683D01*
X469375Y299892D01*
G01X469000Y301950D02*
X471500D01*
X471000Y301450D01*
G01X469000D02*
Y302450D01*
G01X471083Y304258D02*
X471333Y304508D01*
X471458Y304800D01*
X471500Y305133D01*
X471417Y305550D01*
X471208Y305842D01*
X470958Y305925D01*
X470708Y305883D01*
X470500Y305717D01*
X470083Y304883D01*
X469792Y304508D01*
X469375Y304258D01*
X469000Y304175D01*
Y305925D01*
G01Y308150D02*
X471500D01*
X471000Y307650D01*
G01X469000D02*
Y308650D01*
G01X501233Y318292D02*
X501483Y318417D01*
X501775Y318500D01*
X502108D01*
X502483Y318375D01*
X502775Y318167D01*
X502983Y317917D01*
X503150Y317500D01*
X503192Y317125D01*
X503108Y316750D01*
X502983Y316500D01*
X502733Y316250D01*
X502442Y316083D01*
X502150Y316000D01*
X501858D01*
X501567Y316083D01*
X501317Y316208D01*
X501108Y316375D01*
G01X499050Y316000D02*
Y318500D01*
X499550Y318000D01*
G01Y316000D02*
X498550D01*
G01X496867Y316375D02*
X496617Y316167D01*
X496325Y316042D01*
X495950Y316000D01*
X495575Y316083D01*
X495283Y316250D01*
X495075Y316542D01*
X495033Y316875D01*
X495117Y317208D01*
X495325Y317417D01*
X495617Y317583D01*
X495908Y317625D01*
X496200Y317583D01*
X496575Y317417D01*
X496450Y318500D01*
X495325D01*
G01X492850Y316000D02*
Y318500D01*
X493350Y318000D01*
G01Y316000D02*
X492350D01*
G01X460792Y322267D02*
X460917Y322017D01*
X461000Y321725D01*
Y321392D01*
X460875Y321017D01*
X460667Y320725D01*
X460417Y320517D01*
X460000Y320350D01*
X459625Y320308D01*
X459250Y320392D01*
X459000Y320517D01*
X458750Y320767D01*
X458583Y321058D01*
X458500Y321350D01*
Y321642D01*
X458583Y321933D01*
X458708Y322183D01*
X458875Y322392D01*
G01X458500Y324450D02*
X461000D01*
X460500Y323950D01*
G01X458500D02*
Y324950D01*
G01Y328050D02*
X461000D01*
X459208Y326508D01*
Y328592D01*
G01X458792Y329942D02*
X458583Y330233D01*
X458500Y330567D01*
X458583Y330900D01*
X458833Y331192D01*
X459208Y331400D01*
X459583Y331483D01*
X460042D01*
X460417Y331400D01*
X460750Y331192D01*
X460917Y330942D01*
X461000Y330650D01*
X460917Y330317D01*
X460750Y330067D01*
X460500Y329900D01*
X460167Y329817D01*
X459875Y329900D01*
X459583Y330108D01*
X459417Y330358D01*
X459375Y330650D01*
X459458Y330983D01*
X459667Y331233D01*
X460042Y331483D01*
G01X490792Y314267D02*
X490917Y314017D01*
X491000Y313725D01*
Y313392D01*
X490875Y313017D01*
X490667Y312725D01*
X490417Y312517D01*
X490000Y312350D01*
X489625Y312308D01*
X489250Y312392D01*
X489000Y312517D01*
X488750Y312767D01*
X488583Y313058D01*
X488500Y313350D01*
Y313642D01*
X488583Y313933D01*
X488708Y314183D01*
X488875Y314392D01*
G01X488500Y316450D02*
X491000D01*
X490500Y315950D01*
G01X488500D02*
Y316950D01*
G01Y320050D02*
X491000D01*
X489208Y318508D01*
Y320592D01*
G01X488500Y322567D02*
X489042Y322650D01*
X489500Y322775D01*
X489917Y322942D01*
X490375Y323150D01*
X491000Y323483D01*
Y321817D01*
G01X477792Y305767D02*
X477917Y305517D01*
X478000Y305225D01*
Y304892D01*
X477875Y304517D01*
X477667Y304225D01*
X477417Y304017D01*
X477000Y303850D01*
X476625Y303808D01*
X476250Y303892D01*
X476000Y304017D01*
X475750Y304267D01*
X475583Y304558D01*
X475500Y304850D01*
Y305142D01*
X475583Y305433D01*
X475708Y305683D01*
X475875Y305892D01*
G01X475500Y307950D02*
X478000D01*
X477500Y307450D01*
G01X475500D02*
Y308450D01*
G01Y311550D02*
X478000D01*
X476208Y310008D01*
Y312092D01*
G01X475500Y314650D02*
X478000D01*
X476208Y313108D01*
Y315192D01*
G01X454792Y305267D02*
X454917Y305017D01*
X455000Y304725D01*
Y304392D01*
X454875Y304017D01*
X454667Y303725D01*
X454417Y303517D01*
X454000Y303350D01*
X453625Y303308D01*
X453250Y303392D01*
X453000Y303517D01*
X452750Y303767D01*
X452583Y304058D01*
X452500Y304350D01*
Y304642D01*
X452583Y304933D01*
X452708Y305183D01*
X452875Y305392D01*
G01X452500Y307450D02*
X455000D01*
X454500Y306950D01*
G01X452500D02*
Y307950D01*
G01X453000Y309633D02*
X452708Y309883D01*
X452542Y310217D01*
X452500Y310592D01*
X452542Y310925D01*
X452750Y311258D01*
X453000Y311467D01*
X453250Y311508D01*
X453542Y311425D01*
X453750Y311133D01*
X453833Y310842D01*
Y310467D01*
G01Y310842D02*
X453958Y311092D01*
X454167Y311300D01*
X454417Y311383D01*
X454667Y311300D01*
X454875Y311092D01*
X455000Y310717D01*
X454958Y310342D01*
X454792Y309967D01*
G01X452500Y313650D02*
X452542Y313942D01*
X452667Y314275D01*
X452875Y314483D01*
X453167Y314567D01*
X453458Y314483D01*
X453708Y314233D01*
X453833Y313858D01*
Y313442D01*
X453917Y313192D01*
X454125Y312983D01*
X454417Y312900D01*
X454708Y313025D01*
X454917Y313317D01*
X455000Y313650D01*
X454917Y313983D01*
X454708Y314275D01*
X454417Y314400D01*
X454125Y314317D01*
X453917Y314108D01*
X453833Y313858D01*
Y313442D01*
X453708Y313067D01*
X453458Y312817D01*
X453167Y312733D01*
X452875Y312817D01*
X452667Y313025D01*
X452542Y313358D01*
X452500Y313650D01*
G01X458792Y304767D02*
X458917Y304517D01*
X459000Y304225D01*
Y303892D01*
X458875Y303517D01*
X458667Y303225D01*
X458417Y303017D01*
X458000Y302850D01*
X457625Y302808D01*
X457250Y302892D01*
X457000Y303017D01*
X456750Y303267D01*
X456583Y303558D01*
X456500Y303850D01*
Y304142D01*
X456583Y304433D01*
X456708Y304683D01*
X456875Y304892D01*
G01X456500Y306950D02*
X459000D01*
X458500Y306450D01*
G01X456500D02*
Y307450D01*
G01X457000Y309133D02*
X456708Y309383D01*
X456542Y309717D01*
X456500Y310092D01*
X456542Y310425D01*
X456750Y310758D01*
X457000Y310967D01*
X457250Y311008D01*
X457542Y310925D01*
X457750Y310633D01*
X457833Y310342D01*
Y309967D01*
G01Y310342D02*
X457958Y310592D01*
X458167Y310800D01*
X458417Y310883D01*
X458667Y310800D01*
X458875Y310592D01*
X459000Y310217D01*
X458958Y309842D01*
X458792Y309467D01*
G01X456500Y313150D02*
X459000D01*
X458500Y312650D01*
G01X456500D02*
Y313650D01*
G01X476400Y361400D02*
Y365400D01*
X483800D01*
G01X488544Y361195D02*
Y357195D01*
X481144D01*
G01X469900Y348800D02*
X465900D01*
Y356200D01*
G01X476577Y337465D02*
X472577D01*
Y344865D01*
G01X498100Y349900D02*
X494100D01*
Y357300D01*
G01X499206Y339831D02*
X495206D01*
Y347231D01*
G01X459741Y358355D02*
Y354355D01*
X452341D01*
G01X466000Y338800D02*
X462000D01*
Y346200D01*
G01X453167Y320017D02*
X455667D01*
Y321058D01*
X455542Y321392D01*
X455375Y321600D01*
X455042Y321683D01*
X454709Y321600D01*
X454500Y321350D01*
X454375Y321058D01*
Y320017D01*
G01Y321058D02*
X453167Y321683D01*
G01Y323950D02*
X455667D01*
X455167Y323450D01*
G01X453167D02*
Y324450D01*
G01Y327550D02*
X455667D01*
X453875Y326008D01*
Y328092D01*
G01X453542Y329233D02*
X453334Y329483D01*
X453209Y329775D01*
X453167Y330150D01*
X453250Y330525D01*
X453417Y330817D01*
X453709Y331025D01*
X454042Y331067D01*
X454375Y330983D01*
X454584Y330775D01*
X454750Y330483D01*
X454792Y330192D01*
X454750Y329900D01*
X454584Y329525D01*
X455667Y329650D01*
Y330775D01*
G01X462000Y338800D02*
X458000D01*
Y346200D01*
G01X453300Y338900D02*
X449300D01*
Y346300D01*
G01X493445Y344958D02*
X489445D01*
Y352358D01*
G01X508000Y357000D02*
X512000D01*
Y349600D01*
G01X504000Y357000D02*
X508000D01*
Y349600D01*
G01X479400Y348900D02*
X475400D01*
Y356300D01*
G01X503379Y347211D02*
X507379D01*
Y339811D01*
G01X499281Y347211D02*
X503281D01*
Y339811D01*
G01X507517Y347246D02*
X511517D01*
Y339846D01*
G01X500200Y366009D02*
X504200D01*
Y358609D01*
G01X470000Y338800D02*
X466000D01*
Y346200D01*
G01X488873Y344956D02*
X484873D01*
Y352356D01*
G01X474000Y348800D02*
X470000D01*
Y356200D01*
G01X484644Y352873D02*
Y356873D01*
X492044D01*
G01X453900Y346200D02*
X457900D01*
Y338800D01*
G01X476618Y344842D02*
X480618D01*
Y337442D01*
G01X484618D02*
X480618D01*
Y344842D01*
G01X494792Y304467D02*
X494917Y304217D01*
X495000Y303925D01*
Y303592D01*
X494875Y303217D01*
X494667Y302925D01*
X494417Y302717D01*
X494000Y302550D01*
X493625Y302508D01*
X493250Y302592D01*
X493000Y302717D01*
X492750Y302967D01*
X492583Y303258D01*
X492500Y303550D01*
Y303842D01*
X492583Y304133D01*
X492708Y304383D01*
X492875Y304592D01*
G01X492500Y306650D02*
X495000D01*
X494500Y306150D01*
G01X492500D02*
Y307150D01*
G01Y309750D02*
X495000D01*
X494500Y309250D01*
G01X492500D02*
Y310250D01*
G01Y312850D02*
X492542Y313142D01*
X492667Y313475D01*
X492875Y313683D01*
X493167Y313767D01*
X493458Y313683D01*
X493708Y313433D01*
X493833Y313058D01*
Y312642D01*
X493917Y312392D01*
X494125Y312183D01*
X494417Y312100D01*
X494708Y312225D01*
X494917Y312517D01*
X495000Y312850D01*
X494917Y313183D01*
X494708Y313475D01*
X494417Y313600D01*
X494125Y313517D01*
X493917Y313308D01*
X493833Y313058D01*
Y312642D01*
X493708Y312267D01*
X493458Y312017D01*
X493167Y311933D01*
X492875Y312017D01*
X492667Y312225D01*
X492542Y312558D01*
X492500Y312850D01*
G01X462792Y304767D02*
X462917Y304517D01*
X463000Y304225D01*
Y303892D01*
X462875Y303517D01*
X462667Y303225D01*
X462417Y303017D01*
X462000Y302850D01*
X461625Y302808D01*
X461250Y302892D01*
X461000Y303017D01*
X460750Y303267D01*
X460583Y303558D01*
X460500Y303850D01*
Y304142D01*
X460583Y304433D01*
X460708Y304683D01*
X460875Y304892D01*
G01X460500Y306950D02*
X463000D01*
X462500Y306450D01*
G01X460500D02*
Y307450D01*
G01X462583Y309258D02*
X462833Y309508D01*
X462958Y309800D01*
X463000Y310133D01*
X462917Y310550D01*
X462708Y310842D01*
X462458Y310925D01*
X462208Y310883D01*
X462000Y310717D01*
X461583Y309883D01*
X461292Y309508D01*
X460875Y309258D01*
X460500Y309175D01*
Y310925D01*
G01X462583Y312358D02*
X462833Y312608D01*
X462958Y312900D01*
X463000Y313233D01*
X462917Y313650D01*
X462708Y313942D01*
X462458Y314025D01*
X462208Y313983D01*
X462000Y313817D01*
X461583Y312983D01*
X461292Y312608D01*
X460875Y312358D01*
X460500Y312275D01*
Y314025D01*
G01X513150Y329500D02*
Y327000D01*
G01X514108Y329500D02*
X512192D01*
G01X510883Y327000D02*
Y329500D01*
X509883D01*
X509550Y329375D01*
X509300Y329083D01*
X509217Y328750D01*
X509300Y328417D01*
X509508Y328167D01*
X509883Y328042D01*
X510883D01*
G01X507867Y327500D02*
X507617Y327208D01*
X507283Y327042D01*
X506908Y327000D01*
X506575Y327042D01*
X506242Y327250D01*
X506033Y327500D01*
X505992Y327750D01*
X506075Y328042D01*
X506367Y328250D01*
X506658Y328333D01*
X507033D01*
G01X506658D02*
X506408Y328458D01*
X506200Y328667D01*
X506117Y328917D01*
X506200Y329167D01*
X506408Y329375D01*
X506783Y329500D01*
X507158Y329458D01*
X507533Y329292D01*
G01X504642Y328042D02*
X504350Y328333D01*
X504100Y328500D01*
X503767Y328583D01*
X503475Y328500D01*
X503267Y328333D01*
X503100Y328083D01*
X503058Y327792D01*
X503100Y327542D01*
X503267Y327292D01*
X503517Y327083D01*
X503808Y327000D01*
X504142Y327083D01*
X504433Y327333D01*
X504600Y327708D01*
X504642Y328125D01*
X504558Y328667D01*
X504433Y328958D01*
X504225Y329250D01*
X503933Y329458D01*
X503642Y329500D01*
X503350Y329417D01*
X503142Y329208D01*
G01X497200Y329000D02*
Y326500D01*
G01X498158Y329000D02*
X496242D01*
G01X494933Y326500D02*
Y329000D01*
X493933D01*
X493600Y328875D01*
X493350Y328583D01*
X493267Y328250D01*
X493350Y327917D01*
X493558Y327667D01*
X493933Y327542D01*
X494933D01*
G01X491000Y326500D02*
Y329000D01*
X491500Y328500D01*
G01Y326500D02*
X490500D01*
G01X488692Y327542D02*
X488400Y327833D01*
X488150Y328000D01*
X487817Y328083D01*
X487525Y328000D01*
X487317Y327833D01*
X487150Y327583D01*
X487108Y327292D01*
X487150Y327042D01*
X487317Y326792D01*
X487567Y326583D01*
X487858Y326500D01*
X488192Y326583D01*
X488483Y326833D01*
X488650Y327208D01*
X488692Y327625D01*
X488608Y328167D01*
X488483Y328458D01*
X488275Y328750D01*
X487983Y328958D01*
X487692Y329000D01*
X487400Y328917D01*
X487192Y328708D01*
G01X484800Y326500D02*
Y329000D01*
X485300Y328500D01*
G01Y326500D02*
X484300D01*
G01X465500Y335500D02*
Y333000D01*
G01X466458Y335500D02*
X464542D01*
G01X463233Y333000D02*
Y335500D01*
X462233D01*
X461900Y335375D01*
X461650Y335083D01*
X461567Y334750D01*
X461650Y334417D01*
X461858Y334167D01*
X462233Y334042D01*
X463233D01*
G01X459300Y333000D02*
Y335500D01*
X459800Y335000D01*
G01Y333000D02*
X458800D01*
G01X457117Y333375D02*
X456867Y333167D01*
X456575Y333042D01*
X456200Y333000D01*
X455825Y333083D01*
X455533Y333250D01*
X455325Y333542D01*
X455283Y333875D01*
X455367Y334208D01*
X455575Y334417D01*
X455867Y334583D01*
X456158Y334625D01*
X456450Y334583D01*
X456825Y334417D01*
X456700Y335500D01*
X455575D01*
G01X453183Y333000D02*
X453100Y333542D01*
X452975Y334000D01*
X452808Y334417D01*
X452600Y334875D01*
X452267Y335500D01*
X453933D01*
G01X513150Y333500D02*
Y331000D01*
G01X514108Y333500D02*
X512192D01*
G01X510883Y331000D02*
Y333500D01*
X509883D01*
X509550Y333375D01*
X509300Y333083D01*
X509217Y332750D01*
X509300Y332417D01*
X509508Y332167D01*
X509883Y332042D01*
X510883D01*
G01X506950Y331000D02*
Y333500D01*
X507450Y333000D01*
G01Y331000D02*
X506450D01*
G01X504767Y331375D02*
X504517Y331167D01*
X504225Y331042D01*
X503850Y331000D01*
X503475Y331083D01*
X503183Y331250D01*
X502975Y331542D01*
X502933Y331875D01*
X503017Y332208D01*
X503225Y332417D01*
X503517Y332583D01*
X503808Y332625D01*
X504100Y332583D01*
X504475Y332417D01*
X504350Y333500D01*
X503225D01*
G01X470500Y312350D02*
X468000D01*
G01X470500Y311392D02*
Y313308D01*
G01X468000Y314617D02*
X470500D01*
Y315617D01*
X470375Y315950D01*
X470083Y316200D01*
X469750Y316283D01*
X469417Y316200D01*
X469167Y315992D01*
X469042Y315617D01*
Y314617D01*
G01X470083Y317758D02*
X470333Y318008D01*
X470458Y318300D01*
X470500Y318633D01*
X470417Y319050D01*
X470208Y319342D01*
X469958Y319425D01*
X469708Y319383D01*
X469500Y319217D01*
X469083Y318383D01*
X468792Y318008D01*
X468375Y317758D01*
X468000Y317675D01*
Y319425D01*
G01Y321567D02*
X468542Y321650D01*
X469000Y321775D01*
X469417Y321942D01*
X469875Y322150D01*
X470500Y322483D01*
Y320817D01*
G01X467000Y308350D02*
X464500D01*
G01X467000Y307392D02*
Y309308D01*
G01X464500Y310617D02*
X467000D01*
Y311617D01*
X466875Y311950D01*
X466583Y312200D01*
X466250Y312283D01*
X465917Y312200D01*
X465667Y311992D01*
X465542Y311617D01*
Y310617D01*
G01X466583Y313758D02*
X466833Y314008D01*
X466958Y314300D01*
X467000Y314633D01*
X466917Y315050D01*
X466708Y315342D01*
X466458Y315425D01*
X466208Y315383D01*
X466000Y315217D01*
X465583Y314383D01*
X465292Y314008D01*
X464875Y313758D01*
X464500Y313675D01*
Y315425D01*
G01X464875Y316733D02*
X464667Y316983D01*
X464542Y317275D01*
X464500Y317650D01*
X464583Y318025D01*
X464750Y318317D01*
X465042Y318525D01*
X465375Y318567D01*
X465708Y318483D01*
X465917Y318275D01*
X466083Y317983D01*
X466125Y317692D01*
X466083Y317400D01*
X465917Y317025D01*
X467000Y317150D01*
Y318275D01*
G01X473461Y412868D02*
Y415368D01*
X472420D01*
X472086Y415243D01*
X471878Y415076D01*
X471795Y414743D01*
X471878Y414410D01*
X472128Y414201D01*
X472420Y414076D01*
X473461D01*
G01X472420D02*
X471795Y412868D01*
G01X470445Y413243D02*
X470195Y413035D01*
X469903Y412910D01*
X469528Y412868D01*
X469153Y412951D01*
X468861Y413118D01*
X468653Y413410D01*
X468611Y413743D01*
X468695Y414076D01*
X468903Y414285D01*
X469195Y414451D01*
X469486Y414493D01*
X469778Y414451D01*
X470153Y414285D01*
X470028Y415368D01*
X468903D01*
G01X467345Y413243D02*
X467095Y413035D01*
X466803Y412910D01*
X466428Y412868D01*
X466053Y412951D01*
X465761Y413118D01*
X465553Y413410D01*
X465511Y413743D01*
X465595Y414076D01*
X465803Y414285D01*
X466095Y414451D01*
X466386Y414493D01*
X466678Y414451D01*
X467053Y414285D01*
X466928Y415368D01*
X465803D01*
G01X463411Y412868D02*
X463328Y413410D01*
X463203Y413868D01*
X463036Y414285D01*
X462828Y414743D01*
X462495Y415368D01*
X464161D01*
G01X483700Y373800D02*
Y369800D01*
X476300D01*
G01X473461Y408368D02*
Y410868D01*
X472420D01*
X472086Y410743D01*
X471878Y410576D01*
X471795Y410243D01*
X471878Y409910D01*
X472128Y409701D01*
X472420Y409576D01*
X473461D01*
G01X472420D02*
X471795Y408368D01*
G01X470445Y408743D02*
X470195Y408535D01*
X469903Y408410D01*
X469528Y408368D01*
X469153Y408451D01*
X468861Y408618D01*
X468653Y408910D01*
X468611Y409243D01*
X468695Y409576D01*
X468903Y409785D01*
X469195Y409951D01*
X469486Y409993D01*
X469778Y409951D01*
X470153Y409785D01*
X470028Y410868D01*
X468903D01*
G01X467345Y408743D02*
X467095Y408535D01*
X466803Y408410D01*
X466428Y408368D01*
X466053Y408451D01*
X465761Y408618D01*
X465553Y408910D01*
X465511Y409243D01*
X465595Y409576D01*
X465803Y409785D01*
X466095Y409951D01*
X466386Y409993D01*
X466678Y409951D01*
X467053Y409785D01*
X466928Y410868D01*
X465803D01*
G01X464036Y408660D02*
X463745Y408451D01*
X463411Y408368D01*
X463078Y408451D01*
X462786Y408701D01*
X462578Y409076D01*
X462495Y409451D01*
Y409910D01*
X462578Y410285D01*
X462786Y410618D01*
X463036Y410785D01*
X463328Y410868D01*
X463661Y410785D01*
X463911Y410618D01*
X464078Y410368D01*
X464161Y410035D01*
X464078Y409743D01*
X463870Y409451D01*
X463620Y409285D01*
X463328Y409243D01*
X462995Y409326D01*
X462745Y409535D01*
X462495Y409910D01*
G01X476400Y365500D02*
Y369500D01*
X483800D01*
G01X473461Y403868D02*
Y406368D01*
X472420D01*
X472086Y406243D01*
X471878Y406076D01*
X471795Y405743D01*
X471878Y405410D01*
X472128Y405201D01*
X472420Y405076D01*
X473461D01*
G01X472420D02*
X471795Y403868D01*
G01X470445Y404243D02*
X470195Y404035D01*
X469903Y403910D01*
X469528Y403868D01*
X469153Y403951D01*
X468861Y404118D01*
X468653Y404410D01*
X468611Y404743D01*
X468695Y405076D01*
X468903Y405285D01*
X469195Y405451D01*
X469486Y405493D01*
X469778Y405451D01*
X470153Y405285D01*
X470028Y406368D01*
X468903D01*
G01X467220Y404910D02*
X466928Y405201D01*
X466678Y405368D01*
X466345Y405451D01*
X466053Y405368D01*
X465845Y405201D01*
X465678Y404951D01*
X465636Y404660D01*
X465678Y404410D01*
X465845Y404160D01*
X466095Y403951D01*
X466386Y403868D01*
X466720Y403951D01*
X467011Y404201D01*
X467178Y404576D01*
X467220Y404993D01*
X467136Y405535D01*
X467011Y405826D01*
X466803Y406118D01*
X466511Y406326D01*
X466220Y406368D01*
X465928Y406285D01*
X465720Y406076D01*
G01X463328Y406368D02*
X463661Y406285D01*
X463911Y406076D01*
X464078Y405826D01*
X464203Y405493D01*
X464245Y405118D01*
X464203Y404743D01*
X464078Y404410D01*
X463911Y404160D01*
X463661Y403951D01*
X463328Y403868D01*
X462995Y403951D01*
X462745Y404160D01*
X462578Y404410D01*
X462453Y404743D01*
X462411Y405118D01*
X462453Y405493D01*
X462578Y405826D01*
X462745Y406076D01*
X462995Y406285D01*
X463328Y406368D01*
G01X479983Y399500D02*
Y402000D01*
X478942D01*
X478608Y401875D01*
X478400Y401708D01*
X478317Y401375D01*
X478400Y401042D01*
X478650Y400833D01*
X478942Y400708D01*
X479983D01*
G01X478942D02*
X478317Y399500D01*
G01X476967Y399875D02*
X476717Y399667D01*
X476425Y399542D01*
X476050Y399500D01*
X475675Y399583D01*
X475383Y399750D01*
X475175Y400042D01*
X475133Y400375D01*
X475217Y400708D01*
X475425Y400917D01*
X475717Y401083D01*
X476008Y401125D01*
X476300Y401083D01*
X476675Y400917D01*
X476550Y402000D01*
X475425D01*
G01X473742Y400542D02*
X473450Y400833D01*
X473200Y401000D01*
X472867Y401083D01*
X472575Y401000D01*
X472367Y400833D01*
X472200Y400583D01*
X472158Y400292D01*
X472200Y400042D01*
X472367Y399792D01*
X472617Y399583D01*
X472908Y399500D01*
X473242Y399583D01*
X473533Y399833D01*
X473700Y400208D01*
X473742Y400625D01*
X473658Y401167D01*
X473533Y401458D01*
X473325Y401750D01*
X473033Y401958D01*
X472742Y402000D01*
X472450Y401917D01*
X472242Y401708D01*
G01X470767Y400000D02*
X470517Y399708D01*
X470183Y399542D01*
X469808Y399500D01*
X469475Y399542D01*
X469142Y399750D01*
X468933Y400000D01*
X468892Y400250D01*
X468975Y400542D01*
X469267Y400750D01*
X469558Y400833D01*
X469933D01*
G01X469558D02*
X469308Y400958D01*
X469100Y401167D01*
X469017Y401417D01*
X469100Y401667D01*
X469308Y401875D01*
X469683Y402000D01*
X470058Y401958D01*
X470433Y401792D01*
G01X450500Y362517D02*
X453000D01*
Y363558D01*
X452875Y363892D01*
X452708Y364100D01*
X452375Y364183D01*
X452042Y364100D01*
X451833Y363850D01*
X451708Y363558D01*
Y362517D01*
G01Y363558D02*
X450500Y364183D01*
G01Y366950D02*
X453000D01*
X451208Y365408D01*
Y367492D01*
G01X453000Y369550D02*
X452917Y369217D01*
X452708Y368967D01*
X452458Y368800D01*
X452125Y368675D01*
X451750Y368633D01*
X451375Y368675D01*
X451042Y368800D01*
X450792Y368967D01*
X450583Y369217D01*
X450500Y369550D01*
X450583Y369883D01*
X450792Y370133D01*
X451042Y370300D01*
X451375Y370425D01*
X451750Y370467D01*
X452125Y370425D01*
X452458Y370300D01*
X452708Y370133D01*
X452917Y369883D01*
X453000Y369550D01*
G01X450500Y373150D02*
X453000D01*
X451208Y371608D01*
Y373692D01*
G01X499978Y379935D02*
X502478D01*
Y380976D01*
X502353Y381310D01*
X502186Y381518D01*
X501853Y381601D01*
X501520Y381518D01*
X501311Y381268D01*
X501186Y380976D01*
Y379935D01*
G01Y380976D02*
X499978Y381601D01*
G01Y384368D02*
X502478D01*
X500686Y382826D01*
Y384910D01*
G01X500478Y386051D02*
X500186Y386301D01*
X500020Y386635D01*
X499978Y387010D01*
X500020Y387343D01*
X500228Y387676D01*
X500478Y387885D01*
X500728Y387926D01*
X501020Y387843D01*
X501228Y387551D01*
X501311Y387260D01*
Y386885D01*
G01Y387260D02*
X501436Y387510D01*
X501645Y387718D01*
X501895Y387801D01*
X502145Y387718D01*
X502353Y387510D01*
X502478Y387135D01*
X502436Y386760D01*
X502270Y386385D01*
G01X507978Y379935D02*
X510478D01*
Y380976D01*
X510353Y381310D01*
X510186Y381518D01*
X509853Y381601D01*
X509520Y381518D01*
X509311Y381268D01*
X509186Y380976D01*
Y379935D01*
G01Y380976D02*
X507978Y381601D01*
G01Y384368D02*
X510478D01*
X508686Y382826D01*
Y384910D01*
G01X510061Y386176D02*
X510311Y386426D01*
X510436Y386718D01*
X510478Y387051D01*
X510395Y387468D01*
X510186Y387760D01*
X509936Y387843D01*
X509686Y387801D01*
X509478Y387635D01*
X509061Y386801D01*
X508770Y386426D01*
X508353Y386176D01*
X507978Y386093D01*
Y387843D01*
G01X486478Y393435D02*
X488978D01*
Y394476D01*
X488853Y394810D01*
X488686Y395018D01*
X488353Y395101D01*
X488020Y395018D01*
X487811Y394768D01*
X487686Y394476D01*
Y393435D01*
G01Y394476D02*
X486478Y395101D01*
G01Y397868D02*
X488978D01*
X487186Y396326D01*
Y398410D01*
G01X486478Y400468D02*
X488978D01*
X488478Y399968D01*
G01X486478D02*
Y400968D01*
G01X483978Y379935D02*
X486478D01*
Y380976D01*
X486353Y381310D01*
X486186Y381518D01*
X485853Y381601D01*
X485520Y381518D01*
X485311Y381268D01*
X485186Y380976D01*
Y379935D01*
G01Y380976D02*
X483978Y381601D01*
G01Y384368D02*
X486478D01*
X484686Y382826D01*
Y384910D01*
G01X486478Y386968D02*
X486395Y386635D01*
X486186Y386385D01*
X485936Y386218D01*
X485603Y386093D01*
X485228Y386051D01*
X484853Y386093D01*
X484520Y386218D01*
X484270Y386385D01*
X484061Y386635D01*
X483978Y386968D01*
X484061Y387301D01*
X484270Y387551D01*
X484520Y387718D01*
X484853Y387843D01*
X485228Y387885D01*
X485603Y387843D01*
X485936Y387718D01*
X486186Y387551D01*
X486395Y387301D01*
X486478Y386968D01*
G01X503978Y379935D02*
X506478D01*
Y380976D01*
X506353Y381310D01*
X506186Y381518D01*
X505853Y381601D01*
X505520Y381518D01*
X505311Y381268D01*
X505186Y380976D01*
Y379935D01*
G01Y380976D02*
X503978Y381601D01*
G01X504478Y382951D02*
X504186Y383201D01*
X504020Y383535D01*
X503978Y383910D01*
X504020Y384243D01*
X504228Y384576D01*
X504478Y384785D01*
X504728Y384826D01*
X505020Y384743D01*
X505228Y384451D01*
X505311Y384160D01*
Y383785D01*
G01Y384160D02*
X505436Y384410D01*
X505645Y384618D01*
X505895Y384701D01*
X506145Y384618D01*
X506353Y384410D01*
X506478Y384035D01*
X506436Y383660D01*
X506270Y383285D01*
G01X505020Y386176D02*
X505311Y386468D01*
X505478Y386718D01*
X505561Y387051D01*
X505478Y387343D01*
X505311Y387551D01*
X505061Y387718D01*
X504770Y387760D01*
X504520Y387718D01*
X504270Y387551D01*
X504061Y387301D01*
X503978Y387010D01*
X504061Y386676D01*
X504311Y386385D01*
X504686Y386218D01*
X505103Y386176D01*
X505645Y386260D01*
X505936Y386385D01*
X506228Y386593D01*
X506436Y386885D01*
X506478Y387176D01*
X506395Y387468D01*
X506186Y387676D01*
G01X479478Y382385D02*
X481978D01*
Y383426D01*
X481853Y383760D01*
X481686Y383968D01*
X481353Y384051D01*
X481020Y383968D01*
X480811Y383718D01*
X480686Y383426D01*
Y382385D01*
G01Y383426D02*
X479478Y384051D01*
G01Y386318D02*
X481978D01*
X481478Y385818D01*
G01X479478D02*
Y386818D01*
G01X481561Y388626D02*
X481811Y388876D01*
X481936Y389168D01*
X481978Y389501D01*
X481895Y389918D01*
X481686Y390210D01*
X481436Y390293D01*
X481186Y390251D01*
X480978Y390085D01*
X480561Y389251D01*
X480270Y388876D01*
X479853Y388626D01*
X479478Y388543D01*
Y390293D01*
G01Y392435D02*
X480020Y392518D01*
X480478Y392643D01*
X480895Y392810D01*
X481353Y393018D01*
X481978Y393351D01*
Y391685D01*
G01X494478Y393435D02*
X496978D01*
Y394476D01*
X496853Y394810D01*
X496686Y395018D01*
X496353Y395101D01*
X496020Y395018D01*
X495811Y394768D01*
X495686Y394476D01*
Y393435D01*
G01Y394476D02*
X494478Y395101D01*
G01X495520Y396576D02*
X495811Y396868D01*
X495978Y397118D01*
X496061Y397451D01*
X495978Y397743D01*
X495811Y397951D01*
X495561Y398118D01*
X495270Y398160D01*
X495020Y398118D01*
X494770Y397951D01*
X494561Y397701D01*
X494478Y397410D01*
X494561Y397076D01*
X494811Y396785D01*
X495186Y396618D01*
X495603Y396576D01*
X496145Y396660D01*
X496436Y396785D01*
X496728Y396993D01*
X496936Y397285D01*
X496978Y397576D01*
X496895Y397868D01*
X496686Y398076D01*
G01X494853Y399551D02*
X494645Y399801D01*
X494520Y400093D01*
X494478Y400468D01*
X494561Y400843D01*
X494728Y401135D01*
X495020Y401343D01*
X495353Y401385D01*
X495686Y401301D01*
X495895Y401093D01*
X496061Y400801D01*
X496103Y400510D01*
X496061Y400218D01*
X495895Y399843D01*
X496978Y399968D01*
Y401093D01*
G01X490478Y393435D02*
X492978D01*
Y394476D01*
X492853Y394810D01*
X492686Y395018D01*
X492353Y395101D01*
X492020Y395018D01*
X491811Y394768D01*
X491686Y394476D01*
Y393435D01*
G01Y394476D02*
X490478Y395101D01*
G01X491520Y396576D02*
X491811Y396868D01*
X491978Y397118D01*
X492061Y397451D01*
X491978Y397743D01*
X491811Y397951D01*
X491561Y398118D01*
X491270Y398160D01*
X491020Y398118D01*
X490770Y397951D01*
X490561Y397701D01*
X490478Y397410D01*
X490561Y397076D01*
X490811Y396785D01*
X491186Y396618D01*
X491603Y396576D01*
X492145Y396660D01*
X492436Y396785D01*
X492728Y396993D01*
X492936Y397285D01*
X492978Y397576D01*
X492895Y397868D01*
X492686Y398076D01*
G01X490478Y400968D02*
X492978D01*
X491186Y399426D01*
Y401510D01*
G01X499000Y393567D02*
X501500D01*
Y394608D01*
X501375Y394942D01*
X501208Y395150D01*
X500875Y395233D01*
X500542Y395150D01*
X500333Y394900D01*
X500208Y394608D01*
Y393567D01*
G01Y394608D02*
X499000Y395233D01*
G01X499375Y396583D02*
X499167Y396833D01*
X499042Y397125D01*
X499000Y397500D01*
X499083Y397875D01*
X499250Y398167D01*
X499542Y398375D01*
X499875Y398417D01*
X500208Y398333D01*
X500417Y398125D01*
X500583Y397833D01*
X500625Y397542D01*
X500583Y397250D01*
X500417Y396875D01*
X501500Y397000D01*
Y398125D01*
G01X499375Y399683D02*
X499167Y399933D01*
X499042Y400225D01*
X499000Y400600D01*
X499083Y400975D01*
X499250Y401267D01*
X499542Y401475D01*
X499875Y401517D01*
X500208Y401433D01*
X500417Y401225D01*
X500583Y400933D01*
X500625Y400642D01*
X500583Y400350D01*
X500417Y399975D01*
X501500Y400100D01*
Y401225D01*
G01X503000Y393567D02*
X505500D01*
Y394608D01*
X505375Y394942D01*
X505208Y395150D01*
X504875Y395233D01*
X504542Y395150D01*
X504333Y394900D01*
X504208Y394608D01*
Y393567D01*
G01Y394608D02*
X503000Y395233D01*
G01X503375Y396583D02*
X503167Y396833D01*
X503042Y397125D01*
X503000Y397500D01*
X503083Y397875D01*
X503250Y398167D01*
X503542Y398375D01*
X503875Y398417D01*
X504208Y398333D01*
X504417Y398125D01*
X504583Y397833D01*
X504625Y397542D01*
X504583Y397250D01*
X504417Y396875D01*
X505500Y397000D01*
Y398125D01*
G01X503000Y401100D02*
X505500D01*
X503708Y399558D01*
Y401642D01*
G01X456478Y375885D02*
X458978D01*
Y376926D01*
X458853Y377260D01*
X458686Y377468D01*
X458353Y377551D01*
X458020Y377468D01*
X457811Y377218D01*
X457686Y376926D01*
Y375885D01*
G01Y376926D02*
X456478Y377551D01*
G01X456978Y378901D02*
X456686Y379151D01*
X456520Y379485D01*
X456478Y379860D01*
X456520Y380193D01*
X456728Y380526D01*
X456978Y380735D01*
X457228Y380776D01*
X457520Y380693D01*
X457728Y380401D01*
X457811Y380110D01*
Y379735D01*
G01Y380110D02*
X457936Y380360D01*
X458145Y380568D01*
X458395Y380651D01*
X458645Y380568D01*
X458853Y380360D01*
X458978Y379985D01*
X458936Y379610D01*
X458770Y379235D01*
G01X458978Y382918D02*
X458895Y382585D01*
X458686Y382335D01*
X458436Y382168D01*
X458103Y382043D01*
X457728Y382001D01*
X457353Y382043D01*
X457020Y382168D01*
X456770Y382335D01*
X456561Y382585D01*
X456478Y382918D01*
X456561Y383251D01*
X456770Y383501D01*
X457020Y383668D01*
X457353Y383793D01*
X457728Y383835D01*
X458103Y383793D01*
X458436Y383668D01*
X458686Y383501D01*
X458895Y383251D01*
X458978Y382918D01*
G01X458561Y385226D02*
X458811Y385476D01*
X458936Y385768D01*
X458978Y386101D01*
X458895Y386518D01*
X458686Y386810D01*
X458436Y386893D01*
X458186Y386851D01*
X457978Y386685D01*
X457561Y385851D01*
X457270Y385476D01*
X456853Y385226D01*
X456478Y385143D01*
Y386893D01*
G01X491978Y379935D02*
X494478D01*
Y380976D01*
X494353Y381310D01*
X494186Y381518D01*
X493853Y381601D01*
X493520Y381518D01*
X493311Y381268D01*
X493186Y380976D01*
Y379935D01*
G01Y380976D02*
X491978Y381601D01*
G01X492478Y382951D02*
X492186Y383201D01*
X492020Y383535D01*
X491978Y383910D01*
X492020Y384243D01*
X492228Y384576D01*
X492478Y384785D01*
X492728Y384826D01*
X493020Y384743D01*
X493228Y384451D01*
X493311Y384160D01*
Y383785D01*
G01Y384160D02*
X493436Y384410D01*
X493645Y384618D01*
X493895Y384701D01*
X494145Y384618D01*
X494353Y384410D01*
X494478Y384035D01*
X494436Y383660D01*
X494270Y383285D01*
G01X494478Y386968D02*
X494395Y386635D01*
X494186Y386385D01*
X493936Y386218D01*
X493603Y386093D01*
X493228Y386051D01*
X492853Y386093D01*
X492520Y386218D01*
X492270Y386385D01*
X492061Y386635D01*
X491978Y386968D01*
X492061Y387301D01*
X492270Y387551D01*
X492520Y387718D01*
X492853Y387843D01*
X493228Y387885D01*
X493603Y387843D01*
X493936Y387718D01*
X494186Y387551D01*
X494395Y387301D01*
X494478Y386968D01*
G01X491978Y390068D02*
X494478D01*
X493978Y389568D01*
G01X491978D02*
Y390568D01*
G01X487978Y379935D02*
X490478D01*
Y380976D01*
X490353Y381310D01*
X490186Y381518D01*
X489853Y381601D01*
X489520Y381518D01*
X489311Y381268D01*
X489186Y380976D01*
Y379935D01*
G01Y380976D02*
X487978Y381601D01*
G01X490061Y383076D02*
X490311Y383326D01*
X490436Y383618D01*
X490478Y383951D01*
X490395Y384368D01*
X490186Y384660D01*
X489936Y384743D01*
X489686Y384701D01*
X489478Y384535D01*
X489061Y383701D01*
X488770Y383326D01*
X488353Y383076D01*
X487978Y382993D01*
Y384743D01*
G01X488478Y386051D02*
X488186Y386301D01*
X488020Y386635D01*
X487978Y387010D01*
X488020Y387343D01*
X488228Y387676D01*
X488478Y387885D01*
X488728Y387926D01*
X489020Y387843D01*
X489228Y387551D01*
X489311Y387260D01*
Y386885D01*
G01Y387260D02*
X489436Y387510D01*
X489645Y387718D01*
X489895Y387801D01*
X490145Y387718D01*
X490353Y387510D01*
X490478Y387135D01*
X490436Y386760D01*
X490270Y386385D01*
G01X489020Y389276D02*
X489311Y389568D01*
X489478Y389818D01*
X489561Y390151D01*
X489478Y390443D01*
X489311Y390651D01*
X489061Y390818D01*
X488770Y390860D01*
X488520Y390818D01*
X488270Y390651D01*
X488061Y390401D01*
X487978Y390110D01*
X488061Y389776D01*
X488311Y389485D01*
X488686Y389318D01*
X489103Y389276D01*
X489645Y389360D01*
X489936Y389485D01*
X490228Y389693D01*
X490436Y389985D01*
X490478Y390276D01*
X490395Y390568D01*
X490186Y390776D01*
G01X495978Y379935D02*
X498478D01*
Y380976D01*
X498353Y381310D01*
X498186Y381518D01*
X497853Y381601D01*
X497520Y381518D01*
X497311Y381268D01*
X497186Y380976D01*
Y379935D01*
G01Y380976D02*
X495978Y381601D01*
G01X498061Y383076D02*
X498311Y383326D01*
X498436Y383618D01*
X498478Y383951D01*
X498395Y384368D01*
X498186Y384660D01*
X497936Y384743D01*
X497686Y384701D01*
X497478Y384535D01*
X497061Y383701D01*
X496770Y383326D01*
X496353Y383076D01*
X495978Y382993D01*
Y384743D01*
G01Y386968D02*
X498478D01*
X497978Y386468D01*
G01X495978D02*
Y387468D01*
G01X498061Y389276D02*
X498311Y389526D01*
X498436Y389818D01*
X498478Y390151D01*
X498395Y390568D01*
X498186Y390860D01*
X497936Y390943D01*
X497686Y390901D01*
X497478Y390735D01*
X497061Y389901D01*
X496770Y389526D01*
X496353Y389276D01*
X495978Y389193D01*
Y390943D01*
G01X494983Y403500D02*
Y406000D01*
X493942D01*
X493608Y405875D01*
X493400Y405708D01*
X493317Y405375D01*
X493400Y405042D01*
X493650Y404833D01*
X493942Y404708D01*
X494983D01*
G01X493942D02*
X493317Y403500D01*
G01X491050D02*
Y406000D01*
X491550Y405500D01*
G01Y403500D02*
X490550D01*
G01X487950D02*
Y406000D01*
X488450Y405500D01*
G01Y403500D02*
X487450D01*
G01X484850Y406000D02*
X485183Y405917D01*
X485433Y405708D01*
X485600Y405458D01*
X485725Y405125D01*
X485767Y404750D01*
X485725Y404375D01*
X485600Y404042D01*
X485433Y403792D01*
X485183Y403583D01*
X484850Y403500D01*
X484517Y403583D01*
X484267Y403792D01*
X484100Y404042D01*
X483975Y404375D01*
X483933Y404750D01*
X483975Y405125D01*
X484100Y405458D01*
X484267Y405708D01*
X484517Y405917D01*
X484850Y406000D01*
G01X475478Y382385D02*
X477978D01*
Y383426D01*
X477853Y383760D01*
X477686Y383968D01*
X477353Y384051D01*
X477020Y383968D01*
X476811Y383718D01*
X476686Y383426D01*
Y382385D01*
G01Y383426D02*
X475478Y384051D01*
G01Y386318D02*
X477978D01*
X477478Y385818D01*
G01X475478D02*
Y386818D01*
G01X475853Y388501D02*
X475645Y388751D01*
X475520Y389043D01*
X475478Y389418D01*
X475561Y389793D01*
X475728Y390085D01*
X476020Y390293D01*
X476353Y390335D01*
X476686Y390251D01*
X476895Y390043D01*
X477061Y389751D01*
X477103Y389460D01*
X477061Y389168D01*
X476895Y388793D01*
X477978Y388918D01*
Y390043D01*
G01X476520Y391726D02*
X476811Y392018D01*
X476978Y392268D01*
X477061Y392601D01*
X476978Y392893D01*
X476811Y393101D01*
X476561Y393268D01*
X476270Y393310D01*
X476020Y393268D01*
X475770Y393101D01*
X475561Y392851D01*
X475478Y392560D01*
X475561Y392226D01*
X475811Y391935D01*
X476186Y391768D01*
X476603Y391726D01*
X477145Y391810D01*
X477436Y391935D01*
X477728Y392143D01*
X477936Y392435D01*
X477978Y392726D01*
X477895Y393018D01*
X477686Y393226D01*
G01X452478Y375885D02*
X454978D01*
Y376926D01*
X454853Y377260D01*
X454686Y377468D01*
X454353Y377551D01*
X454020Y377468D01*
X453811Y377218D01*
X453686Y376926D01*
Y375885D01*
G01Y376926D02*
X452478Y377551D01*
G01X452978Y378901D02*
X452686Y379151D01*
X452520Y379485D01*
X452478Y379860D01*
X452520Y380193D01*
X452728Y380526D01*
X452978Y380735D01*
X453228Y380776D01*
X453520Y380693D01*
X453728Y380401D01*
X453811Y380110D01*
Y379735D01*
G01Y380110D02*
X453936Y380360D01*
X454145Y380568D01*
X454395Y380651D01*
X454645Y380568D01*
X454853Y380360D01*
X454978Y379985D01*
X454936Y379610D01*
X454770Y379235D01*
G01X452478Y382835D02*
X453020Y382918D01*
X453478Y383043D01*
X453895Y383210D01*
X454353Y383418D01*
X454978Y383751D01*
Y382085D01*
G01X452853Y385101D02*
X452645Y385351D01*
X452520Y385643D01*
X452478Y386018D01*
X452561Y386393D01*
X452728Y386685D01*
X453020Y386893D01*
X453353Y386935D01*
X453686Y386851D01*
X453895Y386643D01*
X454061Y386351D01*
X454103Y386060D01*
X454061Y385768D01*
X453895Y385393D01*
X454978Y385518D01*
Y386643D01*
G01X481983Y395000D02*
Y397500D01*
X480942D01*
X480608Y397375D01*
X480400Y397208D01*
X480317Y396875D01*
X480400Y396542D01*
X480650Y396333D01*
X480942Y396208D01*
X481983D01*
G01X480942D02*
X480317Y395000D01*
G01X478967Y395500D02*
X478717Y395208D01*
X478383Y395042D01*
X478008Y395000D01*
X477675Y395042D01*
X477342Y395250D01*
X477133Y395500D01*
X477092Y395750D01*
X477175Y396042D01*
X477467Y396250D01*
X477758Y396333D01*
X478133D01*
G01X477758D02*
X477508Y396458D01*
X477300Y396667D01*
X477217Y396917D01*
X477300Y397167D01*
X477508Y397375D01*
X477883Y397500D01*
X478258Y397458D01*
X478633Y397292D01*
G01X474950Y397500D02*
X475283Y397417D01*
X475533Y397208D01*
X475700Y396958D01*
X475825Y396625D01*
X475867Y396250D01*
X475825Y395875D01*
X475700Y395542D01*
X475533Y395292D01*
X475283Y395083D01*
X474950Y395000D01*
X474617Y395083D01*
X474367Y395292D01*
X474200Y395542D01*
X474075Y395875D01*
X474033Y396250D01*
X474075Y396625D01*
X474200Y396958D01*
X474367Y397208D01*
X474617Y397417D01*
X474950Y397500D01*
G01X471933Y395000D02*
X471850Y395542D01*
X471725Y396000D01*
X471558Y396417D01*
X471350Y396875D01*
X471017Y397500D01*
X472683D01*
G01X488983Y408000D02*
Y410500D01*
X487942D01*
X487608Y410375D01*
X487400Y410208D01*
X487317Y409875D01*
X487400Y409542D01*
X487650Y409333D01*
X487942Y409208D01*
X488983D01*
G01X487942D02*
X487317Y408000D01*
G01X485967Y408500D02*
X485717Y408208D01*
X485383Y408042D01*
X485008Y408000D01*
X484675Y408042D01*
X484342Y408250D01*
X484133Y408500D01*
X484092Y408750D01*
X484175Y409042D01*
X484467Y409250D01*
X484758Y409333D01*
X485133D01*
G01X484758D02*
X484508Y409458D01*
X484300Y409667D01*
X484217Y409917D01*
X484300Y410167D01*
X484508Y410375D01*
X484883Y410500D01*
X485258Y410458D01*
X485633Y410292D01*
G01X482867Y408375D02*
X482617Y408167D01*
X482325Y408042D01*
X481950Y408000D01*
X481575Y408083D01*
X481283Y408250D01*
X481075Y408542D01*
X481033Y408875D01*
X481117Y409208D01*
X481325Y409417D01*
X481617Y409583D01*
X481908Y409625D01*
X482200Y409583D01*
X482575Y409417D01*
X482450Y410500D01*
X481325D01*
G01X478850D02*
X479183Y410417D01*
X479433Y410208D01*
X479600Y409958D01*
X479725Y409625D01*
X479767Y409250D01*
X479725Y408875D01*
X479600Y408542D01*
X479433Y408292D01*
X479183Y408083D01*
X478850Y408000D01*
X478517Y408083D01*
X478267Y408292D01*
X478100Y408542D01*
X477975Y408875D01*
X477933Y409250D01*
X477975Y409625D01*
X478100Y409958D01*
X478267Y410208D01*
X478517Y410417D01*
X478850Y410500D01*
G01X493100Y366350D02*
Y370350D01*
X500500D01*
G01X454500Y362567D02*
X457000D01*
Y363608D01*
X456875Y363942D01*
X456708Y364150D01*
X456375Y364233D01*
X456042Y364150D01*
X455833Y363900D01*
X455708Y363608D01*
Y362567D01*
G01Y363608D02*
X454500Y364233D01*
G01Y366417D02*
X455042Y366500D01*
X455500Y366625D01*
X455917Y366792D01*
X456375Y367000D01*
X457000Y367333D01*
Y365667D01*
G01X454500Y370100D02*
X457000D01*
X455208Y368558D01*
Y370642D01*
G01X458500Y362567D02*
X461000D01*
Y363608D01*
X460875Y363942D01*
X460708Y364150D01*
X460375Y364233D01*
X460042Y364150D01*
X459833Y363900D01*
X459708Y363608D01*
Y362567D01*
G01Y363608D02*
X458500Y364233D01*
G01Y366417D02*
X459042Y366500D01*
X459500Y366625D01*
X459917Y366792D01*
X460375Y367000D01*
X461000Y367333D01*
Y365667D01*
G01X458500Y369600D02*
X458542Y369892D01*
X458667Y370225D01*
X458875Y370433D01*
X459167Y370517D01*
X459458Y370433D01*
X459708Y370183D01*
X459833Y369808D01*
Y369392D01*
X459917Y369142D01*
X460125Y368933D01*
X460417Y368850D01*
X460708Y368975D01*
X460917Y369267D01*
X461000Y369600D01*
X460917Y369933D01*
X460708Y370225D01*
X460417Y370350D01*
X460125Y370267D01*
X459917Y370058D01*
X459833Y369808D01*
Y369392D01*
X459708Y369017D01*
X459458Y368767D01*
X459167Y368683D01*
X458875Y368767D01*
X458667Y368975D01*
X458542Y369308D01*
X458500Y369600D01*
G01X488200Y377667D02*
Y375167D01*
G01X489158Y377667D02*
X487242D01*
G01X485933Y375167D02*
Y377667D01*
X484933D01*
X484600Y377542D01*
X484350Y377250D01*
X484267Y376917D01*
X484350Y376584D01*
X484558Y376334D01*
X484933Y376209D01*
X485933D01*
G01X482000Y375167D02*
Y377667D01*
X482500Y377167D01*
G01Y375167D02*
X481500D01*
G01X479692Y376209D02*
X479400Y376500D01*
X479150Y376667D01*
X478817Y376750D01*
X478525Y376667D01*
X478317Y376500D01*
X478150Y376250D01*
X478108Y375959D01*
X478150Y375709D01*
X478317Y375459D01*
X478567Y375250D01*
X478858Y375167D01*
X479192Y375250D01*
X479483Y375500D01*
X479650Y375875D01*
X479692Y376292D01*
X479608Y376834D01*
X479483Y377125D01*
X479275Y377417D01*
X478983Y377625D01*
X478692Y377667D01*
X478400Y377584D01*
X478192Y377375D01*
G01X475800Y377667D02*
X476133Y377584D01*
X476383Y377375D01*
X476550Y377125D01*
X476675Y376792D01*
X476717Y376417D01*
X476675Y376042D01*
X476550Y375709D01*
X476383Y375459D01*
X476133Y375250D01*
X475800Y375167D01*
X475467Y375250D01*
X475217Y375459D01*
X475050Y375709D01*
X474925Y376042D01*
X474883Y376417D01*
X474925Y376792D01*
X475050Y377125D01*
X475217Y377375D01*
X475467Y377584D01*
X475800Y377667D01*
G01X518796Y377698D02*
Y375198D01*
G01X519754Y377698D02*
X517838D01*
G01X516529Y375198D02*
Y377698D01*
X515529D01*
X515196Y377573D01*
X514946Y377281D01*
X514863Y376948D01*
X514946Y376615D01*
X515154Y376365D01*
X515529Y376240D01*
X516529D01*
G01X512596Y375198D02*
Y377698D01*
X513096Y377198D01*
G01Y375198D02*
X512096D01*
G01X510413Y375573D02*
X510163Y375365D01*
X509871Y375240D01*
X509496Y375198D01*
X509121Y375281D01*
X508829Y375448D01*
X508621Y375740D01*
X508579Y376073D01*
X508663Y376406D01*
X508871Y376615D01*
X509163Y376781D01*
X509454Y376823D01*
X509746Y376781D01*
X510121Y376615D01*
X509996Y377698D01*
X508871D01*
G01X507104Y375490D02*
X506813Y375281D01*
X506479Y375198D01*
X506146Y375281D01*
X505854Y375531D01*
X505646Y375906D01*
X505563Y376281D01*
Y376740D01*
X505646Y377115D01*
X505854Y377448D01*
X506104Y377615D01*
X506396Y377698D01*
X506729Y377615D01*
X506979Y377448D01*
X507146Y377198D01*
X507229Y376865D01*
X507146Y376573D01*
X506938Y376281D01*
X506688Y376115D01*
X506396Y376073D01*
X506063Y376156D01*
X505813Y376365D01*
X505563Y376740D01*
G01X503501Y377848D02*
Y375348D01*
G01X504459Y377848D02*
X502543D01*
G01X501234Y375348D02*
Y377848D01*
X500234D01*
X499901Y377723D01*
X499651Y377431D01*
X499568Y377098D01*
X499651Y376765D01*
X499859Y376515D01*
X500234Y376390D01*
X501234D01*
G01X497301Y375348D02*
Y377848D01*
X497801Y377348D01*
G01Y375348D02*
X496801D01*
G01X495118Y375723D02*
X494868Y375515D01*
X494576Y375390D01*
X494201Y375348D01*
X493826Y375431D01*
X493534Y375598D01*
X493326Y375890D01*
X493284Y376223D01*
X493368Y376556D01*
X493576Y376765D01*
X493868Y376931D01*
X494159Y376973D01*
X494451Y376931D01*
X494826Y376765D01*
X494701Y377848D01*
X493576D01*
G01X491101Y375348D02*
X490809Y375390D01*
X490476Y375515D01*
X490268Y375723D01*
X490184Y376015D01*
X490268Y376306D01*
X490518Y376556D01*
X490893Y376681D01*
X491309D01*
X491559Y376765D01*
X491768Y376973D01*
X491851Y377265D01*
X491726Y377556D01*
X491434Y377765D01*
X491101Y377848D01*
X490768Y377765D01*
X490476Y377556D01*
X490351Y377265D01*
X490434Y376973D01*
X490643Y376765D01*
X490893Y376681D01*
X491309D01*
X491684Y376556D01*
X491934Y376306D01*
X492018Y376015D01*
X491934Y375723D01*
X491726Y375515D01*
X491393Y375390D01*
X491101Y375348D01*
G01X514433Y493500D02*
Y496000D01*
X513392D01*
X513058Y495875D01*
X512850Y495708D01*
X512767Y495375D01*
X512850Y495042D01*
X513100Y494833D01*
X513392Y494708D01*
X514433D01*
G01X513392D02*
X512767Y493500D01*
G01X510500D02*
Y496000D01*
X511000Y495500D01*
G01Y493500D02*
X510000D01*
G01X507400Y496000D02*
X507733Y495917D01*
X507983Y495708D01*
X508150Y495458D01*
X508275Y495125D01*
X508317Y494750D01*
X508275Y494375D01*
X508150Y494042D01*
X507983Y493792D01*
X507733Y493583D01*
X507400Y493500D01*
X507067Y493583D01*
X506817Y493792D01*
X506650Y494042D01*
X506525Y494375D01*
X506483Y494750D01*
X506525Y495125D01*
X506650Y495458D01*
X506817Y495708D01*
X507067Y495917D01*
X507400Y496000D01*
G01X521792Y167317D02*
X521917Y167067D01*
X522000Y166775D01*
Y166442D01*
X521875Y166067D01*
X521667Y165775D01*
X521417Y165567D01*
X521000Y165400D01*
X520625Y165358D01*
X520250Y165442D01*
X520000Y165567D01*
X519750Y165817D01*
X519583Y166108D01*
X519500Y166400D01*
Y166692D01*
X519583Y166983D01*
X519708Y167233D01*
X519875Y167442D01*
G01X521583Y168708D02*
X521833Y168958D01*
X521958Y169250D01*
X522000Y169583D01*
X521917Y170000D01*
X521708Y170292D01*
X521458Y170375D01*
X521208Y170333D01*
X521000Y170167D01*
X520583Y169333D01*
X520292Y168958D01*
X519875Y168708D01*
X519500Y168625D01*
Y170375D01*
G01X519792Y171892D02*
X519583Y172183D01*
X519500Y172517D01*
X519583Y172850D01*
X519833Y173142D01*
X520208Y173350D01*
X520583Y173433D01*
X521042D01*
X521417Y173350D01*
X521750Y173142D01*
X521917Y172892D01*
X522000Y172600D01*
X521917Y172267D01*
X521750Y172017D01*
X521500Y171850D01*
X521167Y171767D01*
X520875Y171850D01*
X520583Y172058D01*
X520417Y172308D01*
X520375Y172600D01*
X520458Y172933D01*
X520667Y173183D01*
X521042Y173433D01*
G01X522792Y179317D02*
X522917Y179067D01*
X523000Y178775D01*
Y178442D01*
X522875Y178067D01*
X522667Y177775D01*
X522417Y177567D01*
X522000Y177400D01*
X521625Y177358D01*
X521250Y177442D01*
X521000Y177567D01*
X520750Y177817D01*
X520583Y178108D01*
X520500Y178400D01*
Y178692D01*
X520583Y178983D01*
X520708Y179233D01*
X520875Y179442D01*
G01X522583Y180708D02*
X522833Y180958D01*
X522958Y181250D01*
X523000Y181583D01*
X522917Y182000D01*
X522708Y182292D01*
X522458Y182375D01*
X522208Y182333D01*
X522000Y182167D01*
X521583Y181333D01*
X521292Y180958D01*
X520875Y180708D01*
X520500Y180625D01*
Y182375D01*
G01Y184600D02*
X520542Y184892D01*
X520667Y185225D01*
X520875Y185433D01*
X521167Y185517D01*
X521458Y185433D01*
X521708Y185183D01*
X521833Y184808D01*
Y184392D01*
X521917Y184142D01*
X522125Y183933D01*
X522417Y183850D01*
X522708Y183975D01*
X522917Y184267D01*
X523000Y184600D01*
X522917Y184933D01*
X522708Y185225D01*
X522417Y185350D01*
X522125Y185267D01*
X521917Y185058D01*
X521833Y184808D01*
Y184392D01*
X521708Y184017D01*
X521458Y183767D01*
X521167Y183683D01*
X520875Y183767D01*
X520667Y183975D01*
X520542Y184308D01*
X520500Y184600D01*
G01X531209Y180088D02*
X531334Y179838D01*
X531417Y179546D01*
Y179213D01*
X531292Y178838D01*
X531084Y178546D01*
X530834Y178338D01*
X530417Y178171D01*
X530042Y178129D01*
X529667Y178213D01*
X529417Y178338D01*
X529167Y178588D01*
X529000Y178879D01*
X528917Y179171D01*
Y179463D01*
X529000Y179754D01*
X529125Y180004D01*
X529292Y180213D01*
G01X531000Y181479D02*
X531250Y181729D01*
X531375Y182021D01*
X531417Y182354D01*
X531334Y182771D01*
X531125Y183063D01*
X530875Y183146D01*
X530625Y183104D01*
X530417Y182938D01*
X530000Y182104D01*
X529709Y181729D01*
X529292Y181479D01*
X528917Y181396D01*
Y183146D01*
G01Y185288D02*
X529459Y185371D01*
X529917Y185496D01*
X530334Y185663D01*
X530792Y185871D01*
X531417Y186204D01*
Y184538D01*
G01X522292Y318767D02*
X522417Y318517D01*
X522500Y318225D01*
Y317892D01*
X522375Y317517D01*
X522167Y317225D01*
X521917Y317017D01*
X521500Y316850D01*
X521125Y316808D01*
X520750Y316892D01*
X520500Y317017D01*
X520250Y317267D01*
X520083Y317558D01*
X520000Y317850D01*
Y318142D01*
X520083Y318433D01*
X520208Y318683D01*
X520375Y318892D01*
G01X520000Y320950D02*
X522500D01*
X522000Y320450D01*
G01X520000D02*
Y321450D01*
G01Y324550D02*
X522500D01*
X520708Y323008D01*
Y325092D01*
G01X521042Y326358D02*
X521333Y326650D01*
X521500Y326900D01*
X521583Y327233D01*
X521500Y327525D01*
X521333Y327733D01*
X521083Y327900D01*
X520792Y327942D01*
X520542Y327900D01*
X520292Y327733D01*
X520083Y327483D01*
X520000Y327192D01*
X520083Y326858D01*
X520333Y326567D01*
X520708Y326400D01*
X521125Y326358D01*
X521667Y326442D01*
X521958Y326567D01*
X522250Y326775D01*
X522458Y327067D01*
X522500Y327358D01*
X522417Y327650D01*
X522208Y327858D01*
G01X517792Y313267D02*
X517917Y313017D01*
X518000Y312725D01*
Y312392D01*
X517875Y312017D01*
X517667Y311725D01*
X517417Y311517D01*
X517000Y311350D01*
X516625Y311308D01*
X516250Y311392D01*
X516000Y311517D01*
X515750Y311767D01*
X515583Y312058D01*
X515500Y312350D01*
Y312642D01*
X515583Y312933D01*
X515708Y313183D01*
X515875Y313392D01*
G01X515500Y315450D02*
X518000D01*
X517500Y314950D01*
G01X515500D02*
Y315950D01*
G01X516000Y317633D02*
X515708Y317883D01*
X515542Y318217D01*
X515500Y318592D01*
X515542Y318925D01*
X515750Y319258D01*
X516000Y319467D01*
X516250Y319508D01*
X516542Y319425D01*
X516750Y319133D01*
X516833Y318842D01*
Y318467D01*
G01Y318842D02*
X516958Y319092D01*
X517167Y319300D01*
X517417Y319383D01*
X517667Y319300D01*
X517875Y319092D01*
X518000Y318717D01*
X517958Y318342D01*
X517792Y317967D01*
G01X515500Y321567D02*
X516042Y321650D01*
X516500Y321775D01*
X516917Y321942D01*
X517375Y322150D01*
X518000Y322483D01*
Y320817D01*
G01X536808Y321387D02*
X539308D01*
Y322428D01*
X539183Y322762D01*
X539016Y322970D01*
X538683Y323053D01*
X538350Y322970D01*
X538141Y322720D01*
X538016Y322428D01*
Y321387D01*
G01Y322428D02*
X536808Y323053D01*
G01Y325820D02*
X539308D01*
X537516Y324278D01*
Y326362D01*
G01X537100Y327712D02*
X536891Y328003D01*
X536808Y328337D01*
X536891Y328670D01*
X537141Y328962D01*
X537516Y329170D01*
X537891Y329253D01*
X538350D01*
X538725Y329170D01*
X539058Y328962D01*
X539225Y328712D01*
X539308Y328420D01*
X539225Y328087D01*
X539058Y327837D01*
X538808Y327670D01*
X538475Y327587D01*
X538183Y327670D01*
X537891Y327878D01*
X537725Y328128D01*
X537683Y328420D01*
X537766Y328753D01*
X537975Y329003D01*
X538350Y329253D01*
G01X545908Y337132D02*
X549908D01*
Y329732D01*
G01X532808Y321387D02*
X535308D01*
Y322428D01*
X535183Y322762D01*
X535016Y322970D01*
X534683Y323053D01*
X534350Y322970D01*
X534141Y322720D01*
X534016Y322428D01*
Y321387D01*
G01Y322428D02*
X532808Y323053D01*
G01X533183Y324403D02*
X532975Y324653D01*
X532850Y324945D01*
X532808Y325320D01*
X532891Y325695D01*
X533058Y325987D01*
X533350Y326195D01*
X533683Y326237D01*
X534016Y326153D01*
X534225Y325945D01*
X534391Y325653D01*
X534433Y325362D01*
X534391Y325070D01*
X534225Y324695D01*
X535308Y324820D01*
Y325945D01*
G01X532808Y328420D02*
X535308D01*
X534808Y327920D01*
G01X532808D02*
Y328920D01*
G01X539747Y337165D02*
X543747D01*
Y329765D01*
G01X524808Y321387D02*
X527308D01*
Y322428D01*
X527183Y322762D01*
X527016Y322970D01*
X526683Y323053D01*
X526350Y322970D01*
X526141Y322720D01*
X526016Y322428D01*
Y321387D01*
G01Y322428D02*
X524808Y323053D01*
G01X525850Y324528D02*
X526141Y324820D01*
X526308Y325070D01*
X526391Y325403D01*
X526308Y325695D01*
X526141Y325903D01*
X525891Y326070D01*
X525600Y326112D01*
X525350Y326070D01*
X525100Y325903D01*
X524891Y325653D01*
X524808Y325362D01*
X524891Y325028D01*
X525141Y324737D01*
X525516Y324570D01*
X525933Y324528D01*
X526475Y324612D01*
X526766Y324737D01*
X527058Y324945D01*
X527266Y325237D01*
X527308Y325528D01*
X527225Y325820D01*
X527016Y326028D01*
G01X525308Y327503D02*
X525016Y327753D01*
X524850Y328087D01*
X524808Y328462D01*
X524850Y328795D01*
X525058Y329128D01*
X525308Y329337D01*
X525558Y329378D01*
X525850Y329295D01*
X526058Y329003D01*
X526141Y328712D01*
Y328337D01*
G01Y328712D02*
X526266Y328962D01*
X526475Y329170D01*
X526725Y329253D01*
X526975Y329170D01*
X527183Y328962D01*
X527308Y328587D01*
X527266Y328212D01*
X527100Y327837D01*
G01X527947Y337200D02*
X531947D01*
Y329800D01*
G01X515517Y339846D02*
X511517D01*
Y347246D01*
G01X523522Y339846D02*
X519522D01*
Y347246D01*
G01X519517Y339846D02*
X515517D01*
Y347246D01*
G01X523522D02*
X527522D01*
Y339846D01*
G01X527622Y347246D02*
X531622D01*
Y339846D01*
G01X553000Y359567D02*
X555500D01*
Y360608D01*
X555375Y360942D01*
X555208Y361150D01*
X554875Y361233D01*
X554542Y361150D01*
X554333Y360900D01*
X554208Y360608D01*
Y359567D01*
G01Y360608D02*
X553000Y361233D01*
G01X554042Y362708D02*
X554333Y363000D01*
X554500Y363250D01*
X554583Y363583D01*
X554500Y363875D01*
X554333Y364083D01*
X554083Y364250D01*
X553792Y364292D01*
X553542Y364250D01*
X553292Y364083D01*
X553083Y363833D01*
X553000Y363542D01*
X553083Y363208D01*
X553333Y362917D01*
X553708Y362750D01*
X554125Y362708D01*
X554667Y362792D01*
X554958Y362917D01*
X555250Y363125D01*
X555458Y363417D01*
X555500Y363708D01*
X555417Y364000D01*
X555208Y364208D01*
G01X553000Y366517D02*
X553542Y366600D01*
X554000Y366725D01*
X554417Y366892D01*
X554875Y367100D01*
X555500Y367433D01*
Y365767D01*
G01X556000Y353700D02*
X560000D01*
Y346300D01*
G01X549000Y359567D02*
X551500D01*
Y360608D01*
X551375Y360942D01*
X551208Y361150D01*
X550875Y361233D01*
X550542Y361150D01*
X550333Y360900D01*
X550208Y360608D01*
Y359567D01*
G01Y360608D02*
X549000Y361233D01*
G01X550042Y362708D02*
X550333Y363000D01*
X550500Y363250D01*
X550583Y363583D01*
X550500Y363875D01*
X550333Y364083D01*
X550083Y364250D01*
X549792Y364292D01*
X549542Y364250D01*
X549292Y364083D01*
X549083Y363833D01*
X549000Y363542D01*
X549083Y363208D01*
X549333Y362917D01*
X549708Y362750D01*
X550125Y362708D01*
X550667Y362792D01*
X550958Y362917D01*
X551250Y363125D01*
X551458Y363417D01*
X551500Y363708D01*
X551417Y364000D01*
X551208Y364208D01*
G01X550042Y365808D02*
X550333Y366100D01*
X550500Y366350D01*
X550583Y366683D01*
X550500Y366975D01*
X550333Y367183D01*
X550083Y367350D01*
X549792Y367392D01*
X549542Y367350D01*
X549292Y367183D01*
X549083Y366933D01*
X549000Y366642D01*
X549083Y366308D01*
X549333Y366017D01*
X549708Y365850D01*
X550125Y365808D01*
X550667Y365892D01*
X550958Y366017D01*
X551250Y366225D01*
X551458Y366517D01*
X551500Y366808D01*
X551417Y367100D01*
X551208Y367308D01*
G01X552000Y353700D02*
X556000D01*
Y346300D01*
G01X528808Y321387D02*
X531308D01*
Y322428D01*
X531183Y322762D01*
X531016Y322970D01*
X530683Y323053D01*
X530350Y322970D01*
X530141Y322720D01*
X530016Y322428D01*
Y321387D01*
G01Y322428D02*
X528808Y323053D01*
G01X529183Y324403D02*
X528975Y324653D01*
X528850Y324945D01*
X528808Y325320D01*
X528891Y325695D01*
X529058Y325987D01*
X529350Y326195D01*
X529683Y326237D01*
X530016Y326153D01*
X530225Y325945D01*
X530391Y325653D01*
X530433Y325362D01*
X530391Y325070D01*
X530225Y324695D01*
X531308Y324820D01*
Y325945D01*
G01X529100Y327712D02*
X528891Y328003D01*
X528808Y328337D01*
X528891Y328670D01*
X529141Y328962D01*
X529516Y329170D01*
X529891Y329253D01*
X530350D01*
X530725Y329170D01*
X531058Y328962D01*
X531225Y328712D01*
X531308Y328420D01*
X531225Y328087D01*
X531058Y327837D01*
X530808Y327670D01*
X530475Y327587D01*
X530183Y327670D01*
X529891Y327878D01*
X529725Y328128D01*
X529683Y328420D01*
X529766Y328753D01*
X529975Y329003D01*
X530350Y329253D01*
G01X531947Y337200D02*
X535947D01*
Y329800D01*
G01X530500Y354067D02*
X533000D01*
Y355108D01*
X532875Y355442D01*
X532708Y355650D01*
X532375Y355733D01*
X532042Y355650D01*
X531833Y355400D01*
X531708Y355108D01*
Y354067D01*
G01Y355108D02*
X530500Y355733D01*
G01X530875Y357083D02*
X530667Y357333D01*
X530542Y357625D01*
X530500Y358000D01*
X530583Y358375D01*
X530750Y358667D01*
X531042Y358875D01*
X531375Y358917D01*
X531708Y358833D01*
X531917Y358625D01*
X532083Y358333D01*
X532125Y358042D01*
X532083Y357750D01*
X531917Y357375D01*
X533000Y357500D01*
Y358625D01*
G01X530500Y361017D02*
X531042Y361100D01*
X531500Y361225D01*
X531917Y361392D01*
X532375Y361600D01*
X533000Y361933D01*
Y360267D01*
G01X538200Y356800D02*
X542200D01*
Y349400D01*
G01X526993Y354086D02*
X529493D01*
Y355127D01*
X529368Y355461D01*
X529201Y355669D01*
X528868Y355752D01*
X528535Y355669D01*
X528326Y355419D01*
X528201Y355127D01*
Y354086D01*
G01Y355127D02*
X526993Y355752D01*
G01X527368Y357102D02*
X527160Y357352D01*
X527035Y357644D01*
X526993Y358019D01*
X527076Y358394D01*
X527243Y358686D01*
X527535Y358894D01*
X527868Y358936D01*
X528201Y358852D01*
X528410Y358644D01*
X528576Y358352D01*
X528618Y358061D01*
X528576Y357769D01*
X528410Y357394D01*
X529493Y357519D01*
Y358644D01*
G01X528035Y360327D02*
X528326Y360619D01*
X528493Y360869D01*
X528576Y361202D01*
X528493Y361494D01*
X528326Y361702D01*
X528076Y361869D01*
X527785Y361911D01*
X527535Y361869D01*
X527285Y361702D01*
X527076Y361452D01*
X526993Y361161D01*
X527076Y360827D01*
X527326Y360536D01*
X527701Y360369D01*
X528118Y360327D01*
X528660Y360411D01*
X528951Y360536D01*
X529243Y360744D01*
X529451Y361036D01*
X529493Y361327D01*
X529410Y361619D01*
X529201Y361827D01*
G01X534200Y356800D02*
X538200D01*
Y349400D01*
G01X520500Y350300D02*
X516500D01*
Y357700D01*
G01X524500Y350300D02*
X520500D01*
Y357700D01*
G01X541000Y359567D02*
X543500D01*
Y360608D01*
X543375Y360942D01*
X543208Y361150D01*
X542875Y361233D01*
X542542Y361150D01*
X542333Y360900D01*
X542208Y360608D01*
Y359567D01*
G01Y360608D02*
X541000Y361233D01*
G01X541375Y362583D02*
X541167Y362833D01*
X541042Y363125D01*
X541000Y363500D01*
X541083Y363875D01*
X541250Y364167D01*
X541542Y364375D01*
X541875Y364417D01*
X542208Y364333D01*
X542417Y364125D01*
X542583Y363833D01*
X542625Y363542D01*
X542583Y363250D01*
X542417Y362875D01*
X543500Y363000D01*
Y364125D01*
G01X541500Y365683D02*
X541208Y365933D01*
X541042Y366267D01*
X541000Y366642D01*
X541042Y366975D01*
X541250Y367308D01*
X541500Y367517D01*
X541750Y367558D01*
X542042Y367475D01*
X542250Y367183D01*
X542333Y366892D01*
Y366517D01*
G01Y366892D02*
X542458Y367142D01*
X542667Y367350D01*
X542917Y367433D01*
X543167Y367350D01*
X543375Y367142D01*
X543500Y366767D01*
X543458Y366392D01*
X543292Y366017D01*
G01X543200Y356800D02*
X547200D01*
Y349400D01*
G01X545000Y359567D02*
X547500D01*
Y360608D01*
X547375Y360942D01*
X547208Y361150D01*
X546875Y361233D01*
X546542Y361150D01*
X546333Y360900D01*
X546208Y360608D01*
Y359567D01*
G01Y360608D02*
X545000Y361233D01*
G01X545375Y362583D02*
X545167Y362833D01*
X545042Y363125D01*
X545000Y363500D01*
X545083Y363875D01*
X545250Y364167D01*
X545542Y364375D01*
X545875Y364417D01*
X546208Y364333D01*
X546417Y364125D01*
X546583Y363833D01*
X546625Y363542D01*
X546583Y363250D01*
X546417Y362875D01*
X547500Y363000D01*
Y364125D01*
G01X547083Y365808D02*
X547333Y366058D01*
X547458Y366350D01*
X547500Y366683D01*
X547417Y367100D01*
X547208Y367392D01*
X546958Y367475D01*
X546708Y367433D01*
X546500Y367267D01*
X546083Y366433D01*
X545792Y366058D01*
X545375Y365808D01*
X545000Y365725D01*
Y367475D01*
G01X547200Y356800D02*
X551200D01*
Y349400D01*
G01X558748Y329356D02*
X556248D01*
G01X558748Y328398D02*
Y330314D01*
G01X556248Y331623D02*
X558748D01*
Y332623D01*
X558623Y332956D01*
X558331Y333206D01*
X557998Y333289D01*
X557665Y333206D01*
X557415Y332998D01*
X557290Y332623D01*
Y331623D01*
G01X558331Y334764D02*
X558581Y335014D01*
X558706Y335306D01*
X558748Y335639D01*
X558665Y336056D01*
X558456Y336348D01*
X558206Y336431D01*
X557956Y336389D01*
X557748Y336223D01*
X557331Y335389D01*
X557040Y335014D01*
X556623Y334764D01*
X556248Y334681D01*
Y336431D01*
G01X558748Y338656D02*
X558665Y338323D01*
X558456Y338073D01*
X558206Y337906D01*
X557873Y337781D01*
X557498Y337739D01*
X557123Y337781D01*
X556790Y337906D01*
X556540Y338073D01*
X556331Y338323D01*
X556248Y338656D01*
X556331Y338989D01*
X556540Y339239D01*
X556790Y339406D01*
X557123Y339531D01*
X557498Y339573D01*
X557873Y339531D01*
X558206Y339406D01*
X558456Y339239D01*
X558665Y338989D01*
X558748Y338656D01*
G01X548300Y346450D02*
Y343950D01*
G01X549258Y346450D02*
X547342D01*
G01X546033Y343950D02*
Y346450D01*
X545033D01*
X544700Y346325D01*
X544450Y346033D01*
X544367Y345700D01*
X544450Y345367D01*
X544658Y345117D01*
X545033Y344992D01*
X546033D01*
G01X542100Y343950D02*
Y346450D01*
X542600Y345950D01*
G01Y343950D02*
X541600D01*
G01X539792Y344992D02*
X539500Y345283D01*
X539250Y345450D01*
X538917Y345533D01*
X538625Y345450D01*
X538417Y345283D01*
X538250Y345033D01*
X538208Y344742D01*
X538250Y344492D01*
X538417Y344242D01*
X538667Y344033D01*
X538958Y343950D01*
X539292Y344033D01*
X539583Y344283D01*
X539750Y344658D01*
X539792Y345075D01*
X539708Y345617D01*
X539583Y345908D01*
X539375Y346200D01*
X539083Y346408D01*
X538792Y346450D01*
X538500Y346367D01*
X538292Y346158D01*
G01X536608Y344242D02*
X536317Y344033D01*
X535983Y343950D01*
X535650Y344033D01*
X535358Y344283D01*
X535150Y344658D01*
X535067Y345033D01*
Y345492D01*
X535150Y345867D01*
X535358Y346200D01*
X535608Y346367D01*
X535900Y346450D01*
X536233Y346367D01*
X536483Y346200D01*
X536650Y345950D01*
X536733Y345617D01*
X536650Y345325D01*
X536442Y345033D01*
X536192Y344867D01*
X535900Y344825D01*
X535567Y344908D01*
X535317Y345117D01*
X535067Y345492D01*
G01X521650Y338667D02*
Y336167D01*
G01X522608Y338667D02*
X520692D01*
G01X519383Y336167D02*
Y338667D01*
X518383D01*
X518050Y338542D01*
X517800Y338250D01*
X517717Y337917D01*
X517800Y337584D01*
X518008Y337334D01*
X518383Y337209D01*
X519383D01*
G01X515450Y336167D02*
Y338667D01*
X515950Y338167D01*
G01Y336167D02*
X514950D01*
G01X513142Y337209D02*
X512850Y337500D01*
X512600Y337667D01*
X512267Y337750D01*
X511975Y337667D01*
X511767Y337500D01*
X511600Y337250D01*
X511558Y336959D01*
X511600Y336709D01*
X511767Y336459D01*
X512017Y336250D01*
X512308Y336167D01*
X512642Y336250D01*
X512933Y336500D01*
X513100Y336875D01*
X513142Y337292D01*
X513058Y337834D01*
X512933Y338125D01*
X512725Y338417D01*
X512433Y338625D01*
X512142Y338667D01*
X511850Y338584D01*
X511642Y338375D01*
G01X511978Y379935D02*
X514478D01*
Y380976D01*
X514353Y381310D01*
X514186Y381518D01*
X513853Y381601D01*
X513520Y381518D01*
X513311Y381268D01*
X513186Y380976D01*
Y379935D01*
G01Y380976D02*
X511978Y381601D01*
G01Y383785D02*
X512520Y383868D01*
X512978Y383993D01*
X513395Y384160D01*
X513853Y384368D01*
X514478Y384701D01*
Y383035D01*
G01X511978Y386968D02*
X514478D01*
X513978Y386468D01*
G01X511978D02*
Y387468D01*
G01X516078Y379935D02*
X518578D01*
Y380976D01*
X518453Y381310D01*
X518286Y381518D01*
X517953Y381601D01*
X517620Y381518D01*
X517411Y381268D01*
X517286Y380976D01*
Y379935D01*
G01Y380976D02*
X516078Y381601D01*
G01Y383785D02*
X516620Y383868D01*
X517078Y383993D01*
X517495Y384160D01*
X517953Y384368D01*
X518578Y384701D01*
Y383035D01*
G01Y386968D02*
X518495Y386635D01*
X518286Y386385D01*
X518036Y386218D01*
X517703Y386093D01*
X517328Y386051D01*
X516953Y386093D01*
X516620Y386218D01*
X516370Y386385D01*
X516161Y386635D01*
X516078Y386968D01*
X516161Y387301D01*
X516370Y387551D01*
X516620Y387718D01*
X516953Y387843D01*
X517328Y387885D01*
X517703Y387843D01*
X518036Y387718D01*
X518286Y387551D01*
X518495Y387301D01*
X518578Y386968D01*
G01X542553Y484220D02*
Y486720D01*
X541512D01*
X541178Y486595D01*
X540970Y486428D01*
X540887Y486095D01*
X540970Y485762D01*
X541220Y485553D01*
X541512Y485428D01*
X542553D01*
G01X541512D02*
X540887Y484220D01*
G01X538620D02*
Y486720D01*
X539120Y486220D01*
G01Y484220D02*
X538120D01*
G01X540295Y478090D02*
Y482090D01*
X547695D01*
G01X568633Y474488D02*
Y478488D01*
X576033D01*
G01X529650Y478000D02*
Y474000D01*
X522250D01*
G01X579500Y485400D02*
Y481400D01*
X572100D01*
G01X522150Y478000D02*
Y474000D01*
X514750D01*
G01X579500Y489900D02*
Y485900D01*
X572100D01*
G01X575483Y453167D02*
Y455667D01*
X574442D01*
X574108Y455542D01*
X573900Y455375D01*
X573817Y455042D01*
X573900Y454709D01*
X574150Y454500D01*
X574442Y454375D01*
X575483D01*
G01X574442D02*
X573817Y453167D01*
G01X572467Y453542D02*
X572217Y453334D01*
X571925Y453209D01*
X571550Y453167D01*
X571175Y453250D01*
X570883Y453417D01*
X570675Y453709D01*
X570633Y454042D01*
X570717Y454375D01*
X570925Y454584D01*
X571217Y454750D01*
X571508Y454792D01*
X571800Y454750D01*
X572175Y454584D01*
X572050Y455667D01*
X570925D01*
G01X569367Y453667D02*
X569117Y453375D01*
X568783Y453209D01*
X568408Y453167D01*
X568075Y453209D01*
X567742Y453417D01*
X567533Y453667D01*
X567492Y453917D01*
X567575Y454209D01*
X567867Y454417D01*
X568158Y454500D01*
X568533D01*
G01X568158D02*
X567908Y454625D01*
X567700Y454834D01*
X567617Y455084D01*
X567700Y455334D01*
X567908Y455542D01*
X568283Y455667D01*
X568658Y455625D01*
X569033Y455459D01*
G01X566058Y453459D02*
X565767Y453250D01*
X565433Y453167D01*
X565100Y453250D01*
X564808Y453500D01*
X564600Y453875D01*
X564517Y454250D01*
Y454709D01*
X564600Y455084D01*
X564808Y455417D01*
X565058Y455584D01*
X565350Y455667D01*
X565683Y455584D01*
X565933Y455417D01*
X566100Y455167D01*
X566183Y454834D01*
X566100Y454542D01*
X565892Y454250D01*
X565642Y454084D01*
X565350Y454042D01*
X565017Y454125D01*
X564767Y454334D01*
X564517Y454709D01*
G01X564539Y459261D02*
Y463261D01*
X571939D01*
G01X551400Y483990D02*
X547400D01*
Y491390D01*
G01X560733Y455459D02*
X560983Y455584D01*
X561275Y455667D01*
X561608D01*
X561983Y455542D01*
X562275Y455334D01*
X562483Y455084D01*
X562650Y454667D01*
X562692Y454292D01*
X562608Y453917D01*
X562483Y453667D01*
X562233Y453417D01*
X561942Y453250D01*
X561650Y453167D01*
X561358D01*
X561067Y453250D01*
X560817Y453375D01*
X560608Y453542D01*
G01X558633Y453167D02*
X558550Y453709D01*
X558425Y454167D01*
X558258Y454584D01*
X558050Y455042D01*
X557717Y455667D01*
X559383D01*
G01X556242Y455250D02*
X555992Y455500D01*
X555700Y455625D01*
X555367Y455667D01*
X554950Y455584D01*
X554658Y455375D01*
X554575Y455125D01*
X554617Y454875D01*
X554783Y454667D01*
X555617Y454250D01*
X555992Y453959D01*
X556242Y453542D01*
X556325Y453167D01*
X554575D01*
G01X552350D02*
Y455667D01*
X552850Y455167D01*
G01Y453167D02*
X551850D01*
G01X522733Y443792D02*
X522983Y443917D01*
X523275Y444000D01*
X523608D01*
X523983Y443875D01*
X524275Y443667D01*
X524483Y443417D01*
X524650Y443000D01*
X524692Y442625D01*
X524608Y442250D01*
X524483Y442000D01*
X524233Y441750D01*
X523942Y441583D01*
X523650Y441500D01*
X523358D01*
X523067Y441583D01*
X522817Y441708D01*
X522608Y441875D01*
G01X521342Y442542D02*
X521050Y442833D01*
X520800Y443000D01*
X520467Y443083D01*
X520175Y443000D01*
X519967Y442833D01*
X519800Y442583D01*
X519758Y442292D01*
X519800Y442042D01*
X519967Y441792D01*
X520217Y441583D01*
X520508Y441500D01*
X520842Y441583D01*
X521133Y441833D01*
X521300Y442208D01*
X521342Y442625D01*
X521258Y443167D01*
X521133Y443458D01*
X520925Y443750D01*
X520633Y443958D01*
X520342Y444000D01*
X520050Y443917D01*
X519842Y443708D01*
G01X517450Y441500D02*
X517158Y441542D01*
X516825Y441667D01*
X516617Y441875D01*
X516533Y442167D01*
X516617Y442458D01*
X516867Y442708D01*
X517242Y442833D01*
X517658D01*
X517908Y442917D01*
X518117Y443125D01*
X518200Y443417D01*
X518075Y443708D01*
X517783Y443917D01*
X517450Y444000D01*
X517117Y443917D01*
X516825Y443708D01*
X516700Y443417D01*
X516783Y443125D01*
X516992Y442917D01*
X517242Y442833D01*
X517658D01*
X518033Y442708D01*
X518283Y442458D01*
X518367Y442167D01*
X518283Y441875D01*
X518075Y441667D01*
X517742Y441542D01*
X517450Y441500D01*
G01X515058Y441792D02*
X514767Y441583D01*
X514433Y441500D01*
X514100Y441583D01*
X513808Y441833D01*
X513600Y442208D01*
X513517Y442583D01*
Y443042D01*
X513600Y443417D01*
X513808Y443750D01*
X514058Y443917D01*
X514350Y444000D01*
X514683Y443917D01*
X514933Y443750D01*
X515100Y443500D01*
X515183Y443167D01*
X515100Y442875D01*
X514892Y442583D01*
X514642Y442417D01*
X514350Y442375D01*
X514017Y442458D01*
X513767Y442667D01*
X513517Y443042D01*
G01X578100Y469167D02*
X578433Y469209D01*
X578725Y469375D01*
X578975Y469625D01*
X579142Y469917D01*
X579225Y470250D01*
Y470584D01*
X579142Y470917D01*
X578975Y471209D01*
X578725Y471459D01*
X578433Y471625D01*
X578100Y471667D01*
X577767Y471625D01*
X577475Y471459D01*
X577225Y471209D01*
X577058Y470917D01*
X576975Y470584D01*
Y470250D01*
X577058Y469917D01*
X577225Y469625D01*
X577475Y469375D01*
X577767Y469209D01*
X578100Y469167D01*
G01X577767Y469834D02*
X577267Y469167D01*
G01X575000D02*
Y471667D01*
X575500Y471167D01*
G01Y469167D02*
X574500D01*
G01X572817Y469667D02*
X572567Y469375D01*
X572233Y469209D01*
X571858Y469167D01*
X571525Y469209D01*
X571192Y469417D01*
X570983Y469667D01*
X570942Y469917D01*
X571025Y470209D01*
X571317Y470417D01*
X571608Y470500D01*
X571983D01*
G01X571608D02*
X571358Y470625D01*
X571150Y470834D01*
X571067Y471084D01*
X571150Y471334D01*
X571358Y471542D01*
X571733Y471667D01*
X572108Y471625D01*
X572483Y471459D01*
G01X552105Y477040D02*
X566105D01*
G01X552105Y464040D02*
Y477040D01*
G01X566105Y464040D02*
X552105D01*
G01X566105Y477040D02*
Y464040D01*
G01X552300Y478400D02*
Y491400D01*
G01X566300Y478400D02*
X552300D01*
G01X566300Y491400D02*
Y478400D01*
G01X532700Y478600D02*
X518700D01*
G01X532700Y491600D02*
Y478600D01*
G01X518700D02*
Y491600D01*
G01X552167Y442900D02*
X552209Y442567D01*
X552375Y442275D01*
X552625Y442025D01*
X552917Y441858D01*
X553250Y441775D01*
X553584D01*
X553917Y441858D01*
X554209Y442025D01*
X554459Y442275D01*
X554625Y442567D01*
X554667Y442900D01*
X554625Y443233D01*
X554459Y443525D01*
X554209Y443775D01*
X553917Y443942D01*
X553584Y444025D01*
X553250D01*
X552917Y443942D01*
X552625Y443775D01*
X552375Y443525D01*
X552209Y443233D01*
X552167Y442900D01*
G01X552834Y443233D02*
X552167Y443733D01*
G01X552667Y445083D02*
X552375Y445333D01*
X552209Y445667D01*
X552167Y446042D01*
X552209Y446375D01*
X552417Y446708D01*
X552667Y446917D01*
X552917Y446958D01*
X553209Y446875D01*
X553417Y446583D01*
X553500Y446292D01*
Y445917D01*
G01Y446292D02*
X553625Y446542D01*
X553834Y446750D01*
X554084Y446833D01*
X554334Y446750D01*
X554542Y446542D01*
X554667Y446167D01*
X554625Y445792D01*
X554459Y445417D01*
G01X553209Y448308D02*
X553500Y448600D01*
X553667Y448850D01*
X553750Y449183D01*
X553667Y449475D01*
X553500Y449683D01*
X553250Y449850D01*
X552959Y449892D01*
X552709Y449850D01*
X552459Y449683D01*
X552250Y449433D01*
X552167Y449142D01*
X552250Y448808D01*
X552500Y448517D01*
X552875Y448350D01*
X553292Y448308D01*
X553834Y448392D01*
X554125Y448517D01*
X554417Y448725D01*
X554625Y449017D01*
X554667Y449308D01*
X554584Y449600D01*
X554375Y449808D01*
G01X529612Y452771D02*
X531712Y454571D01*
X529612Y456771D01*
G01X529512Y460371D02*
X548712D01*
Y449171D01*
X529512D01*
Y460371D01*
X529912D01*
G01X522745Y452863D02*
X522995Y452988D01*
X523287Y453071D01*
X523620D01*
X523995Y452946D01*
X524287Y452738D01*
X524495Y452488D01*
X524662Y452071D01*
X524704Y451696D01*
X524620Y451321D01*
X524495Y451071D01*
X524245Y450821D01*
X523954Y450654D01*
X523662Y450571D01*
X523370D01*
X523079Y450654D01*
X522829Y450779D01*
X522620Y450946D01*
G01X521354Y451613D02*
X521062Y451904D01*
X520812Y452071D01*
X520479Y452154D01*
X520187Y452071D01*
X519979Y451904D01*
X519812Y451654D01*
X519770Y451363D01*
X519812Y451113D01*
X519979Y450863D01*
X520229Y450654D01*
X520520Y450571D01*
X520854Y450654D01*
X521145Y450904D01*
X521312Y451279D01*
X521354Y451696D01*
X521270Y452238D01*
X521145Y452529D01*
X520937Y452821D01*
X520645Y453029D01*
X520354Y453071D01*
X520062Y452988D01*
X519854Y452779D01*
G01X517462Y453071D02*
X517795Y452988D01*
X518045Y452779D01*
X518212Y452529D01*
X518337Y452196D01*
X518379Y451821D01*
X518337Y451446D01*
X518212Y451113D01*
X518045Y450863D01*
X517795Y450654D01*
X517462Y450571D01*
X517129Y450654D01*
X516879Y450863D01*
X516712Y451113D01*
X516587Y451446D01*
X516545Y451821D01*
X516587Y452196D01*
X516712Y452529D01*
X516879Y452779D01*
X517129Y452988D01*
X517462Y453071D01*
G01X515070Y450863D02*
X514779Y450654D01*
X514445Y450571D01*
X514112Y450654D01*
X513820Y450904D01*
X513612Y451279D01*
X513529Y451654D01*
Y452113D01*
X513612Y452488D01*
X513820Y452821D01*
X514070Y452988D01*
X514362Y453071D01*
X514695Y452988D01*
X514945Y452821D01*
X515112Y452571D01*
X515195Y452238D01*
X515112Y451946D01*
X514904Y451654D01*
X514654Y451488D01*
X514362Y451446D01*
X514029Y451529D01*
X513779Y451738D01*
X513529Y452113D01*
G01X522933Y448192D02*
X523183Y448317D01*
X523475Y448400D01*
X523808D01*
X524183Y448275D01*
X524475Y448067D01*
X524683Y447817D01*
X524850Y447400D01*
X524892Y447025D01*
X524808Y446650D01*
X524683Y446400D01*
X524433Y446150D01*
X524142Y445983D01*
X523850Y445900D01*
X523558D01*
X523267Y445983D01*
X523017Y446108D01*
X522808Y446275D01*
G01X521542Y446942D02*
X521250Y447233D01*
X521000Y447400D01*
X520667Y447483D01*
X520375Y447400D01*
X520167Y447233D01*
X520000Y446983D01*
X519958Y446692D01*
X520000Y446442D01*
X520167Y446192D01*
X520417Y445983D01*
X520708Y445900D01*
X521042Y445983D01*
X521333Y446233D01*
X521500Y446608D01*
X521542Y447025D01*
X521458Y447567D01*
X521333Y447858D01*
X521125Y448150D01*
X520833Y448358D01*
X520542Y448400D01*
X520250Y448317D01*
X520042Y448108D01*
G01X518358Y446192D02*
X518067Y445983D01*
X517733Y445900D01*
X517400Y445983D01*
X517108Y446233D01*
X516900Y446608D01*
X516817Y446983D01*
Y447442D01*
X516900Y447817D01*
X517108Y448150D01*
X517358Y448317D01*
X517650Y448400D01*
X517983Y448317D01*
X518233Y448150D01*
X518400Y447900D01*
X518483Y447567D01*
X518400Y447275D01*
X518192Y446983D01*
X517942Y446817D01*
X517650Y446775D01*
X517317Y446858D01*
X517067Y447067D01*
X516817Y447442D01*
G01X514550Y448400D02*
X514883Y448317D01*
X515133Y448108D01*
X515300Y447858D01*
X515425Y447525D01*
X515467Y447150D01*
X515425Y446775D01*
X515300Y446442D01*
X515133Y446192D01*
X514883Y445983D01*
X514550Y445900D01*
X514217Y445983D01*
X513967Y446192D01*
X513800Y446442D01*
X513675Y446775D01*
X513633Y447150D01*
X513675Y447525D01*
X513800Y447858D01*
X513967Y448108D01*
X514217Y448317D01*
X514550Y448400D01*
G01X548733Y476792D02*
X548983Y476917D01*
X549275Y477000D01*
X549608D01*
X549983Y476875D01*
X550275Y476667D01*
X550483Y476417D01*
X550650Y476000D01*
X550692Y475625D01*
X550608Y475250D01*
X550483Y475000D01*
X550233Y474750D01*
X549942Y474583D01*
X549650Y474500D01*
X549358D01*
X549067Y474583D01*
X548817Y474708D01*
X548608Y474875D01*
G01X547342Y475542D02*
X547050Y475833D01*
X546800Y476000D01*
X546467Y476083D01*
X546175Y476000D01*
X545967Y475833D01*
X545800Y475583D01*
X545758Y475292D01*
X545800Y475042D01*
X545967Y474792D01*
X546217Y474583D01*
X546508Y474500D01*
X546842Y474583D01*
X547133Y474833D01*
X547300Y475208D01*
X547342Y475625D01*
X547258Y476167D01*
X547133Y476458D01*
X546925Y476750D01*
X546633Y476958D01*
X546342Y477000D01*
X546050Y476917D01*
X545842Y476708D01*
G01X543450Y477000D02*
X543783Y476917D01*
X544033Y476708D01*
X544200Y476458D01*
X544325Y476125D01*
X544367Y475750D01*
X544325Y475375D01*
X544200Y475042D01*
X544033Y474792D01*
X543783Y474583D01*
X543450Y474500D01*
X543117Y474583D01*
X542867Y474792D01*
X542700Y475042D01*
X542575Y475375D01*
X542533Y475750D01*
X542575Y476125D01*
X542700Y476458D01*
X542867Y476708D01*
X543117Y476917D01*
X543450Y477000D01*
G01X540350Y474500D02*
X540058Y474542D01*
X539725Y474667D01*
X539517Y474875D01*
X539433Y475167D01*
X539517Y475458D01*
X539767Y475708D01*
X540142Y475833D01*
X540558D01*
X540808Y475917D01*
X541017Y476125D01*
X541100Y476417D01*
X540975Y476708D01*
X540683Y476917D01*
X540350Y477000D01*
X540017Y476917D01*
X539725Y476708D01*
X539600Y476417D01*
X539683Y476125D01*
X539892Y475917D01*
X540142Y475833D01*
X540558D01*
X540933Y475708D01*
X541183Y475458D01*
X541267Y475167D01*
X541183Y474875D01*
X540975Y474667D01*
X540642Y474542D01*
X540350Y474500D01*
G01X527983Y493500D02*
Y496000D01*
X526942D01*
X526608Y495875D01*
X526400Y495708D01*
X526317Y495375D01*
X526400Y495042D01*
X526650Y494833D01*
X526942Y494708D01*
X527983D01*
G01X526942D02*
X526317Y493500D01*
G01X524842Y494542D02*
X524550Y494833D01*
X524300Y495000D01*
X523967Y495083D01*
X523675Y495000D01*
X523467Y494833D01*
X523300Y494583D01*
X523258Y494292D01*
X523300Y494042D01*
X523467Y493792D01*
X523717Y493583D01*
X524008Y493500D01*
X524342Y493583D01*
X524633Y493833D01*
X524800Y494208D01*
X524842Y494625D01*
X524758Y495167D01*
X524633Y495458D01*
X524425Y495750D01*
X524133Y495958D01*
X523842Y496000D01*
X523550Y495917D01*
X523342Y495708D01*
G01X520950Y496000D02*
X521283Y495917D01*
X521533Y495708D01*
X521700Y495458D01*
X521825Y495125D01*
X521867Y494750D01*
X521825Y494375D01*
X521700Y494042D01*
X521533Y493792D01*
X521283Y493583D01*
X520950Y493500D01*
X520617Y493583D01*
X520367Y493792D01*
X520200Y494042D01*
X520075Y494375D01*
X520033Y494750D01*
X520075Y495125D01*
X520200Y495458D01*
X520367Y495708D01*
X520617Y495917D01*
X520950Y496000D01*
G01X518642Y495583D02*
X518392Y495833D01*
X518100Y495958D01*
X517767Y496000D01*
X517350Y495917D01*
X517058Y495708D01*
X516975Y495458D01*
X517017Y495208D01*
X517183Y495000D01*
X518017Y494583D01*
X518392Y494292D01*
X518642Y493875D01*
X518725Y493500D01*
X516975D01*
G01X548610Y492837D02*
X551110D01*
Y493878D01*
X550985Y494212D01*
X550818Y494420D01*
X550485Y494503D01*
X550152Y494420D01*
X549943Y494170D01*
X549818Y493878D01*
Y492837D01*
G01Y493878D02*
X548610Y494503D01*
G01X550693Y495978D02*
X550943Y496228D01*
X551068Y496520D01*
X551110Y496853D01*
X551027Y497270D01*
X550818Y497562D01*
X550568Y497645D01*
X550318Y497603D01*
X550110Y497437D01*
X549693Y496603D01*
X549402Y496228D01*
X548985Y495978D01*
X548610Y495895D01*
Y497645D01*
G01X561900Y494400D02*
X562233Y494442D01*
X562525Y494608D01*
X562775Y494858D01*
X562942Y495150D01*
X563025Y495483D01*
Y495817D01*
X562942Y496150D01*
X562775Y496442D01*
X562525Y496692D01*
X562233Y496858D01*
X561900Y496900D01*
X561567Y496858D01*
X561275Y496692D01*
X561025Y496442D01*
X560858Y496150D01*
X560775Y495817D01*
Y495483D01*
X560858Y495150D01*
X561025Y494858D01*
X561275Y494608D01*
X561567Y494442D01*
X561900Y494400D01*
G01X561567Y495067D02*
X561067Y494400D01*
G01X558800D02*
Y496900D01*
X559300Y496400D01*
G01Y494400D02*
X558300D01*
G01X555700Y496900D02*
X556033Y496817D01*
X556283Y496608D01*
X556450Y496358D01*
X556575Y496025D01*
X556617Y495650D01*
X556575Y495275D01*
X556450Y494942D01*
X556283Y494692D01*
X556033Y494483D01*
X555700Y494400D01*
X555367Y494483D01*
X555117Y494692D01*
X554950Y494942D01*
X554825Y495275D01*
X554783Y495650D01*
X554825Y496025D01*
X554950Y496358D01*
X555117Y496608D01*
X555367Y496817D01*
X555700Y496900D01*
G01X552300Y491400D02*
X566300D01*
G01X526550Y498500D02*
X526883Y498542D01*
X527175Y498708D01*
X527425Y498958D01*
X527592Y499250D01*
X527675Y499583D01*
Y499917D01*
X527592Y500250D01*
X527425Y500542D01*
X527175Y500792D01*
X526883Y500958D01*
X526550Y501000D01*
X526217Y500958D01*
X525925Y500792D01*
X525675Y500542D01*
X525508Y500250D01*
X525425Y499917D01*
Y499583D01*
X525508Y499250D01*
X525675Y498958D01*
X525925Y498708D01*
X526217Y498542D01*
X526550Y498500D01*
G01X526217Y499167D02*
X525717Y498500D01*
G01X524158Y498792D02*
X523867Y498583D01*
X523533Y498500D01*
X523200Y498583D01*
X522908Y498833D01*
X522700Y499208D01*
X522617Y499583D01*
Y500042D01*
X522700Y500417D01*
X522908Y500750D01*
X523158Y500917D01*
X523450Y501000D01*
X523783Y500917D01*
X524033Y500750D01*
X524200Y500500D01*
X524283Y500167D01*
X524200Y499875D01*
X523992Y499583D01*
X523742Y499417D01*
X523450Y499375D01*
X523117Y499458D01*
X522867Y499667D01*
X522617Y500042D01*
G01X518700Y491600D02*
X532700D01*
G01X584248Y80459D02*
X584373Y80209D01*
X584456Y79917D01*
Y79584D01*
X584331Y79209D01*
X584123Y78917D01*
X583873Y78709D01*
X583456Y78542D01*
X583081Y78500D01*
X582706Y78584D01*
X582456Y78709D01*
X582206Y78959D01*
X582039Y79250D01*
X581956Y79542D01*
Y79834D01*
X582039Y80125D01*
X582164Y80375D01*
X582331Y80584D01*
G01X582456Y81725D02*
X582164Y81975D01*
X581998Y82309D01*
X581956Y82684D01*
X581998Y83017D01*
X582206Y83350D01*
X582456Y83559D01*
X582706Y83600D01*
X582998Y83517D01*
X583206Y83225D01*
X583289Y82934D01*
Y82559D01*
G01Y82934D02*
X583414Y83184D01*
X583623Y83392D01*
X583873Y83475D01*
X584123Y83392D01*
X584331Y83184D01*
X584456Y82809D01*
X584414Y82434D01*
X584248Y82059D01*
G01X581956Y85742D02*
X584456D01*
X583956Y85242D01*
G01X581956D02*
Y86242D01*
G01Y88842D02*
X584456D01*
X583956Y88342D01*
G01X581956D02*
Y89342D01*
G01X588248Y80459D02*
X588373Y80209D01*
X588456Y79917D01*
Y79584D01*
X588331Y79209D01*
X588123Y78917D01*
X587873Y78709D01*
X587456Y78542D01*
X587081Y78500D01*
X586706Y78584D01*
X586456Y78709D01*
X586206Y78959D01*
X586039Y79250D01*
X585956Y79542D01*
Y79834D01*
X586039Y80125D01*
X586164Y80375D01*
X586331Y80584D01*
G01X586456Y81725D02*
X586164Y81975D01*
X585998Y82309D01*
X585956Y82684D01*
X585998Y83017D01*
X586206Y83350D01*
X586456Y83559D01*
X586706Y83600D01*
X586998Y83517D01*
X587206Y83225D01*
X587289Y82934D01*
Y82559D01*
G01Y82934D02*
X587414Y83184D01*
X587623Y83392D01*
X587873Y83475D01*
X588123Y83392D01*
X588331Y83184D01*
X588456Y82809D01*
X588414Y82434D01*
X588248Y82059D01*
G01X585956Y85742D02*
X588456D01*
X587956Y85242D01*
G01X585956D02*
Y86242D01*
G01X588039Y88050D02*
X588289Y88300D01*
X588414Y88592D01*
X588456Y88925D01*
X588373Y89342D01*
X588164Y89634D01*
X587914Y89717D01*
X587664Y89675D01*
X587456Y89509D01*
X587039Y88675D01*
X586748Y88300D01*
X586331Y88050D01*
X585956Y87967D01*
Y89717D01*
G01X593349Y80597D02*
X593474Y80347D01*
X593557Y80055D01*
Y79722D01*
X593432Y79347D01*
X593224Y79055D01*
X592974Y78847D01*
X592557Y78680D01*
X592182Y78638D01*
X591807Y78722D01*
X591557Y78847D01*
X591307Y79097D01*
X591140Y79388D01*
X591057Y79680D01*
Y79972D01*
X591140Y80263D01*
X591265Y80513D01*
X591432Y80722D01*
G01X591557Y81863D02*
X591265Y82113D01*
X591099Y82447D01*
X591057Y82822D01*
X591099Y83155D01*
X591307Y83488D01*
X591557Y83697D01*
X591807Y83738D01*
X592099Y83655D01*
X592307Y83363D01*
X592390Y83072D01*
Y82697D01*
G01Y83072D02*
X592515Y83322D01*
X592724Y83530D01*
X592974Y83613D01*
X593224Y83530D01*
X593432Y83322D01*
X593557Y82947D01*
X593515Y82572D01*
X593349Y82197D01*
G01X591057Y85880D02*
X593557D01*
X593057Y85380D01*
G01X591057D02*
Y86380D01*
G01X591557Y88063D02*
X591265Y88313D01*
X591099Y88647D01*
X591057Y89022D01*
X591099Y89355D01*
X591307Y89688D01*
X591557Y89897D01*
X591807Y89938D01*
X592099Y89855D01*
X592307Y89563D01*
X592390Y89272D01*
Y88897D01*
G01Y89272D02*
X592515Y89522D01*
X592724Y89730D01*
X592974Y89813D01*
X593224Y89730D01*
X593432Y89522D01*
X593557Y89147D01*
X593515Y88772D01*
X593349Y88397D01*
G01X597349Y80597D02*
X597474Y80347D01*
X597557Y80055D01*
Y79722D01*
X597432Y79347D01*
X597224Y79055D01*
X596974Y78847D01*
X596557Y78680D01*
X596182Y78638D01*
X595807Y78722D01*
X595557Y78847D01*
X595307Y79097D01*
X595140Y79388D01*
X595057Y79680D01*
Y79972D01*
X595140Y80263D01*
X595265Y80513D01*
X595432Y80722D01*
G01X595557Y81863D02*
X595265Y82113D01*
X595099Y82447D01*
X595057Y82822D01*
X595099Y83155D01*
X595307Y83488D01*
X595557Y83697D01*
X595807Y83738D01*
X596099Y83655D01*
X596307Y83363D01*
X596390Y83072D01*
Y82697D01*
G01Y83072D02*
X596515Y83322D01*
X596724Y83530D01*
X596974Y83613D01*
X597224Y83530D01*
X597432Y83322D01*
X597557Y82947D01*
X597515Y82572D01*
X597349Y82197D01*
G01X595057Y85880D02*
X597557D01*
X597057Y85380D01*
G01X595057D02*
Y86380D01*
G01Y89480D02*
X597557D01*
X595765Y87938D01*
Y90022D01*
G01X602174Y80322D02*
X602299Y80072D01*
X602382Y79780D01*
Y79447D01*
X602257Y79072D01*
X602049Y78780D01*
X601799Y78572D01*
X601382Y78405D01*
X601007Y78363D01*
X600632Y78447D01*
X600382Y78572D01*
X600132Y78822D01*
X599965Y79113D01*
X599882Y79405D01*
Y79697D01*
X599965Y79988D01*
X600090Y80238D01*
X600257Y80447D01*
G01X600382Y81588D02*
X600090Y81838D01*
X599924Y82172D01*
X599882Y82547D01*
X599924Y82880D01*
X600132Y83213D01*
X600382Y83422D01*
X600632Y83463D01*
X600924Y83380D01*
X601132Y83088D01*
X601215Y82797D01*
Y82422D01*
G01Y82797D02*
X601340Y83047D01*
X601549Y83255D01*
X601799Y83338D01*
X602049Y83255D01*
X602257Y83047D01*
X602382Y82672D01*
X602340Y82297D01*
X602174Y81922D01*
G01X599882Y85605D02*
X602382D01*
X601882Y85105D01*
G01X599882D02*
Y86105D01*
G01X600257Y87788D02*
X600049Y88038D01*
X599924Y88330D01*
X599882Y88705D01*
X599965Y89080D01*
X600132Y89372D01*
X600424Y89580D01*
X600757Y89622D01*
X601090Y89538D01*
X601299Y89330D01*
X601465Y89038D01*
X601507Y88747D01*
X601465Y88455D01*
X601299Y88080D01*
X602382Y88205D01*
Y89330D01*
G01X606174Y80322D02*
X606299Y80072D01*
X606382Y79780D01*
Y79447D01*
X606257Y79072D01*
X606049Y78780D01*
X605799Y78572D01*
X605382Y78405D01*
X605007Y78363D01*
X604632Y78447D01*
X604382Y78572D01*
X604132Y78822D01*
X603965Y79113D01*
X603882Y79405D01*
Y79697D01*
X603965Y79988D01*
X604090Y80238D01*
X604257Y80447D01*
G01X604382Y81588D02*
X604090Y81838D01*
X603924Y82172D01*
X603882Y82547D01*
X603924Y82880D01*
X604132Y83213D01*
X604382Y83422D01*
X604632Y83463D01*
X604924Y83380D01*
X605132Y83088D01*
X605215Y82797D01*
Y82422D01*
G01Y82797D02*
X605340Y83047D01*
X605549Y83255D01*
X605799Y83338D01*
X606049Y83255D01*
X606257Y83047D01*
X606382Y82672D01*
X606340Y82297D01*
X606174Y81922D01*
G01X603882Y85605D02*
X606382D01*
X605882Y85105D01*
G01X603882D02*
Y86105D01*
G01X604924Y87913D02*
X605215Y88205D01*
X605382Y88455D01*
X605465Y88788D01*
X605382Y89080D01*
X605215Y89288D01*
X604965Y89455D01*
X604674Y89497D01*
X604424Y89455D01*
X604174Y89288D01*
X603965Y89038D01*
X603882Y88747D01*
X603965Y88413D01*
X604215Y88122D01*
X604590Y87955D01*
X605007Y87913D01*
X605549Y87997D01*
X605840Y88122D01*
X606132Y88330D01*
X606340Y88622D01*
X606382Y88913D01*
X606299Y89205D01*
X606090Y89413D01*
G01X611137Y80184D02*
X611262Y79934D01*
X611345Y79642D01*
Y79309D01*
X611220Y78934D01*
X611012Y78642D01*
X610762Y78434D01*
X610345Y78267D01*
X609970Y78225D01*
X609595Y78309D01*
X609345Y78434D01*
X609095Y78684D01*
X608928Y78975D01*
X608845Y79267D01*
Y79559D01*
X608928Y79850D01*
X609053Y80100D01*
X609220Y80309D01*
G01X609345Y81450D02*
X609053Y81700D01*
X608887Y82034D01*
X608845Y82409D01*
X608887Y82742D01*
X609095Y83075D01*
X609345Y83284D01*
X609595Y83325D01*
X609887Y83242D01*
X610095Y82950D01*
X610178Y82659D01*
Y82284D01*
G01Y82659D02*
X610303Y82909D01*
X610512Y83117D01*
X610762Y83200D01*
X611012Y83117D01*
X611220Y82909D01*
X611345Y82534D01*
X611303Y82159D01*
X611137Y81784D01*
G01X608845Y85467D02*
X611345D01*
X610845Y84967D01*
G01X608845D02*
Y85967D01*
G01Y88484D02*
X609387Y88567D01*
X609845Y88692D01*
X610262Y88859D01*
X610720Y89067D01*
X611345Y89400D01*
Y87734D01*
G01X615137Y80184D02*
X615262Y79934D01*
X615345Y79642D01*
Y79309D01*
X615220Y78934D01*
X615012Y78642D01*
X614762Y78434D01*
X614345Y78267D01*
X613970Y78225D01*
X613595Y78309D01*
X613345Y78434D01*
X613095Y78684D01*
X612928Y78975D01*
X612845Y79267D01*
Y79559D01*
X612928Y79850D01*
X613053Y80100D01*
X613220Y80309D01*
G01X613345Y81450D02*
X613053Y81700D01*
X612887Y82034D01*
X612845Y82409D01*
X612887Y82742D01*
X613095Y83075D01*
X613345Y83284D01*
X613595Y83325D01*
X613887Y83242D01*
X614095Y82950D01*
X614178Y82659D01*
Y82284D01*
G01Y82659D02*
X614303Y82909D01*
X614512Y83117D01*
X614762Y83200D01*
X615012Y83117D01*
X615220Y82909D01*
X615345Y82534D01*
X615303Y82159D01*
X615137Y81784D01*
G01X612845Y85467D02*
X615345D01*
X614845Y84967D01*
G01X612845D02*
Y85967D01*
G01Y88567D02*
X612887Y88859D01*
X613012Y89192D01*
X613220Y89400D01*
X613512Y89484D01*
X613803Y89400D01*
X614053Y89150D01*
X614178Y88775D01*
Y88359D01*
X614262Y88109D01*
X614470Y87900D01*
X614762Y87817D01*
X615053Y87942D01*
X615262Y88234D01*
X615345Y88567D01*
X615262Y88900D01*
X615053Y89192D01*
X614762Y89317D01*
X614470Y89234D01*
X614262Y89025D01*
X614178Y88775D01*
Y88359D01*
X614053Y87984D01*
X613803Y87734D01*
X613512Y87650D01*
X613220Y87734D01*
X613012Y87942D01*
X612887Y88275D01*
X612845Y88567D01*
G01X619961Y80322D02*
X620086Y80072D01*
X620169Y79780D01*
Y79447D01*
X620044Y79072D01*
X619836Y78780D01*
X619586Y78572D01*
X619169Y78405D01*
X618794Y78363D01*
X618419Y78447D01*
X618169Y78572D01*
X617919Y78822D01*
X617752Y79113D01*
X617669Y79405D01*
Y79697D01*
X617752Y79988D01*
X617877Y80238D01*
X618044Y80447D01*
G01X618169Y81588D02*
X617877Y81838D01*
X617711Y82172D01*
X617669Y82547D01*
X617711Y82880D01*
X617919Y83213D01*
X618169Y83422D01*
X618419Y83463D01*
X618711Y83380D01*
X618919Y83088D01*
X619002Y82797D01*
Y82422D01*
G01Y82797D02*
X619127Y83047D01*
X619336Y83255D01*
X619586Y83338D01*
X619836Y83255D01*
X620044Y83047D01*
X620169Y82672D01*
X620127Y82297D01*
X619961Y81922D01*
G01X617669Y85605D02*
X620169D01*
X619669Y85105D01*
G01X617669D02*
Y86105D01*
G01X617961Y87997D02*
X617752Y88288D01*
X617669Y88622D01*
X617752Y88955D01*
X618002Y89247D01*
X618377Y89455D01*
X618752Y89538D01*
X619211D01*
X619586Y89455D01*
X619919Y89247D01*
X620086Y88997D01*
X620169Y88705D01*
X620086Y88372D01*
X619919Y88122D01*
X619669Y87955D01*
X619336Y87872D01*
X619044Y87955D01*
X618752Y88163D01*
X618586Y88413D01*
X618544Y88705D01*
X618627Y89038D01*
X618836Y89288D01*
X619211Y89538D01*
G01X623961Y80322D02*
X624086Y80072D01*
X624169Y79780D01*
Y79447D01*
X624044Y79072D01*
X623836Y78780D01*
X623586Y78572D01*
X623169Y78405D01*
X622794Y78363D01*
X622419Y78447D01*
X622169Y78572D01*
X621919Y78822D01*
X621752Y79113D01*
X621669Y79405D01*
Y79697D01*
X621752Y79988D01*
X621877Y80238D01*
X622044Y80447D01*
G01X622169Y81588D02*
X621877Y81838D01*
X621711Y82172D01*
X621669Y82547D01*
X621711Y82880D01*
X621919Y83213D01*
X622169Y83422D01*
X622419Y83463D01*
X622711Y83380D01*
X622919Y83088D01*
X623002Y82797D01*
Y82422D01*
G01Y82797D02*
X623127Y83047D01*
X623336Y83255D01*
X623586Y83338D01*
X623836Y83255D01*
X624044Y83047D01*
X624169Y82672D01*
X624127Y82297D01*
X623961Y81922D01*
G01X623752Y84813D02*
X624002Y85063D01*
X624127Y85355D01*
X624169Y85688D01*
X624086Y86105D01*
X623877Y86397D01*
X623627Y86480D01*
X623377Y86438D01*
X623169Y86272D01*
X622752Y85438D01*
X622461Y85063D01*
X622044Y84813D01*
X621669Y84730D01*
Y86480D01*
G01X624169Y88705D02*
X624086Y88372D01*
X623877Y88122D01*
X623627Y87955D01*
X623294Y87830D01*
X622919Y87788D01*
X622544Y87830D01*
X622211Y87955D01*
X621961Y88122D01*
X621752Y88372D01*
X621669Y88705D01*
X621752Y89038D01*
X621961Y89288D01*
X622211Y89455D01*
X622544Y89580D01*
X622919Y89622D01*
X623294Y89580D01*
X623627Y89455D01*
X623877Y89288D01*
X624086Y89038D01*
X624169Y88705D01*
G01X629063Y80597D02*
X629188Y80347D01*
X629271Y80055D01*
Y79722D01*
X629146Y79347D01*
X628938Y79055D01*
X628688Y78847D01*
X628271Y78680D01*
X627896Y78638D01*
X627521Y78722D01*
X627271Y78847D01*
X627021Y79097D01*
X626854Y79388D01*
X626771Y79680D01*
Y79972D01*
X626854Y80263D01*
X626979Y80513D01*
X627146Y80722D01*
G01X627271Y81863D02*
X626979Y82113D01*
X626813Y82447D01*
X626771Y82822D01*
X626813Y83155D01*
X627021Y83488D01*
X627271Y83697D01*
X627521Y83738D01*
X627813Y83655D01*
X628021Y83363D01*
X628104Y83072D01*
Y82697D01*
G01Y83072D02*
X628229Y83322D01*
X628438Y83530D01*
X628688Y83613D01*
X628938Y83530D01*
X629146Y83322D01*
X629271Y82947D01*
X629229Y82572D01*
X629063Y82197D01*
G01X628854Y85088D02*
X629104Y85338D01*
X629229Y85630D01*
X629271Y85963D01*
X629188Y86380D01*
X628979Y86672D01*
X628729Y86755D01*
X628479Y86713D01*
X628271Y86547D01*
X627854Y85713D01*
X627563Y85338D01*
X627146Y85088D01*
X626771Y85005D01*
Y86755D01*
G01Y88980D02*
X629271D01*
X628771Y88480D01*
G01X626771D02*
Y89480D01*
G01X633063Y80597D02*
X633188Y80347D01*
X633271Y80055D01*
Y79722D01*
X633146Y79347D01*
X632938Y79055D01*
X632688Y78847D01*
X632271Y78680D01*
X631896Y78638D01*
X631521Y78722D01*
X631271Y78847D01*
X631021Y79097D01*
X630854Y79388D01*
X630771Y79680D01*
Y79972D01*
X630854Y80263D01*
X630979Y80513D01*
X631146Y80722D01*
G01X631271Y81863D02*
X630979Y82113D01*
X630813Y82447D01*
X630771Y82822D01*
X630813Y83155D01*
X631021Y83488D01*
X631271Y83697D01*
X631521Y83738D01*
X631813Y83655D01*
X632021Y83363D01*
X632104Y83072D01*
Y82697D01*
G01Y83072D02*
X632229Y83322D01*
X632438Y83530D01*
X632688Y83613D01*
X632938Y83530D01*
X633146Y83322D01*
X633271Y82947D01*
X633229Y82572D01*
X633063Y82197D01*
G01X632854Y85088D02*
X633104Y85338D01*
X633229Y85630D01*
X633271Y85963D01*
X633188Y86380D01*
X632979Y86672D01*
X632729Y86755D01*
X632479Y86713D01*
X632271Y86547D01*
X631854Y85713D01*
X631563Y85338D01*
X631146Y85088D01*
X630771Y85005D01*
Y86755D01*
G01X632854Y88188D02*
X633104Y88438D01*
X633229Y88730D01*
X633271Y89063D01*
X633188Y89480D01*
X632979Y89772D01*
X632729Y89855D01*
X632479Y89813D01*
X632271Y89647D01*
X631854Y88813D01*
X631563Y88438D01*
X631146Y88188D01*
X630771Y88105D01*
Y89855D01*
G01X644494Y81041D02*
X644744Y81166D01*
X645036Y81249D01*
X645369D01*
X645744Y81124D01*
X646036Y80916D01*
X646244Y80666D01*
X646411Y80249D01*
X646453Y79874D01*
X646369Y79499D01*
X646244Y79249D01*
X645994Y78999D01*
X645703Y78832D01*
X645411Y78749D01*
X645119D01*
X644828Y78832D01*
X644578Y78957D01*
X644369Y79124D01*
G01X643228Y79249D02*
X642978Y78957D01*
X642644Y78791D01*
X642269Y78749D01*
X641936Y78791D01*
X641603Y78999D01*
X641394Y79249D01*
X641353Y79499D01*
X641436Y79791D01*
X641728Y79999D01*
X642019Y80082D01*
X642394D01*
G01X642019D02*
X641769Y80207D01*
X641561Y80416D01*
X641478Y80666D01*
X641561Y80916D01*
X641769Y81124D01*
X642144Y81249D01*
X642519Y81207D01*
X642894Y81041D01*
G01X640003Y80832D02*
X639753Y81082D01*
X639461Y81207D01*
X639128Y81249D01*
X638711Y81166D01*
X638419Y80957D01*
X638336Y80707D01*
X638378Y80457D01*
X638544Y80249D01*
X639378Y79832D01*
X639753Y79541D01*
X640003Y79124D01*
X640086Y78749D01*
X638336D01*
G01X637028Y79249D02*
X636778Y78957D01*
X636444Y78791D01*
X636069Y78749D01*
X635736Y78791D01*
X635403Y78999D01*
X635194Y79249D01*
X635153Y79499D01*
X635236Y79791D01*
X635528Y79999D01*
X635819Y80082D01*
X636194D01*
G01X635819D02*
X635569Y80207D01*
X635361Y80416D01*
X635278Y80666D01*
X635361Y80916D01*
X635569Y81124D01*
X635944Y81249D01*
X636319Y81207D01*
X636694Y81041D01*
G01X644494Y85041D02*
X644744Y85166D01*
X645036Y85249D01*
X645369D01*
X645744Y85124D01*
X646036Y84916D01*
X646244Y84666D01*
X646411Y84249D01*
X646453Y83874D01*
X646369Y83499D01*
X646244Y83249D01*
X645994Y82999D01*
X645703Y82832D01*
X645411Y82749D01*
X645119D01*
X644828Y82832D01*
X644578Y82957D01*
X644369Y83124D01*
G01X643228Y83249D02*
X642978Y82957D01*
X642644Y82791D01*
X642269Y82749D01*
X641936Y82791D01*
X641603Y82999D01*
X641394Y83249D01*
X641353Y83499D01*
X641436Y83791D01*
X641728Y83999D01*
X642019Y84082D01*
X642394D01*
G01X642019D02*
X641769Y84207D01*
X641561Y84416D01*
X641478Y84666D01*
X641561Y84916D01*
X641769Y85124D01*
X642144Y85249D01*
X642519Y85207D01*
X642894Y85041D01*
G01X640003Y84832D02*
X639753Y85082D01*
X639461Y85207D01*
X639128Y85249D01*
X638711Y85166D01*
X638419Y84957D01*
X638336Y84707D01*
X638378Y84457D01*
X638544Y84249D01*
X639378Y83832D01*
X639753Y83541D01*
X640003Y83124D01*
X640086Y82749D01*
X638336D01*
G01X635611D02*
Y85249D01*
X637153Y83457D01*
X635069D01*
G01X614500Y61567D02*
X617000D01*
Y62608D01*
X616875Y62942D01*
X616708Y63150D01*
X616375Y63233D01*
X616042Y63150D01*
X615833Y62900D01*
X615708Y62608D01*
Y61567D01*
G01Y62608D02*
X614500Y63233D01*
G01Y65500D02*
X614542Y65792D01*
X614667Y66125D01*
X614875Y66333D01*
X615167Y66417D01*
X615458Y66333D01*
X615708Y66083D01*
X615833Y65708D01*
Y65292D01*
X615917Y65042D01*
X616125Y64833D01*
X616417Y64750D01*
X616708Y64875D01*
X616917Y65167D01*
X617000Y65500D01*
X616917Y65833D01*
X616708Y66125D01*
X616417Y66250D01*
X616125Y66167D01*
X615917Y65958D01*
X615833Y65708D01*
Y65292D01*
X615708Y64917D01*
X615458Y64667D01*
X615167Y64583D01*
X614875Y64667D01*
X614667Y64875D01*
X614542Y65208D01*
X614500Y65500D01*
G01Y68600D02*
X617000D01*
X616500Y68100D01*
G01X614500D02*
Y69100D01*
G01X631000Y67700D02*
X635000D01*
Y60300D01*
G01X623500Y61517D02*
X626000D01*
Y62558D01*
X625875Y62892D01*
X625708Y63100D01*
X625375Y63183D01*
X625042Y63100D01*
X624833Y62850D01*
X624708Y62558D01*
Y61517D01*
G01Y62558D02*
X623500Y63183D01*
G01X624000Y64533D02*
X623708Y64783D01*
X623542Y65117D01*
X623500Y65492D01*
X623542Y65825D01*
X623750Y66158D01*
X624000Y66367D01*
X624250Y66408D01*
X624542Y66325D01*
X624750Y66033D01*
X624833Y65742D01*
Y65367D01*
G01Y65742D02*
X624958Y65992D01*
X625167Y66200D01*
X625417Y66283D01*
X625667Y66200D01*
X625875Y65992D01*
X626000Y65617D01*
X625958Y65242D01*
X625792Y64867D01*
G01X623500Y68550D02*
X626000D01*
X625500Y68050D01*
G01X623500D02*
Y69050D01*
G01X625583Y70858D02*
X625833Y71108D01*
X625958Y71400D01*
X626000Y71733D01*
X625917Y72150D01*
X625708Y72442D01*
X625458Y72525D01*
X625208Y72483D01*
X625000Y72317D01*
X624583Y71483D01*
X624292Y71108D01*
X623875Y70858D01*
X623500Y70775D01*
Y72525D01*
G01X619003Y61526D02*
X621503D01*
Y62567D01*
X621378Y62901D01*
X621211Y63109D01*
X620878Y63192D01*
X620545Y63109D01*
X620336Y62859D01*
X620211Y62567D01*
Y61526D01*
G01Y62567D02*
X619003Y63192D01*
G01X619503Y64542D02*
X619211Y64792D01*
X619045Y65126D01*
X619003Y65501D01*
X619045Y65834D01*
X619253Y66167D01*
X619503Y66376D01*
X619753Y66417D01*
X620045Y66334D01*
X620253Y66042D01*
X620336Y65751D01*
Y65376D01*
G01Y65751D02*
X620461Y66001D01*
X620670Y66209D01*
X620920Y66292D01*
X621170Y66209D01*
X621378Y66001D01*
X621503Y65626D01*
X621461Y65251D01*
X621295Y64876D01*
G01X619003Y68559D02*
X621503D01*
X621003Y68059D01*
G01X619003D02*
Y69059D01*
G01X619503Y70742D02*
X619211Y70992D01*
X619045Y71326D01*
X619003Y71701D01*
X619045Y72034D01*
X619253Y72367D01*
X619503Y72576D01*
X619753Y72617D01*
X620045Y72534D01*
X620253Y72242D01*
X620336Y71951D01*
Y71576D01*
G01Y71951D02*
X620461Y72201D01*
X620670Y72409D01*
X620920Y72492D01*
X621170Y72409D01*
X621378Y72201D01*
X621503Y71826D01*
X621461Y71451D01*
X621295Y71076D01*
G01X639003Y60309D02*
X635003D01*
Y67709D01*
G01X642233Y116459D02*
X642483Y116584D01*
X642775Y116667D01*
X643108D01*
X643483Y116542D01*
X643775Y116334D01*
X643983Y116084D01*
X644150Y115667D01*
X644192Y115292D01*
X644108Y114917D01*
X643983Y114667D01*
X643733Y114417D01*
X643442Y114250D01*
X643150Y114167D01*
X642858D01*
X642567Y114250D01*
X642317Y114375D01*
X642108Y114542D01*
G01X640967Y114667D02*
X640717Y114375D01*
X640383Y114209D01*
X640008Y114167D01*
X639675Y114209D01*
X639342Y114417D01*
X639133Y114667D01*
X639092Y114917D01*
X639175Y115209D01*
X639467Y115417D01*
X639758Y115500D01*
X640133D01*
G01X639758D02*
X639508Y115625D01*
X639300Y115834D01*
X639217Y116084D01*
X639300Y116334D01*
X639508Y116542D01*
X639883Y116667D01*
X640258Y116625D01*
X640633Y116459D01*
G01X637658Y114459D02*
X637367Y114250D01*
X637033Y114167D01*
X636700Y114250D01*
X636408Y114500D01*
X636200Y114875D01*
X636117Y115250D01*
Y115709D01*
X636200Y116084D01*
X636408Y116417D01*
X636658Y116584D01*
X636950Y116667D01*
X637283Y116584D01*
X637533Y116417D01*
X637700Y116167D01*
X637783Y115834D01*
X637700Y115542D01*
X637492Y115250D01*
X637242Y115084D01*
X636950Y115042D01*
X636617Y115125D01*
X636367Y115334D01*
X636117Y115709D01*
G01X633850Y114167D02*
X633558Y114209D01*
X633225Y114334D01*
X633017Y114542D01*
X632933Y114834D01*
X633017Y115125D01*
X633267Y115375D01*
X633642Y115500D01*
X634058D01*
X634308Y115584D01*
X634517Y115792D01*
X634600Y116084D01*
X634475Y116375D01*
X634183Y116584D01*
X633850Y116667D01*
X633517Y116584D01*
X633225Y116375D01*
X633100Y116084D01*
X633183Y115792D01*
X633392Y115584D01*
X633642Y115500D01*
X634058D01*
X634433Y115375D01*
X634683Y115125D01*
X634767Y114834D01*
X634683Y114542D01*
X634475Y114334D01*
X634142Y114209D01*
X633850Y114167D01*
G01X615500Y109567D02*
X613000D01*
Y111233D01*
G01X615083Y112708D02*
X615333Y112958D01*
X615458Y113250D01*
X615500Y113583D01*
X615417Y114000D01*
X615208Y114292D01*
X614958Y114375D01*
X614708Y114333D01*
X614500Y114167D01*
X614083Y113333D01*
X613792Y112958D01*
X613375Y112708D01*
X613000Y112625D01*
Y114375D01*
G01Y117100D02*
X615500D01*
X613708Y115558D01*
Y117642D01*
G01X628800Y113700D02*
X621800D01*
Y100300D01*
X628800D01*
Y113700D01*
G01X617500Y107017D02*
X620000D01*
Y108058D01*
X619875Y108392D01*
X619708Y108600D01*
X619375Y108683D01*
X619042Y108600D01*
X618833Y108350D01*
X618708Y108058D01*
Y107017D01*
G01Y108058D02*
X617500Y108683D01*
G01X619583Y110158D02*
X619833Y110408D01*
X619958Y110700D01*
X620000Y111033D01*
X619917Y111450D01*
X619708Y111742D01*
X619458Y111825D01*
X619208Y111783D01*
X619000Y111617D01*
X618583Y110783D01*
X618292Y110408D01*
X617875Y110158D01*
X617500Y110075D01*
Y111825D01*
G01Y114050D02*
X617542Y114342D01*
X617667Y114675D01*
X617875Y114883D01*
X618167Y114967D01*
X618458Y114883D01*
X618708Y114633D01*
X618833Y114258D01*
Y113842D01*
X618917Y113592D01*
X619125Y113383D01*
X619417Y113300D01*
X619708Y113425D01*
X619917Y113717D01*
X620000Y114050D01*
X619917Y114383D01*
X619708Y114675D01*
X619417Y114800D01*
X619125Y114717D01*
X618917Y114508D01*
X618833Y114258D01*
Y113842D01*
X618708Y113467D01*
X618458Y113217D01*
X618167Y113133D01*
X617875Y113217D01*
X617667Y113425D01*
X617542Y113758D01*
X617500Y114050D01*
G01X619583Y116358D02*
X619833Y116608D01*
X619958Y116900D01*
X620000Y117233D01*
X619917Y117650D01*
X619708Y117942D01*
X619458Y118025D01*
X619208Y117983D01*
X619000Y117817D01*
X618583Y116983D01*
X618292Y116608D01*
X617875Y116358D01*
X617500Y116275D01*
Y118025D01*
G01X633500Y103300D02*
X629500D01*
Y110700D01*
G01X633733Y176292D02*
X633983Y176417D01*
X634275Y176500D01*
X634608D01*
X634983Y176375D01*
X635275Y176167D01*
X635483Y175917D01*
X635650Y175500D01*
X635692Y175125D01*
X635608Y174750D01*
X635483Y174500D01*
X635233Y174250D01*
X634942Y174083D01*
X634650Y174000D01*
X634358D01*
X634067Y174083D01*
X633817Y174208D01*
X633608Y174375D01*
G01X631050Y174000D02*
Y176500D01*
X632592Y174708D01*
X630508D01*
G01X629367Y174375D02*
X629117Y174167D01*
X628825Y174042D01*
X628450Y174000D01*
X628075Y174083D01*
X627783Y174250D01*
X627575Y174542D01*
X627533Y174875D01*
X627617Y175208D01*
X627825Y175417D01*
X628117Y175583D01*
X628408Y175625D01*
X628700Y175583D01*
X629075Y175417D01*
X628950Y176500D01*
X627825D01*
G01X626267Y174375D02*
X626017Y174167D01*
X625725Y174042D01*
X625350Y174000D01*
X624975Y174083D01*
X624683Y174250D01*
X624475Y174542D01*
X624433Y174875D01*
X624517Y175208D01*
X624725Y175417D01*
X625017Y175583D01*
X625308Y175625D01*
X625600Y175583D01*
X625975Y175417D01*
X625850Y176500D01*
X624725D01*
G01X633733Y172292D02*
X633983Y172417D01*
X634275Y172500D01*
X634608D01*
X634983Y172375D01*
X635275Y172167D01*
X635483Y171917D01*
X635650Y171500D01*
X635692Y171125D01*
X635608Y170750D01*
X635483Y170500D01*
X635233Y170250D01*
X634942Y170083D01*
X634650Y170000D01*
X634358D01*
X634067Y170083D01*
X633817Y170208D01*
X633608Y170375D01*
G01X631050Y170000D02*
Y172500D01*
X632592Y170708D01*
X630508D01*
G01X629367Y170375D02*
X629117Y170167D01*
X628825Y170042D01*
X628450Y170000D01*
X628075Y170083D01*
X627783Y170250D01*
X627575Y170542D01*
X627533Y170875D01*
X627617Y171208D01*
X627825Y171417D01*
X628117Y171583D01*
X628408Y171625D01*
X628700Y171583D01*
X629075Y171417D01*
X628950Y172500D01*
X627825D01*
G01X626267Y170500D02*
X626017Y170208D01*
X625683Y170042D01*
X625308Y170000D01*
X624975Y170042D01*
X624642Y170250D01*
X624433Y170500D01*
X624392Y170750D01*
X624475Y171042D01*
X624767Y171250D01*
X625058Y171333D01*
X625433D01*
G01X625058D02*
X624808Y171458D01*
X624600Y171667D01*
X624517Y171917D01*
X624600Y172167D01*
X624808Y172375D01*
X625183Y172500D01*
X625558Y172458D01*
X625933Y172292D01*
G01X622000Y148517D02*
X624500D01*
Y149558D01*
X624375Y149892D01*
X624208Y150100D01*
X623875Y150183D01*
X623542Y150100D01*
X623333Y149850D01*
X623208Y149558D01*
Y148517D01*
G01Y149558D02*
X622000Y150183D01*
G01X624083Y151658D02*
X624333Y151908D01*
X624458Y152200D01*
X624500Y152533D01*
X624417Y152950D01*
X624208Y153242D01*
X623958Y153325D01*
X623708Y153283D01*
X623500Y153117D01*
X623083Y152283D01*
X622792Y151908D01*
X622375Y151658D01*
X622000Y151575D01*
Y153325D01*
G01Y156050D02*
X624500D01*
X622708Y154508D01*
Y156592D01*
G01X624500Y158650D02*
X624417Y158317D01*
X624208Y158067D01*
X623958Y157900D01*
X623625Y157775D01*
X623250Y157733D01*
X622875Y157775D01*
X622542Y157900D01*
X622292Y158067D01*
X622083Y158317D01*
X622000Y158650D01*
X622083Y158983D01*
X622292Y159233D01*
X622542Y159400D01*
X622875Y159525D01*
X623250Y159567D01*
X623625Y159525D01*
X623958Y159400D01*
X624208Y159233D01*
X624417Y158983D01*
X624500Y158650D01*
G01X634300Y152700D02*
X630300D01*
Y160100D01*
G01X633983Y166000D02*
Y168500D01*
X632942D01*
X632608Y168375D01*
X632400Y168208D01*
X632317Y167875D01*
X632400Y167542D01*
X632650Y167333D01*
X632942Y167208D01*
X633983D01*
G01X632942D02*
X632317Y166000D01*
G01X630842Y168083D02*
X630592Y168333D01*
X630300Y168458D01*
X629967Y168500D01*
X629550Y168417D01*
X629258Y168208D01*
X629175Y167958D01*
X629217Y167708D01*
X629383Y167500D01*
X630217Y167083D01*
X630592Y166792D01*
X630842Y166375D01*
X630925Y166000D01*
X629175D01*
G01X627867Y166375D02*
X627617Y166167D01*
X627325Y166042D01*
X626950Y166000D01*
X626575Y166083D01*
X626283Y166250D01*
X626075Y166542D01*
X626033Y166875D01*
X626117Y167208D01*
X626325Y167417D01*
X626617Y167583D01*
X626908Y167625D01*
X627200Y167583D01*
X627575Y167417D01*
X627450Y168500D01*
X626325D01*
G01X624767Y166375D02*
X624517Y166167D01*
X624225Y166042D01*
X623850Y166000D01*
X623475Y166083D01*
X623183Y166250D01*
X622975Y166542D01*
X622933Y166875D01*
X623017Y167208D01*
X623225Y167417D01*
X623517Y167583D01*
X623808Y167625D01*
X624100Y167583D01*
X624475Y167417D01*
X624350Y168500D01*
X623225D01*
G01X621483Y166000D02*
Y168500D01*
X620442D01*
X620108Y168375D01*
X619900Y168208D01*
X619817Y167875D01*
X619900Y167542D01*
X620150Y167333D01*
X620442Y167208D01*
X621483D01*
G01X620442D02*
X619817Y166000D01*
G01X617550D02*
Y168500D01*
X618050Y168000D01*
G01Y166000D02*
X617050D01*
G01X614533D02*
X614450Y166542D01*
X614325Y167000D01*
X614158Y167417D01*
X613950Y167875D01*
X613617Y168500D01*
X615283D01*
G01X611350Y166000D02*
X611058Y166042D01*
X610725Y166167D01*
X610517Y166375D01*
X610433Y166667D01*
X610517Y166958D01*
X610767Y167208D01*
X611142Y167333D01*
X611558D01*
X611808Y167417D01*
X612017Y167625D01*
X612100Y167917D01*
X611975Y168208D01*
X611683Y168417D01*
X611350Y168500D01*
X611017Y168417D01*
X610725Y168208D01*
X610600Y167917D01*
X610683Y167625D01*
X610892Y167417D01*
X611142Y167333D01*
X611558D01*
X611933Y167208D01*
X612183Y166958D01*
X612267Y166667D01*
X612183Y166375D01*
X611975Y166167D01*
X611642Y166042D01*
X611350Y166000D01*
G01X642233Y120459D02*
X642483Y120584D01*
X642775Y120667D01*
X643108D01*
X643483Y120542D01*
X643775Y120334D01*
X643983Y120084D01*
X644150Y119667D01*
X644192Y119292D01*
X644108Y118917D01*
X643983Y118667D01*
X643733Y118417D01*
X643442Y118250D01*
X643150Y118167D01*
X642858D01*
X642567Y118250D01*
X642317Y118375D01*
X642108Y118542D01*
G01X640967Y118667D02*
X640717Y118375D01*
X640383Y118209D01*
X640008Y118167D01*
X639675Y118209D01*
X639342Y118417D01*
X639133Y118667D01*
X639092Y118917D01*
X639175Y119209D01*
X639467Y119417D01*
X639758Y119500D01*
X640133D01*
G01X639758D02*
X639508Y119625D01*
X639300Y119834D01*
X639217Y120084D01*
X639300Y120334D01*
X639508Y120542D01*
X639883Y120667D01*
X640258Y120625D01*
X640633Y120459D01*
G01X637658Y118459D02*
X637367Y118250D01*
X637033Y118167D01*
X636700Y118250D01*
X636408Y118500D01*
X636200Y118875D01*
X636117Y119250D01*
Y119709D01*
X636200Y120084D01*
X636408Y120417D01*
X636658Y120584D01*
X636950Y120667D01*
X637283Y120584D01*
X637533Y120417D01*
X637700Y120167D01*
X637783Y119834D01*
X637700Y119542D01*
X637492Y119250D01*
X637242Y119084D01*
X636950Y119042D01*
X636617Y119125D01*
X636367Y119334D01*
X636117Y119709D01*
G01X634558Y118459D02*
X634267Y118250D01*
X633933Y118167D01*
X633600Y118250D01*
X633308Y118500D01*
X633100Y118875D01*
X633017Y119250D01*
Y119709D01*
X633100Y120084D01*
X633308Y120417D01*
X633558Y120584D01*
X633850Y120667D01*
X634183Y120584D01*
X634433Y120417D01*
X634600Y120167D01*
X634683Y119834D01*
X634600Y119542D01*
X634392Y119250D01*
X634142Y119084D01*
X633850Y119042D01*
X633517Y119125D01*
X633267Y119334D01*
X633017Y119709D01*
G01X636233Y146792D02*
X636483Y146917D01*
X636775Y147000D01*
X637108D01*
X637483Y146875D01*
X637775Y146667D01*
X637983Y146417D01*
X638150Y146000D01*
X638192Y145625D01*
X638108Y145250D01*
X637983Y145000D01*
X637733Y144750D01*
X637442Y144583D01*
X637150Y144500D01*
X636858D01*
X636567Y144583D01*
X636317Y144708D01*
X636108Y144875D01*
G01X634967Y145000D02*
X634717Y144708D01*
X634383Y144542D01*
X634008Y144500D01*
X633675Y144542D01*
X633342Y144750D01*
X633133Y145000D01*
X633092Y145250D01*
X633175Y145542D01*
X633467Y145750D01*
X633758Y145833D01*
X634133D01*
G01X633758D02*
X633508Y145958D01*
X633300Y146167D01*
X633217Y146417D01*
X633300Y146667D01*
X633508Y146875D01*
X633883Y147000D01*
X634258Y146958D01*
X634633Y146792D01*
G01X631033Y144500D02*
X630950Y145042D01*
X630825Y145500D01*
X630658Y145917D01*
X630450Y146375D01*
X630117Y147000D01*
X631783D01*
G01X628642Y145542D02*
X628350Y145833D01*
X628100Y146000D01*
X627767Y146083D01*
X627475Y146000D01*
X627267Y145833D01*
X627100Y145583D01*
X627058Y145292D01*
X627100Y145042D01*
X627267Y144792D01*
X627517Y144583D01*
X627808Y144500D01*
X628142Y144583D01*
X628433Y144833D01*
X628600Y145208D01*
X628642Y145625D01*
X628558Y146167D01*
X628433Y146458D01*
X628225Y146750D01*
X627933Y146958D01*
X627642Y147000D01*
X627350Y146917D01*
X627142Y146708D01*
G01X643733Y138959D02*
X643983Y139084D01*
X644275Y139167D01*
X644608D01*
X644983Y139042D01*
X645275Y138834D01*
X645483Y138584D01*
X645650Y138167D01*
X645692Y137792D01*
X645608Y137417D01*
X645483Y137167D01*
X645233Y136917D01*
X644942Y136750D01*
X644650Y136667D01*
X644358D01*
X644067Y136750D01*
X643817Y136875D01*
X643608Y137042D01*
G01X642467Y137167D02*
X642217Y136875D01*
X641883Y136709D01*
X641508Y136667D01*
X641175Y136709D01*
X640842Y136917D01*
X640633Y137167D01*
X640592Y137417D01*
X640675Y137709D01*
X640967Y137917D01*
X641258Y138000D01*
X641633D01*
G01X641258D02*
X641008Y138125D01*
X640800Y138334D01*
X640717Y138584D01*
X640800Y138834D01*
X641008Y139042D01*
X641383Y139167D01*
X641758Y139125D01*
X642133Y138959D01*
G01X638533Y136667D02*
X638450Y137209D01*
X638325Y137667D01*
X638158Y138084D01*
X637950Y138542D01*
X637617Y139167D01*
X639283D01*
G01X636267Y137042D02*
X636017Y136834D01*
X635725Y136709D01*
X635350Y136667D01*
X634975Y136750D01*
X634683Y136917D01*
X634475Y137209D01*
X634433Y137542D01*
X634517Y137875D01*
X634725Y138084D01*
X635017Y138250D01*
X635308Y138292D01*
X635600Y138250D01*
X635975Y138084D01*
X635850Y139167D01*
X634725D01*
G01X636133Y151092D02*
X636383Y151217D01*
X636675Y151300D01*
X637008D01*
X637383Y151175D01*
X637675Y150967D01*
X637883Y150717D01*
X638050Y150300D01*
X638092Y149925D01*
X638008Y149550D01*
X637883Y149300D01*
X637633Y149050D01*
X637342Y148883D01*
X637050Y148800D01*
X636758D01*
X636467Y148883D01*
X636217Y149008D01*
X636008Y149175D01*
G01X634867Y149300D02*
X634617Y149008D01*
X634283Y148842D01*
X633908Y148800D01*
X633575Y148842D01*
X633242Y149050D01*
X633033Y149300D01*
X632992Y149550D01*
X633075Y149842D01*
X633367Y150050D01*
X633658Y150133D01*
X634033D01*
G01X633658D02*
X633408Y150258D01*
X633200Y150467D01*
X633117Y150717D01*
X633200Y150967D01*
X633408Y151175D01*
X633783Y151300D01*
X634158Y151258D01*
X634533Y151092D01*
G01X630933Y148800D02*
X630850Y149342D01*
X630725Y149800D01*
X630558Y150217D01*
X630350Y150675D01*
X630017Y151300D01*
X631683D01*
G01X627250Y148800D02*
Y151300D01*
X628792Y149508D01*
X626708D01*
G01X616292Y122767D02*
X616417Y122517D01*
X616500Y122225D01*
Y121892D01*
X616375Y121517D01*
X616167Y121225D01*
X615917Y121017D01*
X615500Y120850D01*
X615125Y120808D01*
X614750Y120892D01*
X614500Y121017D01*
X614250Y121267D01*
X614083Y121558D01*
X614000Y121850D01*
Y122142D01*
X614083Y122433D01*
X614208Y122683D01*
X614375Y122892D01*
G01X614500Y124033D02*
X614208Y124283D01*
X614042Y124617D01*
X614000Y124992D01*
X614042Y125325D01*
X614250Y125658D01*
X614500Y125867D01*
X614750Y125908D01*
X615042Y125825D01*
X615250Y125533D01*
X615333Y125242D01*
Y124867D01*
G01Y125242D02*
X615458Y125492D01*
X615667Y125700D01*
X615917Y125783D01*
X616167Y125700D01*
X616375Y125492D01*
X616500Y125117D01*
X616458Y124742D01*
X616292Y124367D01*
G01X614000Y127967D02*
X614542Y128050D01*
X615000Y128175D01*
X615417Y128342D01*
X615875Y128550D01*
X616500Y128883D01*
Y127217D01*
G01X616083Y130358D02*
X616333Y130608D01*
X616458Y130900D01*
X616500Y131233D01*
X616417Y131650D01*
X616208Y131942D01*
X615958Y132025D01*
X615708Y131983D01*
X615500Y131817D01*
X615083Y130983D01*
X614792Y130608D01*
X614375Y130358D01*
X614000Y130275D01*
Y132025D01*
G01X620292Y123267D02*
X620417Y123017D01*
X620500Y122725D01*
Y122392D01*
X620375Y122017D01*
X620167Y121725D01*
X619917Y121517D01*
X619500Y121350D01*
X619125Y121308D01*
X618750Y121392D01*
X618500Y121517D01*
X618250Y121767D01*
X618083Y122058D01*
X618000Y122350D01*
Y122642D01*
X618083Y122933D01*
X618208Y123183D01*
X618375Y123392D01*
G01X618500Y124533D02*
X618208Y124783D01*
X618042Y125117D01*
X618000Y125492D01*
X618042Y125825D01*
X618250Y126158D01*
X618500Y126367D01*
X618750Y126408D01*
X619042Y126325D01*
X619250Y126033D01*
X619333Y125742D01*
Y125367D01*
G01Y125742D02*
X619458Y125992D01*
X619667Y126200D01*
X619917Y126283D01*
X620167Y126200D01*
X620375Y125992D01*
X620500Y125617D01*
X620458Y125242D01*
X620292Y124867D01*
G01X618000Y128467D02*
X618542Y128550D01*
X619000Y128675D01*
X619417Y128842D01*
X619875Y129050D01*
X620500Y129383D01*
Y127717D01*
G01X618000Y131650D02*
X620500D01*
X620000Y131150D01*
G01X618000D02*
Y132150D01*
G01X643733Y124459D02*
X643983Y124584D01*
X644275Y124667D01*
X644608D01*
X644983Y124542D01*
X645275Y124334D01*
X645483Y124084D01*
X645650Y123667D01*
X645692Y123292D01*
X645608Y122917D01*
X645483Y122667D01*
X645233Y122417D01*
X644942Y122250D01*
X644650Y122167D01*
X644358D01*
X644067Y122250D01*
X643817Y122375D01*
X643608Y122542D01*
G01X642467Y122667D02*
X642217Y122375D01*
X641883Y122209D01*
X641508Y122167D01*
X641175Y122209D01*
X640842Y122417D01*
X640633Y122667D01*
X640592Y122917D01*
X640675Y123209D01*
X640967Y123417D01*
X641258Y123500D01*
X641633D01*
G01X641258D02*
X641008Y123625D01*
X640800Y123834D01*
X640717Y124084D01*
X640800Y124334D01*
X641008Y124542D01*
X641383Y124667D01*
X641758Y124625D01*
X642133Y124459D01*
G01X639158Y122459D02*
X638867Y122250D01*
X638533Y122167D01*
X638200Y122250D01*
X637908Y122500D01*
X637700Y122875D01*
X637617Y123250D01*
Y123709D01*
X637700Y124084D01*
X637908Y124417D01*
X638158Y124584D01*
X638450Y124667D01*
X638783Y124584D01*
X639033Y124417D01*
X639200Y124167D01*
X639283Y123834D01*
X639200Y123542D01*
X638992Y123250D01*
X638742Y123084D01*
X638450Y123042D01*
X638117Y123125D01*
X637867Y123334D01*
X637617Y123709D01*
G01X636142Y123209D02*
X635850Y123500D01*
X635600Y123667D01*
X635267Y123750D01*
X634975Y123667D01*
X634767Y123500D01*
X634600Y123250D01*
X634558Y122959D01*
X634600Y122709D01*
X634767Y122459D01*
X635017Y122250D01*
X635308Y122167D01*
X635642Y122250D01*
X635933Y122500D01*
X636100Y122875D01*
X636142Y123292D01*
X636058Y123834D01*
X635933Y124125D01*
X635725Y124417D01*
X635433Y124625D01*
X635142Y124667D01*
X634850Y124584D01*
X634642Y124375D01*
G01X643733Y128459D02*
X643983Y128584D01*
X644275Y128667D01*
X644608D01*
X644983Y128542D01*
X645275Y128334D01*
X645483Y128084D01*
X645650Y127667D01*
X645692Y127292D01*
X645608Y126917D01*
X645483Y126667D01*
X645233Y126417D01*
X644942Y126250D01*
X644650Y126167D01*
X644358D01*
X644067Y126250D01*
X643817Y126375D01*
X643608Y126542D01*
G01X642467Y126667D02*
X642217Y126375D01*
X641883Y126209D01*
X641508Y126167D01*
X641175Y126209D01*
X640842Y126417D01*
X640633Y126667D01*
X640592Y126917D01*
X640675Y127209D01*
X640967Y127417D01*
X641258Y127500D01*
X641633D01*
G01X641258D02*
X641008Y127625D01*
X640800Y127834D01*
X640717Y128084D01*
X640800Y128334D01*
X641008Y128542D01*
X641383Y128667D01*
X641758Y128625D01*
X642133Y128459D01*
G01X638533Y126167D02*
X638450Y126709D01*
X638325Y127167D01*
X638158Y127584D01*
X637950Y128042D01*
X637617Y128667D01*
X639283D01*
G01X636267Y126667D02*
X636017Y126375D01*
X635683Y126209D01*
X635308Y126167D01*
X634975Y126209D01*
X634642Y126417D01*
X634433Y126667D01*
X634392Y126917D01*
X634475Y127209D01*
X634767Y127417D01*
X635058Y127500D01*
X635433D01*
G01X635058D02*
X634808Y127625D01*
X634600Y127834D01*
X634517Y128084D01*
X634600Y128334D01*
X634808Y128542D01*
X635183Y128667D01*
X635558Y128625D01*
X635933Y128459D01*
G01X619733Y172292D02*
X619983Y172417D01*
X620275Y172500D01*
X620608D01*
X620983Y172375D01*
X621275Y172167D01*
X621483Y171917D01*
X621650Y171500D01*
X621692Y171125D01*
X621608Y170750D01*
X621483Y170500D01*
X621233Y170250D01*
X620942Y170083D01*
X620650Y170000D01*
X620358D01*
X620067Y170083D01*
X619817Y170208D01*
X619608Y170375D01*
G01X617050Y170000D02*
Y172500D01*
X618592Y170708D01*
X616508D01*
G01X614450Y170000D02*
X614158Y170042D01*
X613825Y170167D01*
X613617Y170375D01*
X613533Y170667D01*
X613617Y170958D01*
X613867Y171208D01*
X614242Y171333D01*
X614658D01*
X614908Y171417D01*
X615117Y171625D01*
X615200Y171917D01*
X615075Y172208D01*
X614783Y172417D01*
X614450Y172500D01*
X614117Y172417D01*
X613825Y172208D01*
X613700Y171917D01*
X613783Y171625D01*
X613992Y171417D01*
X614242Y171333D01*
X614658D01*
X615033Y171208D01*
X615283Y170958D01*
X615367Y170667D01*
X615283Y170375D01*
X615075Y170167D01*
X614742Y170042D01*
X614450Y170000D01*
G01X610850D02*
Y172500D01*
X612392Y170708D01*
X610308D01*
G01X625650Y163500D02*
Y161000D01*
G01X626608Y163500D02*
X624692D01*
G01X623383Y161000D02*
Y163500D01*
X622383D01*
X622050Y163375D01*
X621800Y163083D01*
X621717Y162750D01*
X621800Y162417D01*
X622008Y162167D01*
X622383Y162042D01*
X623383D01*
G01X620158Y161292D02*
X619867Y161083D01*
X619533Y161000D01*
X619200Y161083D01*
X618908Y161333D01*
X618700Y161708D01*
X618617Y162083D01*
Y162542D01*
X618700Y162917D01*
X618908Y163250D01*
X619158Y163417D01*
X619450Y163500D01*
X619783Y163417D01*
X620033Y163250D01*
X620200Y163000D01*
X620283Y162667D01*
X620200Y162375D01*
X619992Y162083D01*
X619742Y161917D01*
X619450Y161875D01*
X619117Y161958D01*
X618867Y162167D01*
X618617Y162542D01*
G01X616433Y161000D02*
X616350Y161542D01*
X616225Y162000D01*
X616058Y162417D01*
X615850Y162875D01*
X615517Y163500D01*
X617183D01*
G01X609011Y176655D02*
Y174155D01*
G01X609969Y176655D02*
X608053D01*
G01X606744Y174155D02*
Y176655D01*
X605744D01*
X605411Y176530D01*
X605161Y176238D01*
X605078Y175905D01*
X605161Y175572D01*
X605369Y175322D01*
X605744Y175197D01*
X606744D01*
G01X603519Y174447D02*
X603228Y174238D01*
X602894Y174155D01*
X602561Y174238D01*
X602269Y174488D01*
X602061Y174863D01*
X601978Y175238D01*
Y175697D01*
X602061Y176072D01*
X602269Y176405D01*
X602519Y176572D01*
X602811Y176655D01*
X603144Y176572D01*
X603394Y176405D01*
X603561Y176155D01*
X603644Y175822D01*
X603561Y175530D01*
X603353Y175238D01*
X603103Y175072D01*
X602811Y175030D01*
X602478Y175113D01*
X602228Y175322D01*
X601978Y175697D01*
G01X599711Y176655D02*
X600044Y176572D01*
X600294Y176363D01*
X600461Y176113D01*
X600586Y175780D01*
X600628Y175405D01*
X600586Y175030D01*
X600461Y174697D01*
X600294Y174447D01*
X600044Y174238D01*
X599711Y174155D01*
X599378Y174238D01*
X599128Y174447D01*
X598961Y174697D01*
X598836Y175030D01*
X598794Y175405D01*
X598836Y175780D01*
X598961Y176113D01*
X599128Y176363D01*
X599378Y176572D01*
X599711Y176655D01*
G01X637650Y163500D02*
Y161000D01*
G01X638608Y163500D02*
X636692D01*
G01X635383Y161000D02*
Y163500D01*
X634383D01*
X634050Y163375D01*
X633800Y163083D01*
X633717Y162750D01*
X633800Y162417D01*
X634008Y162167D01*
X634383Y162042D01*
X635383D01*
G01X631450Y161000D02*
X631158Y161042D01*
X630825Y161167D01*
X630617Y161375D01*
X630533Y161667D01*
X630617Y161958D01*
X630867Y162208D01*
X631242Y162333D01*
X631658D01*
X631908Y162417D01*
X632117Y162625D01*
X632200Y162917D01*
X632075Y163208D01*
X631783Y163417D01*
X631450Y163500D01*
X631117Y163417D01*
X630825Y163208D01*
X630700Y162917D01*
X630783Y162625D01*
X630992Y162417D01*
X631242Y162333D01*
X631658D01*
X632033Y162208D01*
X632283Y161958D01*
X632367Y161667D01*
X632283Y161375D01*
X632075Y161167D01*
X631742Y161042D01*
X631450Y161000D01*
G01X628350D02*
Y163500D01*
X628850Y163000D01*
G01Y161000D02*
X627850D01*
G01X648200Y159500D02*
Y157000D01*
G01X649158Y159500D02*
X647242D01*
G01X645933Y157000D02*
Y159500D01*
X644933D01*
X644600Y159375D01*
X644350Y159083D01*
X644267Y158750D01*
X644350Y158417D01*
X644558Y158167D01*
X644933Y158042D01*
X645933D01*
G01X642000Y157000D02*
Y159500D01*
X642500Y159000D01*
G01Y157000D02*
X641500D01*
G01X638400D02*
Y159500D01*
X639942Y157708D01*
X637858D01*
G01X635800Y157000D02*
Y159500D01*
X636300Y159000D01*
G01Y157000D02*
X635300D01*
G01X630233Y191792D02*
X630483Y191917D01*
X630775Y192000D01*
X631108D01*
X631483Y191875D01*
X631775Y191667D01*
X631983Y191417D01*
X632150Y191000D01*
X632192Y190625D01*
X632108Y190250D01*
X631983Y190000D01*
X631733Y189750D01*
X631442Y189583D01*
X631150Y189500D01*
X630858D01*
X630567Y189583D01*
X630317Y189708D01*
X630108Y189875D01*
G01X627550Y189500D02*
Y192000D01*
X629092Y190208D01*
X627008D01*
G01X625742Y190542D02*
X625450Y190833D01*
X625200Y191000D01*
X624867Y191083D01*
X624575Y191000D01*
X624367Y190833D01*
X624200Y190583D01*
X624158Y190292D01*
X624200Y190042D01*
X624367Y189792D01*
X624617Y189583D01*
X624908Y189500D01*
X625242Y189583D01*
X625533Y189833D01*
X625700Y190208D01*
X625742Y190625D01*
X625658Y191167D01*
X625533Y191458D01*
X625325Y191750D01*
X625033Y191958D01*
X624742Y192000D01*
X624450Y191917D01*
X624242Y191708D01*
G01X622767Y190000D02*
X622517Y189708D01*
X622183Y189542D01*
X621808Y189500D01*
X621475Y189542D01*
X621142Y189750D01*
X620933Y190000D01*
X620892Y190250D01*
X620975Y190542D01*
X621267Y190750D01*
X621558Y190833D01*
X621933D01*
G01X621558D02*
X621308Y190958D01*
X621100Y191167D01*
X621017Y191417D01*
X621100Y191667D01*
X621308Y191875D01*
X621683Y192000D01*
X622058Y191958D01*
X622433Y191792D01*
G01X619792Y182767D02*
X619917Y182517D01*
X620000Y182225D01*
Y181892D01*
X619875Y181517D01*
X619667Y181225D01*
X619417Y181017D01*
X619000Y180850D01*
X618625Y180808D01*
X618250Y180892D01*
X618000Y181017D01*
X617750Y181267D01*
X617583Y181558D01*
X617500Y181850D01*
Y182142D01*
X617583Y182433D01*
X617708Y182683D01*
X617875Y182892D01*
G01X617500Y185450D02*
X620000D01*
X618208Y183908D01*
Y185992D01*
G01X617875Y187133D02*
X617667Y187383D01*
X617542Y187675D01*
X617500Y188050D01*
X617583Y188425D01*
X617750Y188717D01*
X618042Y188925D01*
X618375Y188967D01*
X618708Y188883D01*
X618917Y188675D01*
X619083Y188383D01*
X619125Y188092D01*
X619083Y187800D01*
X618917Y187425D01*
X620000Y187550D01*
Y188675D01*
G01X618542Y190358D02*
X618833Y190650D01*
X619000Y190900D01*
X619083Y191233D01*
X619000Y191525D01*
X618833Y191733D01*
X618583Y191900D01*
X618292Y191942D01*
X618042Y191900D01*
X617792Y191733D01*
X617583Y191483D01*
X617500Y191192D01*
X617583Y190858D01*
X617833Y190567D01*
X618208Y190400D01*
X618625Y190358D01*
X619167Y190442D01*
X619458Y190567D01*
X619750Y190775D01*
X619958Y191067D01*
X620000Y191358D01*
X619917Y191650D01*
X619708Y191858D01*
G01X634233Y180792D02*
X634483Y180917D01*
X634775Y181000D01*
X635108D01*
X635483Y180875D01*
X635775Y180667D01*
X635983Y180417D01*
X636150Y180000D01*
X636192Y179625D01*
X636108Y179250D01*
X635983Y179000D01*
X635733Y178750D01*
X635442Y178583D01*
X635150Y178500D01*
X634858D01*
X634567Y178583D01*
X634317Y178708D01*
X634108Y178875D01*
G01X631550Y178500D02*
Y181000D01*
X633092Y179208D01*
X631008D01*
G01X629867Y178875D02*
X629617Y178667D01*
X629325Y178542D01*
X628950Y178500D01*
X628575Y178583D01*
X628283Y178750D01*
X628075Y179042D01*
X628033Y179375D01*
X628117Y179708D01*
X628325Y179917D01*
X628617Y180083D01*
X628908Y180125D01*
X629200Y180083D01*
X629575Y179917D01*
X629450Y181000D01*
X628325D01*
G01X626642Y180583D02*
X626392Y180833D01*
X626100Y180958D01*
X625767Y181000D01*
X625350Y180917D01*
X625058Y180708D01*
X624975Y180458D01*
X625017Y180208D01*
X625183Y180000D01*
X626017Y179583D01*
X626392Y179292D01*
X626642Y178875D01*
X626725Y178500D01*
X624975D01*
G01X602500Y202017D02*
X605000D01*
Y203058D01*
X604875Y203392D01*
X604708Y203600D01*
X604375Y203683D01*
X604042Y203600D01*
X603833Y203350D01*
X603708Y203058D01*
Y202017D01*
G01Y203058D02*
X602500Y203683D01*
G01X604583Y205158D02*
X604833Y205408D01*
X604958Y205700D01*
X605000Y206033D01*
X604917Y206450D01*
X604708Y206742D01*
X604458Y206825D01*
X604208Y206783D01*
X604000Y206617D01*
X603583Y205783D01*
X603292Y205408D01*
X602875Y205158D01*
X602500Y205075D01*
Y206825D01*
G01X605000Y209050D02*
X604917Y208717D01*
X604708Y208467D01*
X604458Y208300D01*
X604125Y208175D01*
X603750Y208133D01*
X603375Y208175D01*
X603042Y208300D01*
X602792Y208467D01*
X602583Y208717D01*
X602500Y209050D01*
X602583Y209383D01*
X602792Y209633D01*
X603042Y209800D01*
X603375Y209925D01*
X603750Y209967D01*
X604125Y209925D01*
X604458Y209800D01*
X604708Y209633D01*
X604917Y209383D01*
X605000Y209050D01*
G01X602500Y212650D02*
X605000D01*
X603208Y211108D01*
Y213192D01*
G01X599000Y202017D02*
X601500D01*
Y203058D01*
X601375Y203392D01*
X601208Y203600D01*
X600875Y203683D01*
X600542Y203600D01*
X600333Y203350D01*
X600208Y203058D01*
Y202017D01*
G01Y203058D02*
X599000Y203683D01*
G01X601083Y205158D02*
X601333Y205408D01*
X601458Y205700D01*
X601500Y206033D01*
X601417Y206450D01*
X601208Y206742D01*
X600958Y206825D01*
X600708Y206783D01*
X600500Y206617D01*
X600083Y205783D01*
X599792Y205408D01*
X599375Y205158D01*
X599000Y205075D01*
Y206825D01*
G01X601500Y209050D02*
X601417Y208717D01*
X601208Y208467D01*
X600958Y208300D01*
X600625Y208175D01*
X600250Y208133D01*
X599875Y208175D01*
X599542Y208300D01*
X599292Y208467D01*
X599083Y208717D01*
X599000Y209050D01*
X599083Y209383D01*
X599292Y209633D01*
X599542Y209800D01*
X599875Y209925D01*
X600250Y209967D01*
X600625Y209925D01*
X600958Y209800D01*
X601208Y209633D01*
X601417Y209383D01*
X601500Y209050D01*
G01X599500Y211233D02*
X599208Y211483D01*
X599042Y211817D01*
X599000Y212192D01*
X599042Y212525D01*
X599250Y212858D01*
X599500Y213067D01*
X599750Y213108D01*
X600042Y213025D01*
X600250Y212733D01*
X600333Y212442D01*
Y212067D01*
G01Y212442D02*
X600458Y212692D01*
X600667Y212900D01*
X600917Y212983D01*
X601167Y212900D01*
X601375Y212692D01*
X601500Y212317D01*
X601458Y211942D01*
X601292Y211567D01*
G01X634000Y208700D02*
X638000D01*
Y201300D01*
G01X595500Y202017D02*
X598000D01*
Y203058D01*
X597875Y203392D01*
X597708Y203600D01*
X597375Y203683D01*
X597042Y203600D01*
X596833Y203350D01*
X596708Y203058D01*
Y202017D01*
G01Y203058D02*
X595500Y203683D01*
G01X597583Y205158D02*
X597833Y205408D01*
X597958Y205700D01*
X598000Y206033D01*
X597917Y206450D01*
X597708Y206742D01*
X597458Y206825D01*
X597208Y206783D01*
X597000Y206617D01*
X596583Y205783D01*
X596292Y205408D01*
X595875Y205158D01*
X595500Y205075D01*
Y206825D01*
G01X598000Y209050D02*
X597917Y208717D01*
X597708Y208467D01*
X597458Y208300D01*
X597125Y208175D01*
X596750Y208133D01*
X596375Y208175D01*
X596042Y208300D01*
X595792Y208467D01*
X595583Y208717D01*
X595500Y209050D01*
X595583Y209383D01*
X595792Y209633D01*
X596042Y209800D01*
X596375Y209925D01*
X596750Y209967D01*
X597125Y209925D01*
X597458Y209800D01*
X597708Y209633D01*
X597917Y209383D01*
X598000Y209050D01*
G01Y212150D02*
X597917Y211817D01*
X597708Y211567D01*
X597458Y211400D01*
X597125Y211275D01*
X596750Y211233D01*
X596375Y211275D01*
X596042Y211400D01*
X595792Y211567D01*
X595583Y211817D01*
X595500Y212150D01*
X595583Y212483D01*
X595792Y212733D01*
X596042Y212900D01*
X596375Y213025D01*
X596750Y213067D01*
X597125Y213025D01*
X597458Y212900D01*
X597708Y212733D01*
X597917Y212483D01*
X598000Y212150D01*
G01X630000Y208700D02*
X634000D01*
Y201300D01*
G01X610500Y202017D02*
X613000D01*
Y203058D01*
X612875Y203392D01*
X612708Y203600D01*
X612375Y203683D01*
X612042Y203600D01*
X611833Y203350D01*
X611708Y203058D01*
Y202017D01*
G01Y203058D02*
X610500Y203683D01*
G01Y205950D02*
X613000D01*
X612500Y205450D01*
G01X610500D02*
Y206450D01*
G01X610792Y208342D02*
X610583Y208633D01*
X610500Y208967D01*
X610583Y209300D01*
X610833Y209592D01*
X611208Y209800D01*
X611583Y209883D01*
X612042D01*
X612417Y209800D01*
X612750Y209592D01*
X612917Y209342D01*
X613000Y209050D01*
X612917Y208717D01*
X612750Y208467D01*
X612500Y208300D01*
X612167Y208217D01*
X611875Y208300D01*
X611583Y208508D01*
X611417Y208758D01*
X611375Y209050D01*
X611458Y209383D01*
X611667Y209633D01*
X612042Y209883D01*
G01X610500Y212067D02*
X611042Y212150D01*
X611500Y212275D01*
X611917Y212442D01*
X612375Y212650D01*
X613000Y212983D01*
Y211317D01*
G01X614500Y202017D02*
X617000D01*
Y203058D01*
X616875Y203392D01*
X616708Y203600D01*
X616375Y203683D01*
X616042Y203600D01*
X615833Y203350D01*
X615708Y203058D01*
Y202017D01*
G01Y203058D02*
X614500Y203683D01*
G01Y205950D02*
X617000D01*
X616500Y205450D01*
G01X614500D02*
Y206450D01*
G01X614792Y208342D02*
X614583Y208633D01*
X614500Y208967D01*
X614583Y209300D01*
X614833Y209592D01*
X615208Y209800D01*
X615583Y209883D01*
X616042D01*
X616417Y209800D01*
X616750Y209592D01*
X616917Y209342D01*
X617000Y209050D01*
X616917Y208717D01*
X616750Y208467D01*
X616500Y208300D01*
X616167Y208217D01*
X615875Y208300D01*
X615583Y208508D01*
X615417Y208758D01*
X615375Y209050D01*
X615458Y209383D01*
X615667Y209633D01*
X616042Y209883D01*
G01X615542Y211358D02*
X615833Y211650D01*
X616000Y211900D01*
X616083Y212233D01*
X616000Y212525D01*
X615833Y212733D01*
X615583Y212900D01*
X615292Y212942D01*
X615042Y212900D01*
X614792Y212733D01*
X614583Y212483D01*
X614500Y212192D01*
X614583Y211858D01*
X614833Y211567D01*
X615208Y211400D01*
X615625Y211358D01*
X616167Y211442D01*
X616458Y211567D01*
X616750Y211775D01*
X616958Y212067D01*
X617000Y212358D01*
X616917Y212650D01*
X616708Y212858D01*
G01X606500Y202017D02*
X609000D01*
Y203058D01*
X608875Y203392D01*
X608708Y203600D01*
X608375Y203683D01*
X608042Y203600D01*
X607833Y203350D01*
X607708Y203058D01*
Y202017D01*
G01Y203058D02*
X606500Y203683D01*
G01Y205950D02*
X609000D01*
X608500Y205450D01*
G01X606500D02*
Y206450D01*
G01X606792Y208342D02*
X606583Y208633D01*
X606500Y208967D01*
X606583Y209300D01*
X606833Y209592D01*
X607208Y209800D01*
X607583Y209883D01*
X608042D01*
X608417Y209800D01*
X608750Y209592D01*
X608917Y209342D01*
X609000Y209050D01*
X608917Y208717D01*
X608750Y208467D01*
X608500Y208300D01*
X608167Y208217D01*
X607875Y208300D01*
X607583Y208508D01*
X607417Y208758D01*
X607375Y209050D01*
X607458Y209383D01*
X607667Y209633D01*
X608042Y209883D01*
G01X606875Y211233D02*
X606667Y211483D01*
X606542Y211775D01*
X606500Y212150D01*
X606583Y212525D01*
X606750Y212817D01*
X607042Y213025D01*
X607375Y213067D01*
X607708Y212983D01*
X607917Y212775D01*
X608083Y212483D01*
X608125Y212192D01*
X608083Y211900D01*
X607917Y211525D01*
X609000Y211650D01*
Y212775D01*
G01X586000Y202017D02*
X588500D01*
Y203058D01*
X588375Y203392D01*
X588208Y203600D01*
X587875Y203683D01*
X587542Y203600D01*
X587333Y203350D01*
X587208Y203058D01*
Y202017D01*
G01Y203058D02*
X586000Y203683D01*
G01Y205950D02*
X588500D01*
X588000Y205450D01*
G01X586000D02*
Y206450D01*
G01X586292Y208342D02*
X586083Y208633D01*
X586000Y208967D01*
X586083Y209300D01*
X586333Y209592D01*
X586708Y209800D01*
X587083Y209883D01*
X587542D01*
X587917Y209800D01*
X588250Y209592D01*
X588417Y209342D01*
X588500Y209050D01*
X588417Y208717D01*
X588250Y208467D01*
X588000Y208300D01*
X587667Y208217D01*
X587375Y208300D01*
X587083Y208508D01*
X586917Y208758D01*
X586875Y209050D01*
X586958Y209383D01*
X587167Y209633D01*
X587542Y209883D01*
G01X586000Y212650D02*
X588500D01*
X586708Y211108D01*
Y213192D01*
G01X622000Y208700D02*
X626000D01*
Y201300D01*
G01X591500Y202017D02*
X594000D01*
Y203058D01*
X593875Y203392D01*
X593708Y203600D01*
X593375Y203683D01*
X593042Y203600D01*
X592833Y203350D01*
X592708Y203058D01*
Y202017D01*
G01Y203058D02*
X591500Y203683D01*
G01Y205950D02*
X594000D01*
X593500Y205450D01*
G01X591500D02*
Y206450D01*
G01X591792Y208342D02*
X591583Y208633D01*
X591500Y208967D01*
X591583Y209300D01*
X591833Y209592D01*
X592208Y209800D01*
X592583Y209883D01*
X593042D01*
X593417Y209800D01*
X593750Y209592D01*
X593917Y209342D01*
X594000Y209050D01*
X593917Y208717D01*
X593750Y208467D01*
X593500Y208300D01*
X593167Y208217D01*
X592875Y208300D01*
X592583Y208508D01*
X592417Y208758D01*
X592375Y209050D01*
X592458Y209383D01*
X592667Y209633D01*
X593042Y209883D01*
G01X593583Y211358D02*
X593833Y211608D01*
X593958Y211900D01*
X594000Y212233D01*
X593917Y212650D01*
X593708Y212942D01*
X593458Y213025D01*
X593208Y212983D01*
X593000Y212817D01*
X592583Y211983D01*
X592292Y211608D01*
X591875Y211358D01*
X591500Y211275D01*
Y213025D01*
G01X626000Y208700D02*
X630000D01*
Y201300D01*
G01X618500Y202017D02*
X621000D01*
Y203058D01*
X620875Y203392D01*
X620708Y203600D01*
X620375Y203683D01*
X620042Y203600D01*
X619833Y203350D01*
X619708Y203058D01*
Y202017D01*
G01Y203058D02*
X618500Y203683D01*
G01X620583Y205158D02*
X620833Y205408D01*
X620958Y205700D01*
X621000Y206033D01*
X620917Y206450D01*
X620708Y206742D01*
X620458Y206825D01*
X620208Y206783D01*
X620000Y206617D01*
X619583Y205783D01*
X619292Y205408D01*
X618875Y205158D01*
X618500Y205075D01*
Y206825D01*
G01X619542Y208258D02*
X619833Y208550D01*
X620000Y208800D01*
X620083Y209133D01*
X620000Y209425D01*
X619833Y209633D01*
X619583Y209800D01*
X619292Y209842D01*
X619042Y209800D01*
X618792Y209633D01*
X618583Y209383D01*
X618500Y209092D01*
X618583Y208758D01*
X618833Y208467D01*
X619208Y208300D01*
X619625Y208258D01*
X620167Y208342D01*
X620458Y208467D01*
X620750Y208675D01*
X620958Y208967D01*
X621000Y209258D01*
X620917Y209550D01*
X620708Y209758D01*
G01X618500Y212150D02*
X618542Y212442D01*
X618667Y212775D01*
X618875Y212983D01*
X619167Y213067D01*
X619458Y212983D01*
X619708Y212733D01*
X619833Y212358D01*
Y211942D01*
X619917Y211692D01*
X620125Y211483D01*
X620417Y211400D01*
X620708Y211525D01*
X620917Y211817D01*
X621000Y212150D01*
X620917Y212483D01*
X620708Y212775D01*
X620417Y212900D01*
X620125Y212817D01*
X619917Y212608D01*
X619833Y212358D01*
Y211942D01*
X619708Y211567D01*
X619458Y211317D01*
X619167Y211233D01*
X618875Y211317D01*
X618667Y211525D01*
X618542Y211858D01*
X618500Y212150D01*
G01X633633Y223692D02*
X633883Y223817D01*
X634175Y223900D01*
X634508D01*
X634883Y223775D01*
X635175Y223567D01*
X635383Y223317D01*
X635550Y222900D01*
X635592Y222525D01*
X635508Y222150D01*
X635383Y221900D01*
X635133Y221650D01*
X634842Y221483D01*
X634550Y221400D01*
X634258D01*
X633967Y221483D01*
X633717Y221608D01*
X633508Y221775D01*
G01X632367Y221900D02*
X632117Y221608D01*
X631783Y221442D01*
X631408Y221400D01*
X631075Y221442D01*
X630742Y221650D01*
X630533Y221900D01*
X630492Y222150D01*
X630575Y222442D01*
X630867Y222650D01*
X631158Y222733D01*
X631533D01*
G01X631158D02*
X630908Y222858D01*
X630700Y223067D01*
X630617Y223317D01*
X630700Y223567D01*
X630908Y223775D01*
X631283Y223900D01*
X631658Y223858D01*
X632033Y223692D01*
G01X628433Y221400D02*
X628350Y221942D01*
X628225Y222400D01*
X628058Y222817D01*
X627850Y223275D01*
X627517Y223900D01*
X629183D01*
G01X625250D02*
X625583Y223817D01*
X625833Y223608D01*
X626000Y223358D01*
X626125Y223025D01*
X626167Y222650D01*
X626125Y222275D01*
X626000Y221942D01*
X625833Y221692D01*
X625583Y221483D01*
X625250Y221400D01*
X624917Y221483D01*
X624667Y221692D01*
X624500Y221942D01*
X624375Y222275D01*
X624333Y222650D01*
X624375Y223025D01*
X624500Y223358D01*
X624667Y223608D01*
X624917Y223817D01*
X625250Y223900D01*
G01X619259Y219244D02*
X619509Y219369D01*
X619801Y219452D01*
X620134D01*
X620509Y219327D01*
X620801Y219119D01*
X621009Y218869D01*
X621176Y218452D01*
X621218Y218077D01*
X621134Y217702D01*
X621009Y217452D01*
X620759Y217202D01*
X620468Y217035D01*
X620176Y216952D01*
X619884D01*
X619593Y217035D01*
X619343Y217160D01*
X619134Y217327D01*
G01X617993Y217452D02*
X617743Y217160D01*
X617409Y216994D01*
X617034Y216952D01*
X616701Y216994D01*
X616368Y217202D01*
X616159Y217452D01*
X616118Y217702D01*
X616201Y217994D01*
X616493Y218202D01*
X616784Y218285D01*
X617159D01*
G01X616784D02*
X616534Y218410D01*
X616326Y218619D01*
X616243Y218869D01*
X616326Y219119D01*
X616534Y219327D01*
X616909Y219452D01*
X617284Y219410D01*
X617659Y219244D01*
G01X614768Y217994D02*
X614476Y218285D01*
X614226Y218452D01*
X613893Y218535D01*
X613601Y218452D01*
X613393Y218285D01*
X613226Y218035D01*
X613184Y217744D01*
X613226Y217494D01*
X613393Y217244D01*
X613643Y217035D01*
X613934Y216952D01*
X614268Y217035D01*
X614559Y217285D01*
X614726Y217660D01*
X614768Y218077D01*
X614684Y218619D01*
X614559Y218910D01*
X614351Y219202D01*
X614059Y219410D01*
X613768Y219452D01*
X613476Y219369D01*
X613268Y219160D01*
G01X611668Y219035D02*
X611418Y219285D01*
X611126Y219410D01*
X610793Y219452D01*
X610376Y219369D01*
X610084Y219160D01*
X610001Y218910D01*
X610043Y218660D01*
X610209Y218452D01*
X611043Y218035D01*
X611418Y217744D01*
X611668Y217327D01*
X611751Y216952D01*
X610001D01*
G01X604959Y219244D02*
X605209Y219369D01*
X605501Y219452D01*
X605834D01*
X606209Y219327D01*
X606501Y219119D01*
X606709Y218869D01*
X606876Y218452D01*
X606918Y218077D01*
X606834Y217702D01*
X606709Y217452D01*
X606459Y217202D01*
X606168Y217035D01*
X605876Y216952D01*
X605584D01*
X605293Y217035D01*
X605043Y217160D01*
X604834Y217327D01*
G01X603693Y217452D02*
X603443Y217160D01*
X603109Y216994D01*
X602734Y216952D01*
X602401Y216994D01*
X602068Y217202D01*
X601859Y217452D01*
X601818Y217702D01*
X601901Y217994D01*
X602193Y218202D01*
X602484Y218285D01*
X602859D01*
G01X602484D02*
X602234Y218410D01*
X602026Y218619D01*
X601943Y218869D01*
X602026Y219119D01*
X602234Y219327D01*
X602609Y219452D01*
X602984Y219410D01*
X603359Y219244D01*
G01X600593Y217327D02*
X600343Y217119D01*
X600051Y216994D01*
X599676Y216952D01*
X599301Y217035D01*
X599009Y217202D01*
X598801Y217494D01*
X598759Y217827D01*
X598843Y218160D01*
X599051Y218369D01*
X599343Y218535D01*
X599634Y218577D01*
X599926Y218535D01*
X600301Y218369D01*
X600176Y219452D01*
X599051D01*
G01X596576Y216952D02*
X596284Y216994D01*
X595951Y217119D01*
X595743Y217327D01*
X595659Y217619D01*
X595743Y217910D01*
X595993Y218160D01*
X596368Y218285D01*
X596784D01*
X597034Y218369D01*
X597243Y218577D01*
X597326Y218869D01*
X597201Y219160D01*
X596909Y219369D01*
X596576Y219452D01*
X596243Y219369D01*
X595951Y219160D01*
X595826Y218869D01*
X595909Y218577D01*
X596118Y218369D01*
X596368Y218285D01*
X596784D01*
X597159Y218160D01*
X597409Y217910D01*
X597493Y217619D01*
X597409Y217327D01*
X597201Y217119D01*
X596868Y216994D01*
X596576Y216952D01*
G01X633733Y227792D02*
X633983Y227917D01*
X634275Y228000D01*
X634608D01*
X634983Y227875D01*
X635275Y227667D01*
X635483Y227417D01*
X635650Y227000D01*
X635692Y226625D01*
X635608Y226250D01*
X635483Y226000D01*
X635233Y225750D01*
X634942Y225583D01*
X634650Y225500D01*
X634358D01*
X634067Y225583D01*
X633817Y225708D01*
X633608Y225875D01*
G01X632467Y226000D02*
X632217Y225708D01*
X631883Y225542D01*
X631508Y225500D01*
X631175Y225542D01*
X630842Y225750D01*
X630633Y226000D01*
X630592Y226250D01*
X630675Y226542D01*
X630967Y226750D01*
X631258Y226833D01*
X631633D01*
G01X631258D02*
X631008Y226958D01*
X630800Y227167D01*
X630717Y227417D01*
X630800Y227667D01*
X631008Y227875D01*
X631383Y228000D01*
X631758Y227958D01*
X632133Y227792D01*
G01X629242Y226542D02*
X628950Y226833D01*
X628700Y227000D01*
X628367Y227083D01*
X628075Y227000D01*
X627867Y226833D01*
X627700Y226583D01*
X627658Y226292D01*
X627700Y226042D01*
X627867Y225792D01*
X628117Y225583D01*
X628408Y225500D01*
X628742Y225583D01*
X629033Y225833D01*
X629200Y226208D01*
X629242Y226625D01*
X629158Y227167D01*
X629033Y227458D01*
X628825Y227750D01*
X628533Y227958D01*
X628242Y228000D01*
X627950Y227917D01*
X627742Y227708D01*
G01X625350Y225500D02*
X625058Y225542D01*
X624725Y225667D01*
X624517Y225875D01*
X624433Y226167D01*
X624517Y226458D01*
X624767Y226708D01*
X625142Y226833D01*
X625558D01*
X625808Y226917D01*
X626017Y227125D01*
X626100Y227417D01*
X625975Y227708D01*
X625683Y227917D01*
X625350Y228000D01*
X625017Y227917D01*
X624725Y227708D01*
X624600Y227417D01*
X624683Y227125D01*
X624892Y226917D01*
X625142Y226833D01*
X625558D01*
X625933Y226708D01*
X626183Y226458D01*
X626267Y226167D01*
X626183Y225875D01*
X625975Y225667D01*
X625642Y225542D01*
X625350Y225500D01*
G01X619759Y227744D02*
X620009Y227869D01*
X620301Y227952D01*
X620634D01*
X621009Y227827D01*
X621301Y227619D01*
X621509Y227369D01*
X621676Y226952D01*
X621718Y226577D01*
X621634Y226202D01*
X621509Y225952D01*
X621259Y225702D01*
X620968Y225535D01*
X620676Y225452D01*
X620384D01*
X620093Y225535D01*
X619843Y225660D01*
X619634Y225827D01*
G01X618493Y225952D02*
X618243Y225660D01*
X617909Y225494D01*
X617534Y225452D01*
X617201Y225494D01*
X616868Y225702D01*
X616659Y225952D01*
X616618Y226202D01*
X616701Y226494D01*
X616993Y226702D01*
X617284Y226785D01*
X617659D01*
G01X617284D02*
X617034Y226910D01*
X616826Y227119D01*
X616743Y227369D01*
X616826Y227619D01*
X617034Y227827D01*
X617409Y227952D01*
X617784Y227910D01*
X618159Y227744D01*
G01X615268Y226494D02*
X614976Y226785D01*
X614726Y226952D01*
X614393Y227035D01*
X614101Y226952D01*
X613893Y226785D01*
X613726Y226535D01*
X613684Y226244D01*
X613726Y225994D01*
X613893Y225744D01*
X614143Y225535D01*
X614434Y225452D01*
X614768Y225535D01*
X615059Y225785D01*
X615226Y226160D01*
X615268Y226577D01*
X615184Y227119D01*
X615059Y227410D01*
X614851Y227702D01*
X614559Y227910D01*
X614268Y227952D01*
X613976Y227869D01*
X613768Y227660D01*
G01X611376Y227952D02*
X611709Y227869D01*
X611959Y227660D01*
X612126Y227410D01*
X612251Y227077D01*
X612293Y226702D01*
X612251Y226327D01*
X612126Y225994D01*
X611959Y225744D01*
X611709Y225535D01*
X611376Y225452D01*
X611043Y225535D01*
X610793Y225744D01*
X610626Y225994D01*
X610501Y226327D01*
X610459Y226702D01*
X610501Y227077D01*
X610626Y227410D01*
X610793Y227660D01*
X611043Y227869D01*
X611376Y227952D01*
G01X605259Y227744D02*
X605509Y227869D01*
X605801Y227952D01*
X606134D01*
X606509Y227827D01*
X606801Y227619D01*
X607009Y227369D01*
X607176Y226952D01*
X607218Y226577D01*
X607134Y226202D01*
X607009Y225952D01*
X606759Y225702D01*
X606468Y225535D01*
X606176Y225452D01*
X605884D01*
X605593Y225535D01*
X605343Y225660D01*
X605134Y225827D01*
G01X603993Y225952D02*
X603743Y225660D01*
X603409Y225494D01*
X603034Y225452D01*
X602701Y225494D01*
X602368Y225702D01*
X602159Y225952D01*
X602118Y226202D01*
X602201Y226494D01*
X602493Y226702D01*
X602784Y226785D01*
X603159D01*
G01X602784D02*
X602534Y226910D01*
X602326Y227119D01*
X602243Y227369D01*
X602326Y227619D01*
X602534Y227827D01*
X602909Y227952D01*
X603284Y227910D01*
X603659Y227744D01*
G01X600893Y225827D02*
X600643Y225619D01*
X600351Y225494D01*
X599976Y225452D01*
X599601Y225535D01*
X599309Y225702D01*
X599101Y225994D01*
X599059Y226327D01*
X599143Y226660D01*
X599351Y226869D01*
X599643Y227035D01*
X599934Y227077D01*
X600226Y227035D01*
X600601Y226869D01*
X600476Y227952D01*
X599351D01*
G01X597668Y226494D02*
X597376Y226785D01*
X597126Y226952D01*
X596793Y227035D01*
X596501Y226952D01*
X596293Y226785D01*
X596126Y226535D01*
X596084Y226244D01*
X596126Y225994D01*
X596293Y225744D01*
X596543Y225535D01*
X596834Y225452D01*
X597168Y225535D01*
X597459Y225785D01*
X597626Y226160D01*
X597668Y226577D01*
X597584Y227119D01*
X597459Y227410D01*
X597251Y227702D01*
X596959Y227910D01*
X596668Y227952D01*
X596376Y227869D01*
X596168Y227660D01*
G01X633733Y231792D02*
X633983Y231917D01*
X634275Y232000D01*
X634608D01*
X634983Y231875D01*
X635275Y231667D01*
X635483Y231417D01*
X635650Y231000D01*
X635692Y230625D01*
X635608Y230250D01*
X635483Y230000D01*
X635233Y229750D01*
X634942Y229583D01*
X634650Y229500D01*
X634358D01*
X634067Y229583D01*
X633817Y229708D01*
X633608Y229875D01*
G01X632467Y230000D02*
X632217Y229708D01*
X631883Y229542D01*
X631508Y229500D01*
X631175Y229542D01*
X630842Y229750D01*
X630633Y230000D01*
X630592Y230250D01*
X630675Y230542D01*
X630967Y230750D01*
X631258Y230833D01*
X631633D01*
G01X631258D02*
X631008Y230958D01*
X630800Y231167D01*
X630717Y231417D01*
X630800Y231667D01*
X631008Y231875D01*
X631383Y232000D01*
X631758Y231958D01*
X632133Y231792D01*
G01X629242Y230542D02*
X628950Y230833D01*
X628700Y231000D01*
X628367Y231083D01*
X628075Y231000D01*
X627867Y230833D01*
X627700Y230583D01*
X627658Y230292D01*
X627700Y230042D01*
X627867Y229792D01*
X628117Y229583D01*
X628408Y229500D01*
X628742Y229583D01*
X629033Y229833D01*
X629200Y230208D01*
X629242Y230625D01*
X629158Y231167D01*
X629033Y231458D01*
X628825Y231750D01*
X628533Y231958D01*
X628242Y232000D01*
X627950Y231917D01*
X627742Y231708D01*
G01X625433Y229500D02*
X625350Y230042D01*
X625225Y230500D01*
X625058Y230917D01*
X624850Y231375D01*
X624517Y232000D01*
X626183D01*
G01X619759Y231744D02*
X620009Y231869D01*
X620301Y231952D01*
X620634D01*
X621009Y231827D01*
X621301Y231619D01*
X621509Y231369D01*
X621676Y230952D01*
X621718Y230577D01*
X621634Y230202D01*
X621509Y229952D01*
X621259Y229702D01*
X620968Y229535D01*
X620676Y229452D01*
X620384D01*
X620093Y229535D01*
X619843Y229660D01*
X619634Y229827D01*
G01X618493Y229952D02*
X618243Y229660D01*
X617909Y229494D01*
X617534Y229452D01*
X617201Y229494D01*
X616868Y229702D01*
X616659Y229952D01*
X616618Y230202D01*
X616701Y230494D01*
X616993Y230702D01*
X617284Y230785D01*
X617659D01*
G01X617284D02*
X617034Y230910D01*
X616826Y231119D01*
X616743Y231369D01*
X616826Y231619D01*
X617034Y231827D01*
X617409Y231952D01*
X617784Y231910D01*
X618159Y231744D01*
G01X615393Y229827D02*
X615143Y229619D01*
X614851Y229494D01*
X614476Y229452D01*
X614101Y229535D01*
X613809Y229702D01*
X613601Y229994D01*
X613559Y230327D01*
X613643Y230660D01*
X613851Y230869D01*
X614143Y231035D01*
X614434Y231077D01*
X614726Y231035D01*
X615101Y230869D01*
X614976Y231952D01*
X613851D01*
G01X612084Y229744D02*
X611793Y229535D01*
X611459Y229452D01*
X611126Y229535D01*
X610834Y229785D01*
X610626Y230160D01*
X610543Y230535D01*
Y230994D01*
X610626Y231369D01*
X610834Y231702D01*
X611084Y231869D01*
X611376Y231952D01*
X611709Y231869D01*
X611959Y231702D01*
X612126Y231452D01*
X612209Y231119D01*
X612126Y230827D01*
X611918Y230535D01*
X611668Y230369D01*
X611376Y230327D01*
X611043Y230410D01*
X610793Y230619D01*
X610543Y230994D01*
G01X605259Y231744D02*
X605509Y231869D01*
X605801Y231952D01*
X606134D01*
X606509Y231827D01*
X606801Y231619D01*
X607009Y231369D01*
X607176Y230952D01*
X607218Y230577D01*
X607134Y230202D01*
X607009Y229952D01*
X606759Y229702D01*
X606468Y229535D01*
X606176Y229452D01*
X605884D01*
X605593Y229535D01*
X605343Y229660D01*
X605134Y229827D01*
G01X603993Y229952D02*
X603743Y229660D01*
X603409Y229494D01*
X603034Y229452D01*
X602701Y229494D01*
X602368Y229702D01*
X602159Y229952D01*
X602118Y230202D01*
X602201Y230494D01*
X602493Y230702D01*
X602784Y230785D01*
X603159D01*
G01X602784D02*
X602534Y230910D01*
X602326Y231119D01*
X602243Y231369D01*
X602326Y231619D01*
X602534Y231827D01*
X602909Y231952D01*
X603284Y231910D01*
X603659Y231744D01*
G01X600893Y229827D02*
X600643Y229619D01*
X600351Y229494D01*
X599976Y229452D01*
X599601Y229535D01*
X599309Y229702D01*
X599101Y229994D01*
X599059Y230327D01*
X599143Y230660D01*
X599351Y230869D01*
X599643Y231035D01*
X599934Y231077D01*
X600226Y231035D01*
X600601Y230869D01*
X600476Y231952D01*
X599351D01*
G01X597793Y229827D02*
X597543Y229619D01*
X597251Y229494D01*
X596876Y229452D01*
X596501Y229535D01*
X596209Y229702D01*
X596001Y229994D01*
X595959Y230327D01*
X596043Y230660D01*
X596251Y230869D01*
X596543Y231035D01*
X596834Y231077D01*
X597126Y231035D01*
X597501Y230869D01*
X597376Y231952D01*
X596251D01*
G01X633733Y219792D02*
X633983Y219917D01*
X634275Y220000D01*
X634608D01*
X634983Y219875D01*
X635275Y219667D01*
X635483Y219417D01*
X635650Y219000D01*
X635692Y218625D01*
X635608Y218250D01*
X635483Y218000D01*
X635233Y217750D01*
X634942Y217583D01*
X634650Y217500D01*
X634358D01*
X634067Y217583D01*
X633817Y217708D01*
X633608Y217875D01*
G01X632467Y218000D02*
X632217Y217708D01*
X631883Y217542D01*
X631508Y217500D01*
X631175Y217542D01*
X630842Y217750D01*
X630633Y218000D01*
X630592Y218250D01*
X630675Y218542D01*
X630967Y218750D01*
X631258Y218833D01*
X631633D01*
G01X631258D02*
X631008Y218958D01*
X630800Y219167D01*
X630717Y219417D01*
X630800Y219667D01*
X631008Y219875D01*
X631383Y220000D01*
X631758Y219958D01*
X632133Y219792D01*
G01X629242Y218542D02*
X628950Y218833D01*
X628700Y219000D01*
X628367Y219083D01*
X628075Y219000D01*
X627867Y218833D01*
X627700Y218583D01*
X627658Y218292D01*
X627700Y218042D01*
X627867Y217792D01*
X628117Y217583D01*
X628408Y217500D01*
X628742Y217583D01*
X629033Y217833D01*
X629200Y218208D01*
X629242Y218625D01*
X629158Y219167D01*
X629033Y219458D01*
X628825Y219750D01*
X628533Y219958D01*
X628242Y220000D01*
X627950Y219917D01*
X627742Y219708D01*
G01X626058Y217792D02*
X625767Y217583D01*
X625433Y217500D01*
X625100Y217583D01*
X624808Y217833D01*
X624600Y218208D01*
X624517Y218583D01*
Y219042D01*
X624600Y219417D01*
X624808Y219750D01*
X625058Y219917D01*
X625350Y220000D01*
X625683Y219917D01*
X625933Y219750D01*
X626100Y219500D01*
X626183Y219167D01*
X626100Y218875D01*
X625892Y218583D01*
X625642Y218417D01*
X625350Y218375D01*
X625017Y218458D01*
X624767Y218667D01*
X624517Y219042D01*
G01X619259Y223444D02*
X619509Y223569D01*
X619801Y223652D01*
X620134D01*
X620509Y223527D01*
X620801Y223319D01*
X621009Y223069D01*
X621176Y222652D01*
X621218Y222277D01*
X621134Y221902D01*
X621009Y221652D01*
X620759Y221402D01*
X620468Y221235D01*
X620176Y221152D01*
X619884D01*
X619593Y221235D01*
X619343Y221360D01*
X619134Y221527D01*
G01X617993Y221652D02*
X617743Y221360D01*
X617409Y221194D01*
X617034Y221152D01*
X616701Y221194D01*
X616368Y221402D01*
X616159Y221652D01*
X616118Y221902D01*
X616201Y222194D01*
X616493Y222402D01*
X616784Y222485D01*
X617159D01*
G01X616784D02*
X616534Y222610D01*
X616326Y222819D01*
X616243Y223069D01*
X616326Y223319D01*
X616534Y223527D01*
X616909Y223652D01*
X617284Y223610D01*
X617659Y223444D01*
G01X614768Y222194D02*
X614476Y222485D01*
X614226Y222652D01*
X613893Y222735D01*
X613601Y222652D01*
X613393Y222485D01*
X613226Y222235D01*
X613184Y221944D01*
X613226Y221694D01*
X613393Y221444D01*
X613643Y221235D01*
X613934Y221152D01*
X614268Y221235D01*
X614559Y221485D01*
X614726Y221860D01*
X614768Y222277D01*
X614684Y222819D01*
X614559Y223110D01*
X614351Y223402D01*
X614059Y223610D01*
X613768Y223652D01*
X613476Y223569D01*
X613268Y223360D01*
G01X610876Y221152D02*
Y223652D01*
X611376Y223152D01*
G01Y221152D02*
X610376D01*
G01X605059Y223444D02*
X605309Y223569D01*
X605601Y223652D01*
X605934D01*
X606309Y223527D01*
X606601Y223319D01*
X606809Y223069D01*
X606976Y222652D01*
X607018Y222277D01*
X606934Y221902D01*
X606809Y221652D01*
X606559Y221402D01*
X606268Y221235D01*
X605976Y221152D01*
X605684D01*
X605393Y221235D01*
X605143Y221360D01*
X604934Y221527D01*
G01X603793Y221652D02*
X603543Y221360D01*
X603209Y221194D01*
X602834Y221152D01*
X602501Y221194D01*
X602168Y221402D01*
X601959Y221652D01*
X601918Y221902D01*
X602001Y222194D01*
X602293Y222402D01*
X602584Y222485D01*
X602959D01*
G01X602584D02*
X602334Y222610D01*
X602126Y222819D01*
X602043Y223069D01*
X602126Y223319D01*
X602334Y223527D01*
X602709Y223652D01*
X603084Y223610D01*
X603459Y223444D01*
G01X600693Y221527D02*
X600443Y221319D01*
X600151Y221194D01*
X599776Y221152D01*
X599401Y221235D01*
X599109Y221402D01*
X598901Y221694D01*
X598859Y222027D01*
X598943Y222360D01*
X599151Y222569D01*
X599443Y222735D01*
X599734Y222777D01*
X600026Y222735D01*
X600401Y222569D01*
X600276Y223652D01*
X599151D01*
G01X596759Y221152D02*
X596676Y221694D01*
X596551Y222152D01*
X596384Y222569D01*
X596176Y223027D01*
X595843Y223652D01*
X597509D01*
G01X607500Y187850D02*
X605000D01*
G01X607500Y186892D02*
Y188808D01*
G01X605000Y190117D02*
X607500D01*
Y191117D01*
X607375Y191450D01*
X607083Y191700D01*
X606750Y191783D01*
X606417Y191700D01*
X606167Y191492D01*
X606042Y191117D01*
Y190117D01*
G01X605292Y193342D02*
X605083Y193633D01*
X605000Y193967D01*
X605083Y194300D01*
X605333Y194592D01*
X605708Y194800D01*
X606083Y194883D01*
X606542D01*
X606917Y194800D01*
X607250Y194592D01*
X607417Y194342D01*
X607500Y194050D01*
X607417Y193717D01*
X607250Y193467D01*
X607000Y193300D01*
X606667Y193217D01*
X606375Y193300D01*
X606083Y193508D01*
X605917Y193758D01*
X605875Y194050D01*
X605958Y194383D01*
X606167Y194633D01*
X606542Y194883D01*
G01X605000Y197650D02*
X607500D01*
X605708Y196108D01*
Y198192D01*
G01X603500Y187850D02*
X601000D01*
G01X603500Y186892D02*
Y188808D01*
G01X601000Y190117D02*
X603500D01*
Y191117D01*
X603375Y191450D01*
X603083Y191700D01*
X602750Y191783D01*
X602417Y191700D01*
X602167Y191492D01*
X602042Y191117D01*
Y190117D01*
G01X601292Y193342D02*
X601083Y193633D01*
X601000Y193967D01*
X601083Y194300D01*
X601333Y194592D01*
X601708Y194800D01*
X602083Y194883D01*
X602542D01*
X602917Y194800D01*
X603250Y194592D01*
X603417Y194342D01*
X603500Y194050D01*
X603417Y193717D01*
X603250Y193467D01*
X603000Y193300D01*
X602667Y193217D01*
X602375Y193300D01*
X602083Y193508D01*
X601917Y193758D01*
X601875Y194050D01*
X601958Y194383D01*
X602167Y194633D01*
X602542Y194883D01*
G01X603083Y196358D02*
X603333Y196608D01*
X603458Y196900D01*
X603500Y197233D01*
X603417Y197650D01*
X603208Y197942D01*
X602958Y198025D01*
X602708Y197983D01*
X602500Y197817D01*
X602083Y196983D01*
X601792Y196608D01*
X601375Y196358D01*
X601000Y196275D01*
Y198025D01*
G01X599500Y188350D02*
X597000D01*
G01X599500Y187392D02*
Y189308D01*
G01X597000Y190617D02*
X599500D01*
Y191617D01*
X599375Y191950D01*
X599083Y192200D01*
X598750Y192283D01*
X598417Y192200D01*
X598167Y191992D01*
X598042Y191617D01*
Y190617D01*
G01X597000Y194550D02*
X597042Y194842D01*
X597167Y195175D01*
X597375Y195383D01*
X597667Y195467D01*
X597958Y195383D01*
X598208Y195133D01*
X598333Y194758D01*
Y194342D01*
X598417Y194092D01*
X598625Y193883D01*
X598917Y193800D01*
X599208Y193925D01*
X599417Y194217D01*
X599500Y194550D01*
X599417Y194883D01*
X599208Y195175D01*
X598917Y195300D01*
X598625Y195217D01*
X598417Y195008D01*
X598333Y194758D01*
Y194342D01*
X598208Y193967D01*
X597958Y193717D01*
X597667Y193633D01*
X597375Y193717D01*
X597167Y193925D01*
X597042Y194258D01*
X597000Y194550D01*
G01Y197650D02*
X597042Y197942D01*
X597167Y198275D01*
X597375Y198483D01*
X597667Y198567D01*
X597958Y198483D01*
X598208Y198233D01*
X598333Y197858D01*
Y197442D01*
X598417Y197192D01*
X598625Y196983D01*
X598917Y196900D01*
X599208Y197025D01*
X599417Y197317D01*
X599500Y197650D01*
X599417Y197983D01*
X599208Y198275D01*
X598917Y198400D01*
X598625Y198317D01*
X598417Y198108D01*
X598333Y197858D01*
Y197442D01*
X598208Y197067D01*
X597958Y196817D01*
X597667Y196733D01*
X597375Y196817D01*
X597167Y197025D01*
X597042Y197358D01*
X597000Y197650D01*
G01X613197Y180529D02*
Y178029D01*
G01X614155Y180529D02*
X612239D01*
G01X610930Y178029D02*
Y180529D01*
X609930D01*
X609597Y180404D01*
X609347Y180112D01*
X609264Y179779D01*
X609347Y179446D01*
X609555Y179196D01*
X609930Y179071D01*
X610930D01*
G01X606997Y178029D02*
X606705Y178071D01*
X606372Y178196D01*
X606164Y178404D01*
X606080Y178696D01*
X606164Y178987D01*
X606414Y179237D01*
X606789Y179362D01*
X607205D01*
X607455Y179446D01*
X607664Y179654D01*
X607747Y179946D01*
X607622Y180237D01*
X607330Y180446D01*
X606997Y180529D01*
X606664Y180446D01*
X606372Y180237D01*
X606247Y179946D01*
X606330Y179654D01*
X606539Y179446D01*
X606789Y179362D01*
X607205D01*
X607580Y179237D01*
X607830Y178987D01*
X607914Y178696D01*
X607830Y178404D01*
X607622Y178196D01*
X607289Y178071D01*
X606997Y178029D01*
G01X604814Y178404D02*
X604564Y178196D01*
X604272Y178071D01*
X603897Y178029D01*
X603522Y178112D01*
X603230Y178279D01*
X603022Y178571D01*
X602980Y178904D01*
X603064Y179237D01*
X603272Y179446D01*
X603564Y179612D01*
X603855Y179654D01*
X604147Y179612D01*
X604522Y179446D01*
X604397Y180529D01*
X603272D01*
G01X615229Y184735D02*
Y182235D01*
G01X616187Y184735D02*
X614271D01*
G01X612962Y182235D02*
Y184735D01*
X611962D01*
X611629Y184610D01*
X611379Y184318D01*
X611296Y183985D01*
X611379Y183652D01*
X611587Y183402D01*
X611962Y183277D01*
X612962D01*
G01X609029Y182235D02*
X608737Y182277D01*
X608404Y182402D01*
X608196Y182610D01*
X608112Y182902D01*
X608196Y183193D01*
X608446Y183443D01*
X608821Y183568D01*
X609237D01*
X609487Y183652D01*
X609696Y183860D01*
X609779Y184152D01*
X609654Y184443D01*
X609362Y184652D01*
X609029Y184735D01*
X608696Y184652D01*
X608404Y184443D01*
X608279Y184152D01*
X608362Y183860D01*
X608571Y183652D01*
X608821Y183568D01*
X609237D01*
X609612Y183443D01*
X609862Y183193D01*
X609946Y182902D01*
X609862Y182610D01*
X609654Y182402D01*
X609321Y182277D01*
X609029Y182235D01*
G01X606846Y182735D02*
X606596Y182443D01*
X606262Y182277D01*
X605887Y182235D01*
X605554Y182277D01*
X605221Y182485D01*
X605012Y182735D01*
X604971Y182985D01*
X605054Y183277D01*
X605346Y183485D01*
X605637Y183568D01*
X606012D01*
G01X605637D02*
X605387Y183693D01*
X605179Y183902D01*
X605096Y184152D01*
X605179Y184402D01*
X605387Y184610D01*
X605762Y184735D01*
X606137Y184693D01*
X606512Y184527D01*
G01X595500Y188350D02*
X593000D01*
G01X595500Y187392D02*
Y189308D01*
G01X593000Y190617D02*
X595500D01*
Y191617D01*
X595375Y191950D01*
X595083Y192200D01*
X594750Y192283D01*
X594417Y192200D01*
X594167Y191992D01*
X594042Y191617D01*
Y190617D01*
G01X593000Y194467D02*
X593542Y194550D01*
X594000Y194675D01*
X594417Y194842D01*
X594875Y195050D01*
X595500Y195383D01*
Y193717D01*
G01X593292Y196942D02*
X593083Y197233D01*
X593000Y197567D01*
X593083Y197900D01*
X593333Y198192D01*
X593708Y198400D01*
X594083Y198483D01*
X594542D01*
X594917Y198400D01*
X595250Y198192D01*
X595417Y197942D01*
X595500Y197650D01*
X595417Y197317D01*
X595250Y197067D01*
X595000Y196900D01*
X594667Y196817D01*
X594375Y196900D01*
X594083Y197108D01*
X593917Y197358D01*
X593875Y197650D01*
X593958Y197983D01*
X594167Y198233D01*
X594542Y198483D01*
G01X615500Y187800D02*
X613000D01*
G01X615500Y186842D02*
Y188758D01*
G01X613000Y190067D02*
X615500D01*
Y191067D01*
X615375Y191400D01*
X615083Y191650D01*
X614750Y191733D01*
X614417Y191650D01*
X614167Y191442D01*
X614042Y191067D01*
Y190067D01*
G01X613000Y194000D02*
X615500D01*
X615000Y193500D01*
G01X613000D02*
Y194500D01*
G01X615083Y196308D02*
X615333Y196558D01*
X615458Y196850D01*
X615500Y197183D01*
X615417Y197600D01*
X615208Y197892D01*
X614958Y197975D01*
X614708Y197933D01*
X614500Y197767D01*
X614083Y196933D01*
X613792Y196558D01*
X613375Y196308D01*
X613000Y196225D01*
Y197975D01*
G01X614042Y199408D02*
X614333Y199700D01*
X614500Y199950D01*
X614583Y200283D01*
X614500Y200575D01*
X614333Y200783D01*
X614083Y200950D01*
X613792Y200992D01*
X613542Y200950D01*
X613292Y200783D01*
X613083Y200533D01*
X613000Y200242D01*
X613083Y199908D01*
X613333Y199617D01*
X613708Y199450D01*
X614125Y199408D01*
X614667Y199492D01*
X614958Y199617D01*
X615250Y199825D01*
X615458Y200117D01*
X615500Y200408D01*
X615417Y200700D01*
X615208Y200908D01*
G01X611500Y187800D02*
X609000D01*
G01X611500Y186842D02*
Y188758D01*
G01X609000Y190067D02*
X611500D01*
Y191067D01*
X611375Y191400D01*
X611083Y191650D01*
X610750Y191733D01*
X610417Y191650D01*
X610167Y191442D01*
X610042Y191067D01*
Y190067D01*
G01X609000Y194000D02*
X611500D01*
X611000Y193500D01*
G01X609000D02*
Y194500D01*
G01Y197100D02*
X611500D01*
X611000Y196600D01*
G01X609000D02*
Y197600D01*
G01Y200200D02*
X609042Y200492D01*
X609167Y200825D01*
X609375Y201033D01*
X609667Y201117D01*
X609958Y201033D01*
X610208Y200783D01*
X610333Y200408D01*
Y199992D01*
X610417Y199742D01*
X610625Y199533D01*
X610917Y199450D01*
X611208Y199575D01*
X611417Y199867D01*
X611500Y200200D01*
X611417Y200533D01*
X611208Y200825D01*
X610917Y200950D01*
X610625Y200867D01*
X610417Y200658D01*
X610333Y200408D01*
Y199992D01*
X610208Y199617D01*
X609958Y199367D01*
X609667Y199283D01*
X609375Y199367D01*
X609167Y199575D01*
X609042Y199908D01*
X609000Y200200D01*
G01X593683Y298792D02*
X593933Y298917D01*
X594225Y299000D01*
X594558D01*
X594933Y298875D01*
X595225Y298667D01*
X595433Y298417D01*
X595600Y298000D01*
X595642Y297625D01*
X595558Y297250D01*
X595433Y297000D01*
X595183Y296750D01*
X594892Y296583D01*
X594600Y296500D01*
X594308D01*
X594017Y296583D01*
X593767Y296708D01*
X593558Y296875D01*
G01X591500Y296500D02*
Y299000D01*
X592000Y298500D01*
G01Y296500D02*
X591000D01*
G01X589192Y297542D02*
X588900Y297833D01*
X588650Y298000D01*
X588317Y298083D01*
X588025Y298000D01*
X587817Y297833D01*
X587650Y297583D01*
X587608Y297292D01*
X587650Y297042D01*
X587817Y296792D01*
X588067Y296583D01*
X588358Y296500D01*
X588692Y296583D01*
X588983Y296833D01*
X589150Y297208D01*
X589192Y297625D01*
X589108Y298167D01*
X588983Y298458D01*
X588775Y298750D01*
X588483Y298958D01*
X588192Y299000D01*
X587900Y298917D01*
X587692Y298708D01*
G01X593683Y294792D02*
X593933Y294917D01*
X594225Y295000D01*
X594558D01*
X594933Y294875D01*
X595225Y294667D01*
X595433Y294417D01*
X595600Y294000D01*
X595642Y293625D01*
X595558Y293250D01*
X595433Y293000D01*
X595183Y292750D01*
X594892Y292583D01*
X594600Y292500D01*
X594308D01*
X594017Y292583D01*
X593767Y292708D01*
X593558Y292875D01*
G01X591500Y292500D02*
Y295000D01*
X592000Y294500D01*
G01Y292500D02*
X591000D01*
G01X588483D02*
X588400Y293042D01*
X588275Y293500D01*
X588108Y293917D01*
X587900Y294375D01*
X587567Y295000D01*
X589233D01*
G01X593683Y290792D02*
X593933Y290917D01*
X594225Y291000D01*
X594558D01*
X594933Y290875D01*
X595225Y290667D01*
X595433Y290417D01*
X595600Y290000D01*
X595642Y289625D01*
X595558Y289250D01*
X595433Y289000D01*
X595183Y288750D01*
X594892Y288583D01*
X594600Y288500D01*
X594308D01*
X594017Y288583D01*
X593767Y288708D01*
X593558Y288875D01*
G01X591500Y288500D02*
Y291000D01*
X592000Y290500D01*
G01Y288500D02*
X591000D01*
G01X588400D02*
X588108Y288542D01*
X587775Y288667D01*
X587567Y288875D01*
X587483Y289167D01*
X587567Y289458D01*
X587817Y289708D01*
X588192Y289833D01*
X588608D01*
X588858Y289917D01*
X589067Y290125D01*
X589150Y290417D01*
X589025Y290708D01*
X588733Y290917D01*
X588400Y291000D01*
X588067Y290917D01*
X587775Y290708D01*
X587650Y290417D01*
X587733Y290125D01*
X587942Y289917D01*
X588192Y289833D01*
X588608D01*
X588983Y289708D01*
X589233Y289458D01*
X589317Y289167D01*
X589233Y288875D01*
X589025Y288667D01*
X588692Y288542D01*
X588400Y288500D01*
G01X593683Y286792D02*
X593933Y286917D01*
X594225Y287000D01*
X594558D01*
X594933Y286875D01*
X595225Y286667D01*
X595433Y286417D01*
X595600Y286000D01*
X595642Y285625D01*
X595558Y285250D01*
X595433Y285000D01*
X595183Y284750D01*
X594892Y284583D01*
X594600Y284500D01*
X594308D01*
X594017Y284583D01*
X593767Y284708D01*
X593558Y284875D01*
G01X591500Y284500D02*
Y287000D01*
X592000Y286500D01*
G01Y284500D02*
X591000D01*
G01X589108Y284792D02*
X588817Y284583D01*
X588483Y284500D01*
X588150Y284583D01*
X587858Y284833D01*
X587650Y285208D01*
X587567Y285583D01*
Y286042D01*
X587650Y286417D01*
X587858Y286750D01*
X588108Y286917D01*
X588400Y287000D01*
X588733Y286917D01*
X588983Y286750D01*
X589150Y286500D01*
X589233Y286167D01*
X589150Y285875D01*
X588942Y285583D01*
X588692Y285417D01*
X588400Y285375D01*
X588067Y285458D01*
X587817Y285667D01*
X587567Y286042D01*
G01X593683Y282792D02*
X593933Y282917D01*
X594225Y283000D01*
X594558D01*
X594933Y282875D01*
X595225Y282667D01*
X595433Y282417D01*
X595600Y282000D01*
X595642Y281625D01*
X595558Y281250D01*
X595433Y281000D01*
X595183Y280750D01*
X594892Y280583D01*
X594600Y280500D01*
X594308D01*
X594017Y280583D01*
X593767Y280708D01*
X593558Y280875D01*
G01X592292Y282583D02*
X592042Y282833D01*
X591750Y282958D01*
X591417Y283000D01*
X591000Y282917D01*
X590708Y282708D01*
X590625Y282458D01*
X590667Y282208D01*
X590833Y282000D01*
X591667Y281583D01*
X592042Y281292D01*
X592292Y280875D01*
X592375Y280500D01*
X590625D01*
G01X588400Y283000D02*
X588733Y282917D01*
X588983Y282708D01*
X589150Y282458D01*
X589275Y282125D01*
X589317Y281750D01*
X589275Y281375D01*
X589150Y281042D01*
X588983Y280792D01*
X588733Y280583D01*
X588400Y280500D01*
X588067Y280583D01*
X587817Y280792D01*
X587650Y281042D01*
X587525Y281375D01*
X587483Y281750D01*
X587525Y282125D01*
X587650Y282458D01*
X587817Y282708D01*
X588067Y282917D01*
X588400Y283000D01*
G01X588183Y277792D02*
X588433Y277917D01*
X588725Y278000D01*
X589058D01*
X589433Y277875D01*
X589725Y277667D01*
X589933Y277417D01*
X590100Y277000D01*
X590142Y276625D01*
X590058Y276250D01*
X589933Y276000D01*
X589683Y275750D01*
X589392Y275583D01*
X589100Y275500D01*
X588808D01*
X588517Y275583D01*
X588267Y275708D01*
X588058Y275875D01*
G01X586792Y277583D02*
X586542Y277833D01*
X586250Y277958D01*
X585917Y278000D01*
X585500Y277917D01*
X585208Y277708D01*
X585125Y277458D01*
X585167Y277208D01*
X585333Y277000D01*
X586167Y276583D01*
X586542Y276292D01*
X586792Y275875D01*
X586875Y275500D01*
X585125D01*
G01X582900D02*
Y278000D01*
X583400Y277500D01*
G01Y275500D02*
X582400D01*
G01X588683Y273792D02*
X588933Y273917D01*
X589225Y274000D01*
X589558D01*
X589933Y273875D01*
X590225Y273667D01*
X590433Y273417D01*
X590600Y273000D01*
X590642Y272625D01*
X590558Y272250D01*
X590433Y272000D01*
X590183Y271750D01*
X589892Y271583D01*
X589600Y271500D01*
X589308D01*
X589017Y271583D01*
X588767Y271708D01*
X588558Y271875D01*
G01X587292Y273583D02*
X587042Y273833D01*
X586750Y273958D01*
X586417Y274000D01*
X586000Y273917D01*
X585708Y273708D01*
X585625Y273458D01*
X585667Y273208D01*
X585833Y273000D01*
X586667Y272583D01*
X587042Y272292D01*
X587292Y271875D01*
X587375Y271500D01*
X585625D01*
G01X584192Y273583D02*
X583942Y273833D01*
X583650Y273958D01*
X583317Y274000D01*
X582900Y273917D01*
X582608Y273708D01*
X582525Y273458D01*
X582567Y273208D01*
X582733Y273000D01*
X583567Y272583D01*
X583942Y272292D01*
X584192Y271875D01*
X584275Y271500D01*
X582525D01*
G01X595421Y259303D02*
X595546Y259053D01*
X595629Y258761D01*
Y258428D01*
X595504Y258053D01*
X595296Y257761D01*
X595046Y257553D01*
X594629Y257386D01*
X594254Y257344D01*
X593879Y257428D01*
X593629Y257553D01*
X593379Y257803D01*
X593212Y258094D01*
X593129Y258386D01*
Y258678D01*
X593212Y258969D01*
X593337Y259219D01*
X593504Y259428D01*
G01X595212Y260694D02*
X595462Y260944D01*
X595587Y261236D01*
X595629Y261569D01*
X595546Y261986D01*
X595337Y262278D01*
X595087Y262361D01*
X594837Y262319D01*
X594629Y262153D01*
X594212Y261319D01*
X593921Y260944D01*
X593504Y260694D01*
X593129Y260611D01*
Y262361D01*
G01X593629Y263669D02*
X593337Y263919D01*
X593171Y264253D01*
X593129Y264628D01*
X593171Y264961D01*
X593379Y265294D01*
X593629Y265503D01*
X593879Y265544D01*
X594171Y265461D01*
X594379Y265169D01*
X594462Y264878D01*
Y264503D01*
G01Y264878D02*
X594587Y265128D01*
X594796Y265336D01*
X595046Y265419D01*
X595296Y265336D01*
X595504Y265128D01*
X595629Y264753D01*
X595587Y264378D01*
X595421Y264003D01*
G01X591421Y259303D02*
X591546Y259053D01*
X591629Y258761D01*
Y258428D01*
X591504Y258053D01*
X591296Y257761D01*
X591046Y257553D01*
X590629Y257386D01*
X590254Y257344D01*
X589879Y257428D01*
X589629Y257553D01*
X589379Y257803D01*
X589212Y258094D01*
X589129Y258386D01*
Y258678D01*
X589212Y258969D01*
X589337Y259219D01*
X589504Y259428D01*
G01X591212Y260694D02*
X591462Y260944D01*
X591587Y261236D01*
X591629Y261569D01*
X591546Y261986D01*
X591337Y262278D01*
X591087Y262361D01*
X590837Y262319D01*
X590629Y262153D01*
X590212Y261319D01*
X589921Y260944D01*
X589504Y260694D01*
X589129Y260611D01*
Y262361D01*
G01Y265086D02*
X591629D01*
X589837Y263544D01*
Y265628D01*
G01X597308Y248611D02*
X597433Y248361D01*
X597516Y248069D01*
Y247736D01*
X597391Y247361D01*
X597183Y247069D01*
X596933Y246861D01*
X596516Y246694D01*
X596141Y246652D01*
X595766Y246736D01*
X595516Y246861D01*
X595266Y247111D01*
X595099Y247402D01*
X595016Y247694D01*
Y247986D01*
X595099Y248277D01*
X595224Y248527D01*
X595391Y248736D01*
G01X597099Y250002D02*
X597349Y250252D01*
X597474Y250544D01*
X597516Y250877D01*
X597433Y251294D01*
X597224Y251586D01*
X596974Y251669D01*
X596724Y251627D01*
X596516Y251461D01*
X596099Y250627D01*
X595808Y250252D01*
X595391Y250002D01*
X595016Y249919D01*
Y251669D01*
G01X595391Y252977D02*
X595183Y253227D01*
X595058Y253519D01*
X595016Y253894D01*
X595099Y254269D01*
X595266Y254561D01*
X595558Y254769D01*
X595891Y254811D01*
X596224Y254727D01*
X596433Y254519D01*
X596599Y254227D01*
X596641Y253936D01*
X596599Y253644D01*
X596433Y253269D01*
X597516Y253394D01*
Y254519D01*
G01X593308Y248611D02*
X593433Y248361D01*
X593516Y248069D01*
Y247736D01*
X593391Y247361D01*
X593183Y247069D01*
X592933Y246861D01*
X592516Y246694D01*
X592141Y246652D01*
X591766Y246736D01*
X591516Y246861D01*
X591266Y247111D01*
X591099Y247402D01*
X591016Y247694D01*
Y247986D01*
X591099Y248277D01*
X591224Y248527D01*
X591391Y248736D01*
G01X593099Y250002D02*
X593349Y250252D01*
X593474Y250544D01*
X593516Y250877D01*
X593433Y251294D01*
X593224Y251586D01*
X592974Y251669D01*
X592724Y251627D01*
X592516Y251461D01*
X592099Y250627D01*
X591808Y250252D01*
X591391Y250002D01*
X591016Y249919D01*
Y251669D01*
G01X592058Y253102D02*
X592349Y253394D01*
X592516Y253644D01*
X592599Y253977D01*
X592516Y254269D01*
X592349Y254477D01*
X592099Y254644D01*
X591808Y254686D01*
X591558Y254644D01*
X591308Y254477D01*
X591099Y254227D01*
X591016Y253936D01*
X591099Y253602D01*
X591349Y253311D01*
X591724Y253144D01*
X592141Y253102D01*
X592683Y253186D01*
X592974Y253311D01*
X593266Y253519D01*
X593474Y253811D01*
X593516Y254102D01*
X593433Y254394D01*
X593224Y254602D01*
G01X624000Y273067D02*
X621500D01*
Y274733D01*
G01X623583Y276208D02*
X623833Y276458D01*
X623958Y276750D01*
X624000Y277083D01*
X623917Y277500D01*
X623708Y277792D01*
X623458Y277875D01*
X623208Y277833D01*
X623000Y277667D01*
X622583Y276833D01*
X622292Y276458D01*
X621875Y276208D01*
X621500Y276125D01*
Y277875D01*
G01Y280100D02*
X624000D01*
X623500Y279600D01*
G01X621500D02*
Y280600D01*
G01X620526Y256752D02*
X627526D01*
Y270152D01*
X620526D01*
Y256752D01*
G01X609500Y273067D02*
X607000D01*
Y274733D01*
G01X609083Y276208D02*
X609333Y276458D01*
X609458Y276750D01*
X609500Y277083D01*
X609417Y277500D01*
X609208Y277792D01*
X608958Y277875D01*
X608708Y277833D01*
X608500Y277667D01*
X608083Y276833D01*
X607792Y276458D01*
X607375Y276208D01*
X607000Y276125D01*
Y277875D01*
G01X609500Y280100D02*
X609417Y279767D01*
X609208Y279517D01*
X608958Y279350D01*
X608625Y279225D01*
X608250Y279183D01*
X607875Y279225D01*
X607542Y279350D01*
X607292Y279517D01*
X607083Y279767D01*
X607000Y280100D01*
X607083Y280433D01*
X607292Y280683D01*
X607542Y280850D01*
X607875Y280975D01*
X608250Y281017D01*
X608625Y280975D01*
X608958Y280850D01*
X609208Y280683D01*
X609417Y280433D01*
X609500Y280100D01*
G01X602026Y256752D02*
X609026D01*
Y270152D01*
X602026D01*
Y256752D01*
G01X616526Y271269D02*
X619026D01*
Y272310D01*
X618901Y272644D01*
X618734Y272852D01*
X618401Y272935D01*
X618068Y272852D01*
X617859Y272602D01*
X617734Y272310D01*
Y271269D01*
G01Y272310D02*
X616526Y272935D01*
G01X618609Y274410D02*
X618859Y274660D01*
X618984Y274952D01*
X619026Y275285D01*
X618943Y275702D01*
X618734Y275994D01*
X618484Y276077D01*
X618234Y276035D01*
X618026Y275869D01*
X617609Y275035D01*
X617318Y274660D01*
X616901Y274410D01*
X616526Y274327D01*
Y276077D01*
G01Y278219D02*
X617068Y278302D01*
X617526Y278427D01*
X617943Y278594D01*
X618401Y278802D01*
X619026Y279135D01*
Y277469D01*
G01X616818Y280694D02*
X616609Y280985D01*
X616526Y281319D01*
X616609Y281652D01*
X616859Y281944D01*
X617234Y282152D01*
X617609Y282235D01*
X618068D01*
X618443Y282152D01*
X618776Y281944D01*
X618943Y281694D01*
X619026Y281402D01*
X618943Y281069D01*
X618776Y280819D01*
X618526Y280652D01*
X618193Y280569D01*
X617901Y280652D01*
X617609Y280860D01*
X617443Y281110D01*
X617401Y281402D01*
X617484Y281735D01*
X617693Y281985D01*
X618068Y282235D01*
G01X616026Y266952D02*
X620026D01*
Y259552D01*
G01X611526Y271269D02*
X614026D01*
Y272310D01*
X613901Y272644D01*
X613734Y272852D01*
X613401Y272935D01*
X613068Y272852D01*
X612859Y272602D01*
X612734Y272310D01*
Y271269D01*
G01Y272310D02*
X611526Y272935D01*
G01X613609Y274410D02*
X613859Y274660D01*
X613984Y274952D01*
X614026Y275285D01*
X613943Y275702D01*
X613734Y275994D01*
X613484Y276077D01*
X613234Y276035D01*
X613026Y275869D01*
X612609Y275035D01*
X612318Y274660D01*
X611901Y274410D01*
X611526Y274327D01*
Y276077D01*
G01Y278219D02*
X612068Y278302D01*
X612526Y278427D01*
X612943Y278594D01*
X613401Y278802D01*
X614026Y279135D01*
Y277469D01*
G01X611526Y281402D02*
X611568Y281694D01*
X611693Y282027D01*
X611901Y282235D01*
X612193Y282319D01*
X612484Y282235D01*
X612734Y281985D01*
X612859Y281610D01*
Y281194D01*
X612943Y280944D01*
X613151Y280735D01*
X613443Y280652D01*
X613734Y280777D01*
X613943Y281069D01*
X614026Y281402D01*
X613943Y281735D01*
X613734Y282027D01*
X613443Y282152D01*
X613151Y282069D01*
X612943Y281860D01*
X612859Y281610D01*
Y281194D01*
X612734Y280819D01*
X612484Y280569D01*
X612193Y280485D01*
X611901Y280569D01*
X611693Y280777D01*
X611568Y281110D01*
X611526Y281402D01*
G01X609526Y266952D02*
X613526D01*
Y259552D01*
G01X588860Y356879D02*
X589110Y357004D01*
X589402Y357087D01*
X589735D01*
X590110Y356962D01*
X590402Y356754D01*
X590610Y356504D01*
X590777Y356087D01*
X590819Y355712D01*
X590735Y355337D01*
X590610Y355087D01*
X590360Y354837D01*
X590069Y354670D01*
X589777Y354587D01*
X589485D01*
X589194Y354670D01*
X588944Y354795D01*
X588735Y354962D01*
G01X586677Y354587D02*
Y357087D01*
X587177Y356587D01*
G01Y354587D02*
X586177D01*
G01X593683Y323792D02*
X593933Y323917D01*
X594225Y324000D01*
X594558D01*
X594933Y323875D01*
X595225Y323667D01*
X595433Y323417D01*
X595600Y323000D01*
X595642Y322625D01*
X595558Y322250D01*
X595433Y322000D01*
X595183Y321750D01*
X594892Y321583D01*
X594600Y321500D01*
X594308D01*
X594017Y321583D01*
X593767Y321708D01*
X593558Y321875D01*
G01X591500Y321500D02*
Y324000D01*
X592000Y323500D01*
G01Y321500D02*
X591000D01*
G01X588400Y324000D02*
X588733Y323917D01*
X588983Y323708D01*
X589150Y323458D01*
X589275Y323125D01*
X589317Y322750D01*
X589275Y322375D01*
X589150Y322042D01*
X588983Y321792D01*
X588733Y321583D01*
X588400Y321500D01*
X588067Y321583D01*
X587817Y321792D01*
X587650Y322042D01*
X587525Y322375D01*
X587483Y322750D01*
X587525Y323125D01*
X587650Y323458D01*
X587817Y323708D01*
X588067Y323917D01*
X588400Y324000D01*
G01X593883Y319192D02*
X594133Y319317D01*
X594425Y319400D01*
X594758D01*
X595133Y319275D01*
X595425Y319067D01*
X595633Y318817D01*
X595800Y318400D01*
X595842Y318025D01*
X595758Y317650D01*
X595633Y317400D01*
X595383Y317150D01*
X595092Y316983D01*
X594800Y316900D01*
X594508D01*
X594217Y316983D01*
X593967Y317108D01*
X593758Y317275D01*
G01X591700Y316900D02*
Y319400D01*
X592200Y318900D01*
G01Y316900D02*
X591200D01*
G01X588600D02*
Y319400D01*
X589100Y318900D01*
G01Y316900D02*
X588100D01*
G01X593883Y314992D02*
X594133Y315117D01*
X594425Y315200D01*
X594758D01*
X595133Y315075D01*
X595425Y314867D01*
X595633Y314617D01*
X595800Y314200D01*
X595842Y313825D01*
X595758Y313450D01*
X595633Y313200D01*
X595383Y312950D01*
X595092Y312783D01*
X594800Y312700D01*
X594508D01*
X594217Y312783D01*
X593967Y312908D01*
X593758Y313075D01*
G01X591700Y312700D02*
Y315200D01*
X592200Y314700D01*
G01Y312700D02*
X591200D01*
G01X589392Y314783D02*
X589142Y315033D01*
X588850Y315158D01*
X588517Y315200D01*
X588100Y315117D01*
X587808Y314908D01*
X587725Y314658D01*
X587767Y314408D01*
X587933Y314200D01*
X588767Y313783D01*
X589142Y313492D01*
X589392Y313075D01*
X589475Y312700D01*
X587725D01*
G01X593683Y310792D02*
X593933Y310917D01*
X594225Y311000D01*
X594558D01*
X594933Y310875D01*
X595225Y310667D01*
X595433Y310417D01*
X595600Y310000D01*
X595642Y309625D01*
X595558Y309250D01*
X595433Y309000D01*
X595183Y308750D01*
X594892Y308583D01*
X594600Y308500D01*
X594308D01*
X594017Y308583D01*
X593767Y308708D01*
X593558Y308875D01*
G01X591500Y308500D02*
Y311000D01*
X592000Y310500D01*
G01Y308500D02*
X591000D01*
G01X589317Y309000D02*
X589067Y308708D01*
X588733Y308542D01*
X588358Y308500D01*
X588025Y308542D01*
X587692Y308750D01*
X587483Y309000D01*
X587442Y309250D01*
X587525Y309542D01*
X587817Y309750D01*
X588108Y309833D01*
X588483D01*
G01X588108D02*
X587858Y309958D01*
X587650Y310167D01*
X587567Y310417D01*
X587650Y310667D01*
X587858Y310875D01*
X588233Y311000D01*
X588608Y310958D01*
X588983Y310792D01*
G01X593683Y306792D02*
X593933Y306917D01*
X594225Y307000D01*
X594558D01*
X594933Y306875D01*
X595225Y306667D01*
X595433Y306417D01*
X595600Y306000D01*
X595642Y305625D01*
X595558Y305250D01*
X595433Y305000D01*
X595183Y304750D01*
X594892Y304583D01*
X594600Y304500D01*
X594308D01*
X594017Y304583D01*
X593767Y304708D01*
X593558Y304875D01*
G01X591500Y304500D02*
Y307000D01*
X592000Y306500D01*
G01Y304500D02*
X591000D01*
G01X587900D02*
Y307000D01*
X589442Y305208D01*
X587358D01*
G01X593683Y302792D02*
X593933Y302917D01*
X594225Y303000D01*
X594558D01*
X594933Y302875D01*
X595225Y302667D01*
X595433Y302417D01*
X595600Y302000D01*
X595642Y301625D01*
X595558Y301250D01*
X595433Y301000D01*
X595183Y300750D01*
X594892Y300583D01*
X594600Y300500D01*
X594308D01*
X594017Y300583D01*
X593767Y300708D01*
X593558Y300875D01*
G01X591500Y300500D02*
Y303000D01*
X592000Y302500D01*
G01Y300500D02*
X591000D01*
G01X589317Y300875D02*
X589067Y300667D01*
X588775Y300542D01*
X588400Y300500D01*
X588025Y300583D01*
X587733Y300750D01*
X587525Y301042D01*
X587483Y301375D01*
X587567Y301708D01*
X587775Y301917D01*
X588067Y302083D01*
X588358Y302125D01*
X588650Y302083D01*
X589025Y301917D01*
X588900Y303000D01*
X587775D01*
G01X588860Y360879D02*
X589110Y361004D01*
X589402Y361087D01*
X589735D01*
X590110Y360962D01*
X590402Y360754D01*
X590610Y360504D01*
X590777Y360087D01*
X590819Y359712D01*
X590735Y359337D01*
X590610Y359087D01*
X590360Y358837D01*
X590069Y358670D01*
X589777Y358587D01*
X589485D01*
X589194Y358670D01*
X588944Y358795D01*
X588735Y358962D01*
G01X587469Y360670D02*
X587219Y360920D01*
X586927Y361045D01*
X586594Y361087D01*
X586177Y361004D01*
X585885Y360795D01*
X585802Y360545D01*
X585844Y360295D01*
X586010Y360087D01*
X586844Y359670D01*
X587219Y359379D01*
X587469Y358962D01*
X587552Y358587D01*
X585802D01*
G01X588860Y348879D02*
X589110Y349004D01*
X589402Y349087D01*
X589735D01*
X590110Y348962D01*
X590402Y348754D01*
X590610Y348504D01*
X590777Y348087D01*
X590819Y347712D01*
X590735Y347337D01*
X590610Y347087D01*
X590360Y346837D01*
X590069Y346670D01*
X589777Y346587D01*
X589485D01*
X589194Y346670D01*
X588944Y346795D01*
X588735Y346962D01*
G01X587594Y347087D02*
X587344Y346795D01*
X587010Y346629D01*
X586635Y346587D01*
X586302Y346629D01*
X585969Y346837D01*
X585760Y347087D01*
X585719Y347337D01*
X585802Y347629D01*
X586094Y347837D01*
X586385Y347920D01*
X586760D01*
G01X586385D02*
X586135Y348045D01*
X585927Y348254D01*
X585844Y348504D01*
X585927Y348754D01*
X586135Y348962D01*
X586510Y349087D01*
X586885Y349045D01*
X587260Y348879D01*
G01X588860Y352879D02*
X589110Y353004D01*
X589402Y353087D01*
X589735D01*
X590110Y352962D01*
X590402Y352754D01*
X590610Y352504D01*
X590777Y352087D01*
X590819Y351712D01*
X590735Y351337D01*
X590610Y351087D01*
X590360Y350837D01*
X590069Y350670D01*
X589777Y350587D01*
X589485D01*
X589194Y350670D01*
X588944Y350795D01*
X588735Y350962D01*
G01X586177Y350587D02*
Y353087D01*
X587719Y351295D01*
X585635D01*
G01X588860Y340879D02*
X589110Y341004D01*
X589402Y341087D01*
X589735D01*
X590110Y340962D01*
X590402Y340754D01*
X590610Y340504D01*
X590777Y340087D01*
X590819Y339712D01*
X590735Y339337D01*
X590610Y339087D01*
X590360Y338837D01*
X590069Y338670D01*
X589777Y338587D01*
X589485D01*
X589194Y338670D01*
X588944Y338795D01*
X588735Y338962D01*
G01X587594D02*
X587344Y338754D01*
X587052Y338629D01*
X586677Y338587D01*
X586302Y338670D01*
X586010Y338837D01*
X585802Y339129D01*
X585760Y339462D01*
X585844Y339795D01*
X586052Y340004D01*
X586344Y340170D01*
X586635Y340212D01*
X586927Y340170D01*
X587302Y340004D01*
X587177Y341087D01*
X586052D01*
G01X588860Y344879D02*
X589110Y345004D01*
X589402Y345087D01*
X589735D01*
X590110Y344962D01*
X590402Y344754D01*
X590610Y344504D01*
X590777Y344087D01*
X590819Y343712D01*
X590735Y343337D01*
X590610Y343087D01*
X590360Y342837D01*
X590069Y342670D01*
X589777Y342587D01*
X589485D01*
X589194Y342670D01*
X588944Y342795D01*
X588735Y342962D01*
G01X587469Y343629D02*
X587177Y343920D01*
X586927Y344087D01*
X586594Y344170D01*
X586302Y344087D01*
X586094Y343920D01*
X585927Y343670D01*
X585885Y343379D01*
X585927Y343129D01*
X586094Y342879D01*
X586344Y342670D01*
X586635Y342587D01*
X586969Y342670D01*
X587260Y342920D01*
X587427Y343295D01*
X587469Y343712D01*
X587385Y344254D01*
X587260Y344545D01*
X587052Y344837D01*
X586760Y345045D01*
X586469Y345087D01*
X586177Y345004D01*
X585969Y344795D01*
G01X588860Y332879D02*
X589110Y333004D01*
X589402Y333087D01*
X589735D01*
X590110Y332962D01*
X590402Y332754D01*
X590610Y332504D01*
X590777Y332087D01*
X590819Y331712D01*
X590735Y331337D01*
X590610Y331087D01*
X590360Y330837D01*
X590069Y330670D01*
X589777Y330587D01*
X589485D01*
X589194Y330670D01*
X588944Y330795D01*
X588735Y330962D01*
G01X586760Y330587D02*
X586677Y331129D01*
X586552Y331587D01*
X586385Y332004D01*
X586177Y332462D01*
X585844Y333087D01*
X587510D01*
G01X588860Y336879D02*
X589110Y337004D01*
X589402Y337087D01*
X589735D01*
X590110Y336962D01*
X590402Y336754D01*
X590610Y336504D01*
X590777Y336087D01*
X590819Y335712D01*
X590735Y335337D01*
X590610Y335087D01*
X590360Y334837D01*
X590069Y334670D01*
X589777Y334587D01*
X589485D01*
X589194Y334670D01*
X588944Y334795D01*
X588735Y334962D01*
G01X586677Y334587D02*
X586385Y334629D01*
X586052Y334754D01*
X585844Y334962D01*
X585760Y335254D01*
X585844Y335545D01*
X586094Y335795D01*
X586469Y335920D01*
X586885D01*
X587135Y336004D01*
X587344Y336212D01*
X587427Y336504D01*
X587302Y336795D01*
X587010Y337004D01*
X586677Y337087D01*
X586344Y337004D01*
X586052Y336795D01*
X585927Y336504D01*
X586010Y336212D01*
X586219Y336004D01*
X586469Y335920D01*
X586885D01*
X587260Y335795D01*
X587510Y335545D01*
X587594Y335254D01*
X587510Y334962D01*
X587302Y334754D01*
X586969Y334629D01*
X586677Y334587D01*
G01X592133Y327792D02*
X592383Y327917D01*
X592675Y328000D01*
X593008D01*
X593383Y327875D01*
X593675Y327667D01*
X593883Y327417D01*
X594050Y327000D01*
X594092Y326625D01*
X594008Y326250D01*
X593883Y326000D01*
X593633Y325750D01*
X593342Y325583D01*
X593050Y325500D01*
X592758D01*
X592467Y325583D01*
X592217Y325708D01*
X592008Y325875D01*
G01X590658Y325792D02*
X590367Y325583D01*
X590033Y325500D01*
X589700Y325583D01*
X589408Y325833D01*
X589200Y326208D01*
X589117Y326583D01*
Y327042D01*
X589200Y327417D01*
X589408Y327750D01*
X589658Y327917D01*
X589950Y328000D01*
X590283Y327917D01*
X590533Y327750D01*
X590700Y327500D01*
X590783Y327167D01*
X590700Y326875D01*
X590492Y326583D01*
X590242Y326417D01*
X589950Y326375D01*
X589617Y326458D01*
X589367Y326667D01*
X589117Y327042D01*
G01X582383Y475167D02*
Y477667D01*
X581342D01*
X581008Y477542D01*
X580800Y477375D01*
X580717Y477042D01*
X580800Y476709D01*
X581050Y476500D01*
X581342Y476375D01*
X582383D01*
G01X581342D02*
X580717Y475167D01*
G01X577950D02*
Y477667D01*
X579492Y475875D01*
X577408D01*
G01X592483Y483300D02*
Y485800D01*
X591442D01*
X591108Y485675D01*
X590900Y485508D01*
X590817Y485175D01*
X590900Y484842D01*
X591150Y484633D01*
X591442Y484508D01*
X592483D01*
G01X591442D02*
X590817Y483300D01*
G01X589467Y483675D02*
X589217Y483467D01*
X588925Y483342D01*
X588550Y483300D01*
X588175Y483383D01*
X587883Y483550D01*
X587675Y483842D01*
X587633Y484175D01*
X587717Y484508D01*
X587925Y484717D01*
X588217Y484883D01*
X588508Y484925D01*
X588800Y484883D01*
X589175Y484717D01*
X589050Y485800D01*
X587925D01*
G01X586158Y483592D02*
X585867Y483383D01*
X585533Y483300D01*
X585200Y483383D01*
X584908Y483633D01*
X584700Y484008D01*
X584617Y484383D01*
Y484842D01*
X584700Y485217D01*
X584908Y485550D01*
X585158Y485717D01*
X585450Y485800D01*
X585783Y485717D01*
X586033Y485550D01*
X586200Y485300D01*
X586283Y484967D01*
X586200Y484675D01*
X585992Y484383D01*
X585742Y484217D01*
X585450Y484175D01*
X585117Y484258D01*
X584867Y484467D01*
X584617Y484842D01*
G01X583058Y483592D02*
X582767Y483383D01*
X582433Y483300D01*
X582100Y483383D01*
X581808Y483633D01*
X581600Y484008D01*
X581517Y484383D01*
Y484842D01*
X581600Y485217D01*
X581808Y485550D01*
X582058Y485717D01*
X582350Y485800D01*
X582683Y485717D01*
X582933Y485550D01*
X583100Y485300D01*
X583183Y484967D01*
X583100Y484675D01*
X582892Y484383D01*
X582642Y484217D01*
X582350Y484175D01*
X582017Y484258D01*
X581767Y484467D01*
X581517Y484842D01*
G01X590733Y454292D02*
X590983Y454417D01*
X591275Y454500D01*
X591608D01*
X591983Y454375D01*
X592275Y454167D01*
X592483Y453917D01*
X592650Y453500D01*
X592692Y453125D01*
X592608Y452750D01*
X592483Y452500D01*
X592233Y452250D01*
X591942Y452083D01*
X591650Y452000D01*
X591358D01*
X591067Y452083D01*
X590817Y452208D01*
X590608Y452375D01*
G01X589342Y453042D02*
X589050Y453333D01*
X588800Y453500D01*
X588467Y453583D01*
X588175Y453500D01*
X587967Y453333D01*
X587800Y453083D01*
X587758Y452792D01*
X587800Y452542D01*
X587967Y452292D01*
X588217Y452083D01*
X588508Y452000D01*
X588842Y452083D01*
X589133Y452333D01*
X589300Y452708D01*
X589342Y453125D01*
X589258Y453667D01*
X589133Y453958D01*
X588925Y454250D01*
X588633Y454458D01*
X588342Y454500D01*
X588050Y454417D01*
X587842Y454208D01*
G01X585533Y452000D02*
X585450Y452542D01*
X585325Y453000D01*
X585158Y453417D01*
X584950Y453875D01*
X584617Y454500D01*
X586283D01*
G01X581850Y452000D02*
Y454500D01*
X583392Y452708D01*
X581308D01*
G01X591500Y456517D02*
X594000D01*
Y457558D01*
X593875Y457892D01*
X593708Y458100D01*
X593375Y458183D01*
X593042Y458100D01*
X592833Y457850D01*
X592708Y457558D01*
Y456517D01*
G01Y457558D02*
X591500Y458183D01*
G01X592000Y459533D02*
X591708Y459783D01*
X591542Y460117D01*
X591500Y460492D01*
X591542Y460825D01*
X591750Y461158D01*
X592000Y461367D01*
X592250Y461408D01*
X592542Y461325D01*
X592750Y461033D01*
X592833Y460742D01*
Y460367D01*
G01Y460742D02*
X592958Y460992D01*
X593167Y461200D01*
X593417Y461283D01*
X593667Y461200D01*
X593875Y460992D01*
X594000Y460617D01*
X593958Y460242D01*
X593792Y459867D01*
G01X591500Y463550D02*
X591542Y463842D01*
X591667Y464175D01*
X591875Y464383D01*
X592167Y464467D01*
X592458Y464383D01*
X592708Y464133D01*
X592833Y463758D01*
Y463342D01*
X592917Y463092D01*
X593125Y462883D01*
X593417Y462800D01*
X593708Y462925D01*
X593917Y463217D01*
X594000Y463550D01*
X593917Y463883D01*
X593708Y464175D01*
X593417Y464300D01*
X593125Y464217D01*
X592917Y464008D01*
X592833Y463758D01*
Y463342D01*
X592708Y462967D01*
X592458Y462717D01*
X592167Y462633D01*
X591875Y462717D01*
X591667Y462925D01*
X591542Y463258D01*
X591500Y463550D01*
G01Y466650D02*
X594000D01*
X593500Y466150D01*
G01X591500D02*
Y467150D01*
G01X618792Y452767D02*
X618917Y452517D01*
X619000Y452225D01*
Y451892D01*
X618875Y451517D01*
X618667Y451225D01*
X618417Y451017D01*
X618000Y450850D01*
X617625Y450808D01*
X617250Y450892D01*
X617000Y451017D01*
X616750Y451267D01*
X616583Y451558D01*
X616500Y451850D01*
Y452142D01*
X616583Y452433D01*
X616708Y452683D01*
X616875Y452892D01*
G01X617542Y454158D02*
X617833Y454450D01*
X618000Y454700D01*
X618083Y455033D01*
X618000Y455325D01*
X617833Y455533D01*
X617583Y455700D01*
X617292Y455742D01*
X617042Y455700D01*
X616792Y455533D01*
X616583Y455283D01*
X616500Y454992D01*
X616583Y454658D01*
X616833Y454367D01*
X617208Y454200D01*
X617625Y454158D01*
X618167Y454242D01*
X618458Y454367D01*
X618750Y454575D01*
X618958Y454867D01*
X619000Y455158D01*
X618917Y455450D01*
X618708Y455658D01*
G01X619000Y458050D02*
X618917Y457717D01*
X618708Y457467D01*
X618458Y457300D01*
X618125Y457175D01*
X617750Y457133D01*
X617375Y457175D01*
X617042Y457300D01*
X616792Y457467D01*
X616583Y457717D01*
X616500Y458050D01*
X616583Y458383D01*
X616792Y458633D01*
X617042Y458800D01*
X617375Y458925D01*
X617750Y458967D01*
X618125Y458925D01*
X618458Y458800D01*
X618708Y458633D01*
X618917Y458383D01*
X619000Y458050D01*
G01X616500Y461067D02*
X617042Y461150D01*
X617500Y461275D01*
X617917Y461442D01*
X618375Y461650D01*
X619000Y461983D01*
Y460317D01*
G01X613492Y434167D02*
X613617Y433917D01*
X613700Y433625D01*
Y433292D01*
X613575Y432917D01*
X613367Y432625D01*
X613117Y432417D01*
X612700Y432250D01*
X612325Y432208D01*
X611950Y432292D01*
X611700Y432417D01*
X611450Y432667D01*
X611283Y432958D01*
X611200Y433250D01*
Y433542D01*
X611283Y433833D01*
X611408Y434083D01*
X611575Y434292D01*
G01X611200Y436267D02*
X611742Y436350D01*
X612200Y436475D01*
X612617Y436642D01*
X613075Y436850D01*
X613700Y437183D01*
Y435517D01*
G01Y439450D02*
X613617Y439117D01*
X613408Y438867D01*
X613158Y438700D01*
X612825Y438575D01*
X612450Y438533D01*
X612075Y438575D01*
X611742Y438700D01*
X611492Y438867D01*
X611283Y439117D01*
X611200Y439450D01*
X611283Y439783D01*
X611492Y440033D01*
X611742Y440200D01*
X612075Y440325D01*
X612450Y440367D01*
X612825Y440325D01*
X613158Y440200D01*
X613408Y440033D01*
X613617Y439783D01*
X613700Y439450D01*
G01Y442550D02*
X613617Y442217D01*
X613408Y441967D01*
X613158Y441800D01*
X612825Y441675D01*
X612450Y441633D01*
X612075Y441675D01*
X611742Y441800D01*
X611492Y441967D01*
X611283Y442217D01*
X611200Y442550D01*
X611283Y442883D01*
X611492Y443133D01*
X611742Y443300D01*
X612075Y443425D01*
X612450Y443467D01*
X612825Y443425D01*
X613158Y443300D01*
X613408Y443133D01*
X613617Y442883D01*
X613700Y442550D01*
G01X634292Y434267D02*
X634417Y434017D01*
X634500Y433725D01*
Y433392D01*
X634375Y433017D01*
X634167Y432725D01*
X633917Y432517D01*
X633500Y432350D01*
X633125Y432308D01*
X632750Y432392D01*
X632500Y432517D01*
X632250Y432767D01*
X632083Y433058D01*
X632000Y433350D01*
Y433642D01*
X632083Y433933D01*
X632208Y434183D01*
X632375Y434392D01*
G01X633042Y435658D02*
X633333Y435950D01*
X633500Y436200D01*
X633583Y436533D01*
X633500Y436825D01*
X633333Y437033D01*
X633083Y437200D01*
X632792Y437242D01*
X632542Y437200D01*
X632292Y437033D01*
X632083Y436783D01*
X632000Y436492D01*
X632083Y436158D01*
X632333Y435867D01*
X632708Y435700D01*
X633125Y435658D01*
X633667Y435742D01*
X633958Y435867D01*
X634250Y436075D01*
X634458Y436367D01*
X634500Y436658D01*
X634417Y436950D01*
X634208Y437158D01*
G01X632292Y438842D02*
X632083Y439133D01*
X632000Y439467D01*
X632083Y439800D01*
X632333Y440092D01*
X632708Y440300D01*
X633083Y440383D01*
X633542D01*
X633917Y440300D01*
X634250Y440092D01*
X634417Y439842D01*
X634500Y439550D01*
X634417Y439217D01*
X634250Y438967D01*
X634000Y438800D01*
X633667Y438717D01*
X633375Y438800D01*
X633083Y439008D01*
X632917Y439258D01*
X632875Y439550D01*
X632958Y439883D01*
X633167Y440133D01*
X633542Y440383D01*
G01X632292Y441942D02*
X632083Y442233D01*
X632000Y442567D01*
X632083Y442900D01*
X632333Y443192D01*
X632708Y443400D01*
X633083Y443483D01*
X633542D01*
X633917Y443400D01*
X634250Y443192D01*
X634417Y442942D01*
X634500Y442650D01*
X634417Y442317D01*
X634250Y442067D01*
X634000Y441900D01*
X633667Y441817D01*
X633375Y441900D01*
X633083Y442108D01*
X632917Y442358D01*
X632875Y442650D01*
X632958Y442983D01*
X633167Y443233D01*
X633542Y443483D01*
G01X592483Y487800D02*
Y490300D01*
X591442D01*
X591108Y490175D01*
X590900Y490008D01*
X590817Y489675D01*
X590900Y489342D01*
X591150Y489133D01*
X591442Y489008D01*
X592483D01*
G01X591442D02*
X590817Y487800D01*
G01X589342Y488842D02*
X589050Y489133D01*
X588800Y489300D01*
X588467Y489383D01*
X588175Y489300D01*
X587967Y489133D01*
X587800Y488883D01*
X587758Y488592D01*
X587800Y488342D01*
X587967Y488092D01*
X588217Y487883D01*
X588508Y487800D01*
X588842Y487883D01*
X589133Y488133D01*
X589300Y488508D01*
X589342Y488925D01*
X589258Y489467D01*
X589133Y489758D01*
X588925Y490050D01*
X588633Y490258D01*
X588342Y490300D01*
X588050Y490217D01*
X587842Y490008D01*
G01X585450Y490300D02*
X585783Y490217D01*
X586033Y490008D01*
X586200Y489758D01*
X586325Y489425D01*
X586367Y489050D01*
X586325Y488675D01*
X586200Y488342D01*
X586033Y488092D01*
X585783Y487883D01*
X585450Y487800D01*
X585117Y487883D01*
X584867Y488092D01*
X584700Y488342D01*
X584575Y488675D01*
X584533Y489050D01*
X584575Y489425D01*
X584700Y489758D01*
X584867Y490008D01*
X585117Y490217D01*
X585450Y490300D01*
G01X582350Y487800D02*
Y490300D01*
X582850Y489800D01*
G01Y487800D02*
X581850D01*
G01X666000Y27983D02*
X664208D01*
X663833Y28150D01*
X663583Y28483D01*
X663500Y28900D01*
X663583Y29317D01*
X663833Y29650D01*
X664208Y29817D01*
X666000D01*
G01X663875Y31083D02*
X663667Y31333D01*
X663542Y31625D01*
X663500Y32000D01*
X663583Y32375D01*
X663750Y32667D01*
X664042Y32875D01*
X664375Y32917D01*
X664708Y32833D01*
X664917Y32625D01*
X665083Y32333D01*
X665125Y32042D01*
X665083Y31750D01*
X664917Y31375D01*
X666000Y31500D01*
Y32625D01*
G01Y35100D02*
X665917Y34767D01*
X665708Y34517D01*
X665458Y34350D01*
X665125Y34225D01*
X664750Y34183D01*
X664375Y34225D01*
X664042Y34350D01*
X663792Y34517D01*
X663583Y34767D01*
X663500Y35100D01*
X663583Y35433D01*
X663792Y35683D01*
X664042Y35850D01*
X664375Y35975D01*
X664750Y36017D01*
X665125Y35975D01*
X665458Y35850D01*
X665708Y35683D01*
X665917Y35433D01*
X666000Y35100D01*
G01X648166Y29100D02*
X661566D01*
G01X648166Y39100D02*
Y29100D01*
G01X661566Y39100D02*
X648166D01*
G01X661566Y29100D02*
Y39100D01*
G01X646983Y17000D02*
Y19500D01*
X645942D01*
X645608Y19375D01*
X645400Y19208D01*
X645317Y18875D01*
X645400Y18542D01*
X645650Y18333D01*
X645942Y18208D01*
X646983D01*
G01X645942D02*
X645317Y17000D01*
G01X643967Y17375D02*
X643717Y17167D01*
X643425Y17042D01*
X643050Y17000D01*
X642675Y17083D01*
X642383Y17250D01*
X642175Y17542D01*
X642133Y17875D01*
X642217Y18208D01*
X642425Y18417D01*
X642717Y18583D01*
X643008Y18625D01*
X643300Y18583D01*
X643675Y18417D01*
X643550Y19500D01*
X642425D01*
G01X640033Y17000D02*
X639950Y17542D01*
X639825Y18000D01*
X639658Y18417D01*
X639450Y18875D01*
X639117Y19500D01*
X640783D01*
G01X636850Y17000D02*
X636558Y17042D01*
X636225Y17167D01*
X636017Y17375D01*
X635933Y17667D01*
X636017Y17958D01*
X636267Y18208D01*
X636642Y18333D01*
X637058D01*
X637308Y18417D01*
X637517Y18625D01*
X637600Y18917D01*
X637475Y19208D01*
X637183Y19417D01*
X636850Y19500D01*
X636517Y19417D01*
X636225Y19208D01*
X636100Y18917D01*
X636183Y18625D01*
X636392Y18417D01*
X636642Y18333D01*
X637058D01*
X637433Y18208D01*
X637683Y17958D01*
X637767Y17667D01*
X637683Y17375D01*
X637475Y17167D01*
X637142Y17042D01*
X636850Y17000D01*
G01X646710Y20867D02*
X642710D01*
Y28267D01*
G01X685498Y35271D02*
X687998D01*
Y36312D01*
X687873Y36646D01*
X687706Y36854D01*
X687373Y36937D01*
X687040Y36854D01*
X686831Y36604D01*
X686706Y36312D01*
Y35271D01*
G01Y36312D02*
X685498Y36937D01*
G01X685873Y38287D02*
X685665Y38537D01*
X685540Y38829D01*
X685498Y39204D01*
X685581Y39579D01*
X685748Y39871D01*
X686040Y40079D01*
X686373Y40121D01*
X686706Y40037D01*
X686915Y39829D01*
X687081Y39537D01*
X687123Y39246D01*
X687081Y38954D01*
X686915Y38579D01*
X687998Y38704D01*
Y39829D01*
G01X685498Y42221D02*
X686040Y42304D01*
X686498Y42429D01*
X686915Y42596D01*
X687373Y42804D01*
X687998Y43137D01*
Y41471D01*
G01X685498Y45321D02*
X686040Y45404D01*
X686498Y45529D01*
X686915Y45696D01*
X687373Y45904D01*
X687998Y46237D01*
Y44571D01*
G01X657850Y52200D02*
X661850D01*
Y44800D01*
G01X671790Y37227D02*
X671915Y36977D01*
X671998Y36685D01*
Y36352D01*
X671873Y35977D01*
X671665Y35685D01*
X671415Y35477D01*
X670998Y35310D01*
X670623Y35268D01*
X670248Y35352D01*
X669998Y35477D01*
X669748Y35727D01*
X669581Y36018D01*
X669498Y36310D01*
Y36602D01*
X669581Y36893D01*
X669706Y37143D01*
X669873Y37352D01*
G01X669498Y39410D02*
X671998D01*
X671498Y38910D01*
G01X669498D02*
Y39910D01*
G01X671998Y42510D02*
X671915Y42177D01*
X671706Y41927D01*
X671456Y41760D01*
X671123Y41635D01*
X670748Y41593D01*
X670373Y41635D01*
X670040Y41760D01*
X669790Y41927D01*
X669581Y42177D01*
X669498Y42510D01*
X669581Y42843D01*
X669790Y43093D01*
X670040Y43260D01*
X670373Y43385D01*
X670748Y43427D01*
X671123Y43385D01*
X671456Y43260D01*
X671706Y43093D01*
X671915Y42843D01*
X671998Y42510D01*
G01X669498Y46110D02*
X671998D01*
X670206Y44568D01*
Y46652D01*
G01X675790Y37227D02*
X675915Y36977D01*
X675998Y36685D01*
Y36352D01*
X675873Y35977D01*
X675665Y35685D01*
X675415Y35477D01*
X674998Y35310D01*
X674623Y35268D01*
X674248Y35352D01*
X673998Y35477D01*
X673748Y35727D01*
X673581Y36018D01*
X673498Y36310D01*
Y36602D01*
X673581Y36893D01*
X673706Y37143D01*
X673873Y37352D01*
G01Y38493D02*
X673665Y38743D01*
X673540Y39035D01*
X673498Y39410D01*
X673581Y39785D01*
X673748Y40077D01*
X674040Y40285D01*
X674373Y40327D01*
X674706Y40243D01*
X674915Y40035D01*
X675081Y39743D01*
X675123Y39452D01*
X675081Y39160D01*
X674915Y38785D01*
X675998Y38910D01*
Y40035D01*
G01Y42510D02*
X675915Y42177D01*
X675706Y41927D01*
X675456Y41760D01*
X675123Y41635D01*
X674748Y41593D01*
X674373Y41635D01*
X674040Y41760D01*
X673790Y41927D01*
X673581Y42177D01*
X673498Y42510D01*
X673581Y42843D01*
X673790Y43093D01*
X674040Y43260D01*
X674373Y43385D01*
X674748Y43427D01*
X675123Y43385D01*
X675456Y43260D01*
X675706Y43093D01*
X675915Y42843D01*
X675998Y42510D01*
G01X675581Y44818D02*
X675831Y45068D01*
X675956Y45360D01*
X675998Y45693D01*
X675915Y46110D01*
X675706Y46402D01*
X675456Y46485D01*
X675206Y46443D01*
X674998Y46277D01*
X674581Y45443D01*
X674290Y45068D01*
X673873Y44818D01*
X673498Y44735D01*
Y46485D01*
G01X676233Y24792D02*
X676483Y24917D01*
X676775Y25000D01*
X677108D01*
X677483Y24875D01*
X677775Y24667D01*
X677983Y24417D01*
X678150Y24000D01*
X678192Y23625D01*
X678108Y23250D01*
X677983Y23000D01*
X677733Y22750D01*
X677442Y22583D01*
X677150Y22500D01*
X676858D01*
X676567Y22583D01*
X676317Y22708D01*
X676108Y22875D01*
G01X674967D02*
X674717Y22667D01*
X674425Y22542D01*
X674050Y22500D01*
X673675Y22583D01*
X673383Y22750D01*
X673175Y23042D01*
X673133Y23375D01*
X673217Y23708D01*
X673425Y23917D01*
X673717Y24083D01*
X674008Y24125D01*
X674300Y24083D01*
X674675Y23917D01*
X674550Y25000D01*
X673425D01*
G01X670950D02*
X671283Y24917D01*
X671533Y24708D01*
X671700Y24458D01*
X671825Y24125D01*
X671867Y23750D01*
X671825Y23375D01*
X671700Y23042D01*
X671533Y22792D01*
X671283Y22583D01*
X670950Y22500D01*
X670617Y22583D01*
X670367Y22792D01*
X670200Y23042D01*
X670075Y23375D01*
X670033Y23750D01*
X670075Y24125D01*
X670200Y24458D01*
X670367Y24708D01*
X670617Y24917D01*
X670950Y25000D01*
G01X668767Y22875D02*
X668517Y22667D01*
X668225Y22542D01*
X667850Y22500D01*
X667475Y22583D01*
X667183Y22750D01*
X666975Y23042D01*
X666933Y23375D01*
X667017Y23708D01*
X667225Y23917D01*
X667517Y24083D01*
X667808Y24125D01*
X668100Y24083D01*
X668475Y23917D01*
X668350Y25000D01*
X667225D01*
G01X679790Y37227D02*
X679915Y36977D01*
X679998Y36685D01*
Y36352D01*
X679873Y35977D01*
X679665Y35685D01*
X679415Y35477D01*
X678998Y35310D01*
X678623Y35268D01*
X678248Y35352D01*
X677998Y35477D01*
X677748Y35727D01*
X677581Y36018D01*
X677498Y36310D01*
Y36602D01*
X677581Y36893D01*
X677706Y37143D01*
X677873Y37352D01*
G01Y38493D02*
X677665Y38743D01*
X677540Y39035D01*
X677498Y39410D01*
X677581Y39785D01*
X677748Y40077D01*
X678040Y40285D01*
X678373Y40327D01*
X678706Y40243D01*
X678915Y40035D01*
X679081Y39743D01*
X679123Y39452D01*
X679081Y39160D01*
X678915Y38785D01*
X679998Y38910D01*
Y40035D01*
G01Y42510D02*
X679915Y42177D01*
X679706Y41927D01*
X679456Y41760D01*
X679123Y41635D01*
X678748Y41593D01*
X678373Y41635D01*
X678040Y41760D01*
X677790Y41927D01*
X677581Y42177D01*
X677498Y42510D01*
X677581Y42843D01*
X677790Y43093D01*
X678040Y43260D01*
X678373Y43385D01*
X678748Y43427D01*
X679123Y43385D01*
X679456Y43260D01*
X679706Y43093D01*
X679915Y42843D01*
X679998Y42510D01*
G01X677790Y44902D02*
X677581Y45193D01*
X677498Y45527D01*
X677581Y45860D01*
X677831Y46152D01*
X678206Y46360D01*
X678581Y46443D01*
X679040D01*
X679415Y46360D01*
X679748Y46152D01*
X679915Y45902D01*
X679998Y45610D01*
X679915Y45277D01*
X679748Y45027D01*
X679498Y44860D01*
X679165Y44777D01*
X678873Y44860D01*
X678581Y45068D01*
X678415Y45318D01*
X678373Y45610D01*
X678456Y45943D01*
X678665Y46193D01*
X679040Y46443D01*
G01X638364Y35913D02*
X638489Y35663D01*
X638572Y35371D01*
Y35038D01*
X638447Y34663D01*
X638239Y34371D01*
X637989Y34163D01*
X637572Y33996D01*
X637197Y33954D01*
X636822Y34038D01*
X636572Y34163D01*
X636322Y34413D01*
X636155Y34704D01*
X636072Y34996D01*
Y35288D01*
X636155Y35579D01*
X636280Y35829D01*
X636447Y36038D01*
G01X636072Y38013D02*
X636614Y38096D01*
X637072Y38221D01*
X637489Y38388D01*
X637947Y38596D01*
X638572Y38929D01*
Y37263D01*
G01X636572Y40279D02*
X636280Y40529D01*
X636114Y40863D01*
X636072Y41238D01*
X636114Y41571D01*
X636322Y41904D01*
X636572Y42113D01*
X636822Y42154D01*
X637114Y42071D01*
X637322Y41779D01*
X637405Y41488D01*
Y41113D01*
G01Y41488D02*
X637530Y41738D01*
X637739Y41946D01*
X637989Y42029D01*
X638239Y41946D01*
X638447Y41738D01*
X638572Y41363D01*
X638530Y40988D01*
X638364Y40613D01*
G01X636447Y43379D02*
X636239Y43629D01*
X636114Y43921D01*
X636072Y44296D01*
X636155Y44671D01*
X636322Y44963D01*
X636614Y45171D01*
X636947Y45213D01*
X637280Y45129D01*
X637489Y44921D01*
X637655Y44629D01*
X637697Y44338D01*
X637655Y44046D01*
X637489Y43671D01*
X638572Y43796D01*
Y44921D01*
G01X683790Y37021D02*
X683915Y36771D01*
X683998Y36479D01*
Y36146D01*
X683873Y35771D01*
X683665Y35479D01*
X683415Y35271D01*
X682998Y35104D01*
X682623Y35062D01*
X682248Y35146D01*
X681998Y35271D01*
X681748Y35521D01*
X681581Y35812D01*
X681498Y36104D01*
Y36396D01*
X681581Y36687D01*
X681706Y36937D01*
X681873Y37146D01*
G01X681498Y39121D02*
X682040Y39204D01*
X682498Y39329D01*
X682915Y39496D01*
X683373Y39704D01*
X683998Y40037D01*
Y38371D01*
G01X681498Y42804D02*
X683998D01*
X682206Y41262D01*
Y43346D01*
G01X683998Y45404D02*
X683915Y45071D01*
X683706Y44821D01*
X683456Y44654D01*
X683123Y44529D01*
X682748Y44487D01*
X682373Y44529D01*
X682040Y44654D01*
X681790Y44821D01*
X681581Y45071D01*
X681498Y45404D01*
X681581Y45737D01*
X681790Y45987D01*
X682040Y46154D01*
X682373Y46279D01*
X682748Y46321D01*
X683123Y46279D01*
X683456Y46154D01*
X683706Y45987D01*
X683915Y45737D01*
X683998Y45404D01*
G01X645233Y108792D02*
X645483Y108917D01*
X645775Y109000D01*
X646108D01*
X646483Y108875D01*
X646775Y108667D01*
X646983Y108417D01*
X647150Y108000D01*
X647192Y107625D01*
X647108Y107250D01*
X646983Y107000D01*
X646733Y106750D01*
X646442Y106583D01*
X646150Y106500D01*
X645858D01*
X645567Y106583D01*
X645317Y106708D01*
X645108Y106875D01*
G01X643967Y107000D02*
X643717Y106708D01*
X643383Y106542D01*
X643008Y106500D01*
X642675Y106542D01*
X642342Y106750D01*
X642133Y107000D01*
X642092Y107250D01*
X642175Y107542D01*
X642467Y107750D01*
X642758Y107833D01*
X643133D01*
G01X642758D02*
X642508Y107958D01*
X642300Y108167D01*
X642217Y108417D01*
X642300Y108667D01*
X642508Y108875D01*
X642883Y109000D01*
X643258Y108958D01*
X643633Y108792D01*
G01X640658Y106792D02*
X640367Y106583D01*
X640033Y106500D01*
X639700Y106583D01*
X639408Y106833D01*
X639200Y107208D01*
X639117Y107583D01*
Y108042D01*
X639200Y108417D01*
X639408Y108750D01*
X639658Y108917D01*
X639950Y109000D01*
X640283Y108917D01*
X640533Y108750D01*
X640700Y108500D01*
X640783Y108167D01*
X640700Y107875D01*
X640492Y107583D01*
X640242Y107417D01*
X639950Y107375D01*
X639617Y107458D01*
X639367Y107667D01*
X639117Y108042D01*
G01X637642Y108583D02*
X637392Y108833D01*
X637100Y108958D01*
X636767Y109000D01*
X636350Y108917D01*
X636058Y108708D01*
X635975Y108458D01*
X636017Y108208D01*
X636183Y108000D01*
X637017Y107583D01*
X637392Y107292D01*
X637642Y106875D01*
X637725Y106500D01*
X635975D01*
G01X645116Y104788D02*
X645366Y104913D01*
X645658Y104996D01*
X645991D01*
X646366Y104871D01*
X646658Y104663D01*
X646866Y104413D01*
X647033Y103996D01*
X647075Y103621D01*
X646991Y103246D01*
X646866Y102996D01*
X646616Y102746D01*
X646325Y102579D01*
X646033Y102496D01*
X645741D01*
X645450Y102579D01*
X645200Y102704D01*
X644991Y102871D01*
G01X643850Y102996D02*
X643600Y102704D01*
X643266Y102538D01*
X642891Y102496D01*
X642558Y102538D01*
X642225Y102746D01*
X642016Y102996D01*
X641975Y103246D01*
X642058Y103538D01*
X642350Y103746D01*
X642641Y103829D01*
X643016D01*
G01X642641D02*
X642391Y103954D01*
X642183Y104163D01*
X642100Y104413D01*
X642183Y104663D01*
X642391Y104871D01*
X642766Y104996D01*
X643141Y104954D01*
X643516Y104788D01*
G01X639833Y102496D02*
X639541Y102538D01*
X639208Y102663D01*
X639000Y102871D01*
X638916Y103163D01*
X639000Y103454D01*
X639250Y103704D01*
X639625Y103829D01*
X640041D01*
X640291Y103913D01*
X640500Y104121D01*
X640583Y104413D01*
X640458Y104704D01*
X640166Y104913D01*
X639833Y104996D01*
X639500Y104913D01*
X639208Y104704D01*
X639083Y104413D01*
X639166Y104121D01*
X639375Y103913D01*
X639625Y103829D01*
X640041D01*
X640416Y103704D01*
X640666Y103454D01*
X640750Y103163D01*
X640666Y102871D01*
X640458Y102663D01*
X640125Y102538D01*
X639833Y102496D01*
G01X636816D02*
X636733Y103038D01*
X636608Y103496D01*
X636441Y103913D01*
X636233Y104371D01*
X635900Y104996D01*
X637566D01*
G01X639003Y67709D02*
X643003D01*
Y60309D01*
G01X699914Y105910D02*
Y107989D01*
X697612D01*
Y117517D01*
X695000D01*
Y123500D01*
X693500D01*
Y124500D01*
X680500D01*
G01X674000D02*
X662500D01*
Y127000D01*
X656000D01*
Y138000D01*
X659500D01*
Y148000D01*
X656000D01*
Y156000D01*
X664500D01*
Y171500D01*
X661500D01*
Y193500D01*
X679000D01*
Y197000D01*
X687000D01*
Y193500D01*
X694000D01*
Y196500D01*
X701500D01*
Y197500D01*
X731500D01*
Y193641D01*
X728500D01*
Y149000D01*
X746500D01*
Y138000D01*
X750000D01*
Y136500D01*
G01X678292Y117667D02*
X678417Y117417D01*
X678500Y117125D01*
Y116792D01*
X678375Y116417D01*
X678167Y116125D01*
X677917Y115917D01*
X677500Y115750D01*
X677125Y115708D01*
X676750Y115792D01*
X676500Y115917D01*
X676250Y116167D01*
X676083Y116458D01*
X676000Y116750D01*
Y117042D01*
X676083Y117333D01*
X676208Y117583D01*
X676375Y117792D01*
G01X676500Y118933D02*
X676208Y119183D01*
X676042Y119517D01*
X676000Y119892D01*
X676042Y120225D01*
X676250Y120558D01*
X676500Y120767D01*
X676750Y120808D01*
X677042Y120725D01*
X677250Y120433D01*
X677333Y120142D01*
Y119767D01*
G01Y120142D02*
X677458Y120392D01*
X677667Y120600D01*
X677917Y120683D01*
X678167Y120600D01*
X678375Y120392D01*
X678500Y120017D01*
X678458Y119642D01*
X678292Y119267D01*
G01X676000Y122950D02*
X676042Y123242D01*
X676167Y123575D01*
X676375Y123783D01*
X676667Y123867D01*
X676958Y123783D01*
X677208Y123533D01*
X677333Y123158D01*
Y122742D01*
X677417Y122492D01*
X677625Y122283D01*
X677917Y122200D01*
X678208Y122325D01*
X678417Y122617D01*
X678500Y122950D01*
X678417Y123283D01*
X678208Y123575D01*
X677917Y123700D01*
X677625Y123617D01*
X677417Y123408D01*
X677333Y123158D01*
Y122742D01*
X677208Y122367D01*
X676958Y122117D01*
X676667Y122033D01*
X676375Y122117D01*
X676167Y122325D01*
X676042Y122658D01*
X676000Y122950D01*
G01X676292Y125342D02*
X676083Y125633D01*
X676000Y125967D01*
X676083Y126300D01*
X676333Y126592D01*
X676708Y126800D01*
X677083Y126883D01*
X677542D01*
X677917Y126800D01*
X678250Y126592D01*
X678417Y126342D01*
X678500Y126050D01*
X678417Y125717D01*
X678250Y125467D01*
X678000Y125300D01*
X677667Y125217D01*
X677375Y125300D01*
X677083Y125508D01*
X676917Y125758D01*
X676875Y126050D01*
X676958Y126383D01*
X677167Y126633D01*
X677542Y126883D01*
G01X652313Y164929D02*
Y168929D01*
X659713D01*
G01X647200Y168000D02*
Y164000D01*
X639800D01*
G01X645233Y142459D02*
X645483Y142584D01*
X645775Y142667D01*
X646108D01*
X646483Y142542D01*
X646775Y142334D01*
X646983Y142084D01*
X647150Y141667D01*
X647192Y141292D01*
X647108Y140917D01*
X646983Y140667D01*
X646733Y140417D01*
X646442Y140250D01*
X646150Y140167D01*
X645858D01*
X645567Y140250D01*
X645317Y140375D01*
X645108Y140542D01*
G01X643967Y140667D02*
X643717Y140375D01*
X643383Y140209D01*
X643008Y140167D01*
X642675Y140209D01*
X642342Y140417D01*
X642133Y140667D01*
X642092Y140917D01*
X642175Y141209D01*
X642467Y141417D01*
X642758Y141500D01*
X643133D01*
G01X642758D02*
X642508Y141625D01*
X642300Y141834D01*
X642217Y142084D01*
X642300Y142334D01*
X642508Y142542D01*
X642883Y142667D01*
X643258Y142625D01*
X643633Y142459D01*
G01X640658Y140459D02*
X640367Y140250D01*
X640033Y140167D01*
X639700Y140250D01*
X639408Y140500D01*
X639200Y140875D01*
X639117Y141250D01*
Y141709D01*
X639200Y142084D01*
X639408Y142417D01*
X639658Y142584D01*
X639950Y142667D01*
X640283Y142584D01*
X640533Y142417D01*
X640700Y142167D01*
X640783Y141834D01*
X640700Y141542D01*
X640492Y141250D01*
X640242Y141084D01*
X639950Y141042D01*
X639617Y141125D01*
X639367Y141334D01*
X639117Y141709D01*
G01X636933Y140167D02*
X636850Y140709D01*
X636725Y141167D01*
X636558Y141584D01*
X636350Y142042D01*
X636017Y142667D01*
X637683D01*
G01X673292Y220767D02*
X673417Y220517D01*
X673500Y220225D01*
Y219892D01*
X673375Y219517D01*
X673167Y219225D01*
X672917Y219017D01*
X672500Y218850D01*
X672125Y218808D01*
X671750Y218892D01*
X671500Y219017D01*
X671250Y219267D01*
X671083Y219558D01*
X671000Y219850D01*
Y220142D01*
X671083Y220433D01*
X671208Y220683D01*
X671375Y220892D01*
G01X671000Y223450D02*
X673500D01*
X671708Y221908D01*
Y223992D01*
G01X672042Y225258D02*
X672333Y225550D01*
X672500Y225800D01*
X672583Y226133D01*
X672500Y226425D01*
X672333Y226633D01*
X672083Y226800D01*
X671792Y226842D01*
X671542Y226800D01*
X671292Y226633D01*
X671083Y226383D01*
X671000Y226092D01*
X671083Y225758D01*
X671333Y225467D01*
X671708Y225300D01*
X672125Y225258D01*
X672667Y225342D01*
X672958Y225467D01*
X673250Y225675D01*
X673458Y225967D01*
X673500Y226258D01*
X673417Y226550D01*
X673208Y226758D01*
G01X671375Y228233D02*
X671167Y228483D01*
X671042Y228775D01*
X671000Y229150D01*
X671083Y229525D01*
X671250Y229817D01*
X671542Y230025D01*
X671875Y230067D01*
X672208Y229983D01*
X672417Y229775D01*
X672583Y229483D01*
X672625Y229192D01*
X672583Y228900D01*
X672417Y228525D01*
X673500Y228650D01*
Y229775D01*
G01X638000Y208700D02*
X642000D01*
Y201300D01*
G01X646000Y208700D02*
X650000D01*
Y201300D01*
G01Y208700D02*
X654000D01*
Y201300D01*
G01X642000Y208700D02*
X646000D01*
Y201300D01*
G01X654000Y208700D02*
X658000D01*
Y201300D01*
G01X663500Y201017D02*
X666000D01*
Y202058D01*
X665875Y202392D01*
X665708Y202600D01*
X665375Y202683D01*
X665042Y202600D01*
X664833Y202350D01*
X664708Y202058D01*
Y201017D01*
G01Y202058D02*
X663500Y202683D01*
G01X665583Y204158D02*
X665833Y204408D01*
X665958Y204700D01*
X666000Y205033D01*
X665917Y205450D01*
X665708Y205742D01*
X665458Y205825D01*
X665208Y205783D01*
X665000Y205617D01*
X664583Y204783D01*
X664292Y204408D01*
X663875Y204158D01*
X663500Y204075D01*
Y205825D01*
G01X664542Y207258D02*
X664833Y207550D01*
X665000Y207800D01*
X665083Y208133D01*
X665000Y208425D01*
X664833Y208633D01*
X664583Y208800D01*
X664292Y208842D01*
X664042Y208800D01*
X663792Y208633D01*
X663583Y208383D01*
X663500Y208092D01*
X663583Y207758D01*
X663833Y207467D01*
X664208Y207300D01*
X664625Y207258D01*
X665167Y207342D01*
X665458Y207467D01*
X665750Y207675D01*
X665958Y207967D01*
X666000Y208258D01*
X665917Y208550D01*
X665708Y208758D01*
G01X663500Y211150D02*
X666000D01*
X665500Y210650D01*
G01X663500D02*
Y211650D01*
G01X658000Y208700D02*
X662000D01*
Y201300D01*
G01X675500Y206517D02*
X678000D01*
Y207558D01*
X677875Y207892D01*
X677708Y208100D01*
X677375Y208183D01*
X677042Y208100D01*
X676833Y207850D01*
X676708Y207558D01*
Y206517D01*
G01Y207558D02*
X675500Y208183D01*
G01X677583Y209658D02*
X677833Y209908D01*
X677958Y210200D01*
X678000Y210533D01*
X677917Y210950D01*
X677708Y211242D01*
X677458Y211325D01*
X677208Y211283D01*
X677000Y211117D01*
X676583Y210283D01*
X676292Y209908D01*
X675875Y209658D01*
X675500Y209575D01*
Y211325D01*
G01X676000Y212633D02*
X675708Y212883D01*
X675542Y213217D01*
X675500Y213592D01*
X675542Y213925D01*
X675750Y214258D01*
X676000Y214467D01*
X676250Y214508D01*
X676542Y214425D01*
X676750Y214133D01*
X676833Y213842D01*
Y213467D01*
G01Y213842D02*
X676958Y214092D01*
X677167Y214300D01*
X677417Y214383D01*
X677667Y214300D01*
X677875Y214092D01*
X678000Y213717D01*
X677958Y213342D01*
X677792Y212967D01*
G01X677583Y215858D02*
X677833Y216108D01*
X677958Y216400D01*
X678000Y216733D01*
X677917Y217150D01*
X677708Y217442D01*
X677458Y217525D01*
X677208Y217483D01*
X677000Y217317D01*
X676583Y216483D01*
X676292Y216108D01*
X675875Y215858D01*
X675500Y215775D01*
Y217525D01*
G01X684784Y203545D02*
Y199545D01*
X677384D01*
G01X695000Y217017D02*
X697500D01*
Y218058D01*
X697375Y218392D01*
X697208Y218600D01*
X696875Y218683D01*
X696542Y218600D01*
X696333Y218350D01*
X696208Y218058D01*
Y217017D01*
G01Y218058D02*
X695000Y218683D01*
G01X697083Y220158D02*
X697333Y220408D01*
X697458Y220700D01*
X697500Y221033D01*
X697417Y221450D01*
X697208Y221742D01*
X696958Y221825D01*
X696708Y221783D01*
X696500Y221617D01*
X696083Y220783D01*
X695792Y220408D01*
X695375Y220158D01*
X695000Y220075D01*
Y221825D01*
G01X697083Y223258D02*
X697333Y223508D01*
X697458Y223800D01*
X697500Y224133D01*
X697417Y224550D01*
X697208Y224842D01*
X696958Y224925D01*
X696708Y224883D01*
X696500Y224717D01*
X696083Y223883D01*
X695792Y223508D01*
X695375Y223258D01*
X695000Y223175D01*
Y224925D01*
G01X697500Y227150D02*
X697417Y226817D01*
X697208Y226567D01*
X696958Y226400D01*
X696625Y226275D01*
X696250Y226233D01*
X695875Y226275D01*
X695542Y226400D01*
X695292Y226567D01*
X695083Y226817D01*
X695000Y227150D01*
X695083Y227483D01*
X695292Y227733D01*
X695542Y227900D01*
X695875Y228025D01*
X696250Y228067D01*
X696625Y228025D01*
X696958Y227900D01*
X697208Y227733D01*
X697417Y227483D01*
X697500Y227150D01*
G01X700541Y197189D02*
X696541D01*
Y204589D01*
G01X707983Y235667D02*
Y238167D01*
X706942D01*
X706608Y238042D01*
X706400Y237875D01*
X706317Y237542D01*
X706400Y237209D01*
X706650Y237000D01*
X706942Y236875D01*
X707983D01*
G01X706942D02*
X706317Y235667D01*
G01X703550D02*
Y238167D01*
X705092Y236375D01*
X703008D01*
G01X700950Y238167D02*
X701283Y238084D01*
X701533Y237875D01*
X701700Y237625D01*
X701825Y237292D01*
X701867Y236917D01*
X701825Y236542D01*
X701700Y236209D01*
X701533Y235959D01*
X701283Y235750D01*
X700950Y235667D01*
X700617Y235750D01*
X700367Y235959D01*
X700200Y236209D01*
X700075Y236542D01*
X700033Y236917D01*
X700075Y237292D01*
X700200Y237625D01*
X700367Y237875D01*
X700617Y238084D01*
X700950Y238167D01*
G01X698642Y237750D02*
X698392Y238000D01*
X698100Y238125D01*
X697767Y238167D01*
X697350Y238084D01*
X697058Y237875D01*
X696975Y237625D01*
X697017Y237375D01*
X697183Y237167D01*
X698017Y236750D01*
X698392Y236459D01*
X698642Y236042D01*
X698725Y235667D01*
X696975D01*
G01X695450Y238469D02*
Y234469D01*
X688050D01*
G01X700483Y230500D02*
Y233000D01*
X699442D01*
X699108Y232875D01*
X698900Y232708D01*
X698817Y232375D01*
X698900Y232042D01*
X699150Y231833D01*
X699442Y231708D01*
X700483D01*
G01X699442D02*
X698817Y230500D01*
G01X696050D02*
Y233000D01*
X697592Y231208D01*
X695508D01*
G01X694158Y230792D02*
X693867Y230583D01*
X693533Y230500D01*
X693200Y230583D01*
X692908Y230833D01*
X692700Y231208D01*
X692617Y231583D01*
Y232042D01*
X692700Y232417D01*
X692908Y232750D01*
X693158Y232917D01*
X693450Y233000D01*
X693783Y232917D01*
X694033Y232750D01*
X694200Y232500D01*
X694283Y232167D01*
X694200Y231875D01*
X693992Y231583D01*
X693742Y231417D01*
X693450Y231375D01*
X693117Y231458D01*
X692867Y231667D01*
X692617Y232042D01*
G01X690350Y230500D02*
X690058Y230542D01*
X689725Y230667D01*
X689517Y230875D01*
X689433Y231167D01*
X689517Y231458D01*
X689767Y231708D01*
X690142Y231833D01*
X690558D01*
X690808Y231917D01*
X691017Y232125D01*
X691100Y232417D01*
X690975Y232708D01*
X690683Y232917D01*
X690350Y233000D01*
X690017Y232917D01*
X689725Y232708D01*
X689600Y232417D01*
X689683Y232125D01*
X689892Y231917D01*
X690142Y231833D01*
X690558D01*
X690933Y231708D01*
X691183Y231458D01*
X691267Y231167D01*
X691183Y230875D01*
X690975Y230667D01*
X690642Y230542D01*
X690350Y230500D01*
G01X697700Y212200D02*
Y208200D01*
X690300D01*
G01X686483Y230500D02*
Y233000D01*
X685442D01*
X685108Y232875D01*
X684900Y232708D01*
X684817Y232375D01*
X684900Y232042D01*
X685150Y231833D01*
X685442Y231708D01*
X686483D01*
G01X685442D02*
X684817Y230500D01*
G01X682050D02*
Y233000D01*
X683592Y231208D01*
X681508D01*
G01X680158Y230792D02*
X679867Y230583D01*
X679533Y230500D01*
X679200Y230583D01*
X678908Y230833D01*
X678700Y231208D01*
X678617Y231583D01*
Y232042D01*
X678700Y232417D01*
X678908Y232750D01*
X679158Y232917D01*
X679450Y233000D01*
X679783Y232917D01*
X680033Y232750D01*
X680200Y232500D01*
X680283Y232167D01*
X680200Y231875D01*
X679992Y231583D01*
X679742Y231417D01*
X679450Y231375D01*
X679117Y231458D01*
X678867Y231667D01*
X678617Y232042D01*
G01X676433Y230500D02*
X676350Y231042D01*
X676225Y231500D01*
X676058Y231917D01*
X675850Y232375D01*
X675517Y233000D01*
X677183D01*
G01X682800Y208200D02*
Y212200D01*
X690200D01*
G01X687792Y215267D02*
X687917Y215017D01*
X688000Y214725D01*
Y214392D01*
X687875Y214017D01*
X687667Y213725D01*
X687417Y213517D01*
X687000Y213350D01*
X686625Y213308D01*
X686250Y213392D01*
X686000Y213517D01*
X685750Y213767D01*
X685583Y214058D01*
X685500Y214350D01*
Y214642D01*
X685583Y214933D01*
X685708Y215183D01*
X685875Y215392D01*
G01X685500Y217950D02*
X688000D01*
X686208Y216408D01*
Y218492D01*
G01X685792Y219842D02*
X685583Y220133D01*
X685500Y220467D01*
X685583Y220800D01*
X685833Y221092D01*
X686208Y221300D01*
X686583Y221383D01*
X687042D01*
X687417Y221300D01*
X687750Y221092D01*
X687917Y220842D01*
X688000Y220550D01*
X687917Y220217D01*
X687750Y219967D01*
X687500Y219800D01*
X687167Y219717D01*
X686875Y219800D01*
X686583Y220008D01*
X686417Y220258D01*
X686375Y220550D01*
X686458Y220883D01*
X686667Y221133D01*
X687042Y221383D01*
G01X686542Y222858D02*
X686833Y223150D01*
X687000Y223400D01*
X687083Y223733D01*
X687000Y224025D01*
X686833Y224233D01*
X686583Y224400D01*
X686292Y224442D01*
X686042Y224400D01*
X685792Y224233D01*
X685583Y223983D01*
X685500Y223692D01*
X685583Y223358D01*
X685833Y223067D01*
X686208Y222900D01*
X686625Y222858D01*
X687167Y222942D01*
X687458Y223067D01*
X687750Y223275D01*
X687958Y223567D01*
X688000Y223858D01*
X687917Y224150D01*
X687708Y224358D01*
G01X672792Y207767D02*
X672917Y207517D01*
X673000Y207225D01*
Y206892D01*
X672875Y206517D01*
X672667Y206225D01*
X672417Y206017D01*
X672000Y205850D01*
X671625Y205808D01*
X671250Y205892D01*
X671000Y206017D01*
X670750Y206267D01*
X670583Y206558D01*
X670500Y206850D01*
Y207142D01*
X670583Y207433D01*
X670708Y207683D01*
X670875Y207892D01*
G01X670500Y210450D02*
X673000D01*
X671208Y208908D01*
Y210992D01*
G01X670792Y212342D02*
X670583Y212633D01*
X670500Y212967D01*
X670583Y213300D01*
X670833Y213592D01*
X671208Y213800D01*
X671583Y213883D01*
X672042D01*
X672417Y213800D01*
X672750Y213592D01*
X672917Y213342D01*
X673000Y213050D01*
X672917Y212717D01*
X672750Y212467D01*
X672500Y212300D01*
X672167Y212217D01*
X671875Y212300D01*
X671583Y212508D01*
X671417Y212758D01*
X671375Y213050D01*
X671458Y213383D01*
X671667Y213633D01*
X672042Y213883D01*
G01X670875Y215233D02*
X670667Y215483D01*
X670542Y215775D01*
X670500Y216150D01*
X670583Y216525D01*
X670750Y216817D01*
X671042Y217025D01*
X671375Y217067D01*
X671708Y216983D01*
X671917Y216775D01*
X672083Y216483D01*
X672125Y216192D01*
X672083Y215900D01*
X671917Y215525D01*
X673000Y215650D01*
Y216775D01*
G01X668792Y215267D02*
X668917Y215017D01*
X669000Y214725D01*
Y214392D01*
X668875Y214017D01*
X668667Y213725D01*
X668417Y213517D01*
X668000Y213350D01*
X667625Y213308D01*
X667250Y213392D01*
X667000Y213517D01*
X666750Y213767D01*
X666583Y214058D01*
X666500Y214350D01*
Y214642D01*
X666583Y214933D01*
X666708Y215183D01*
X666875Y215392D01*
G01X666500Y217950D02*
X669000D01*
X667208Y216408D01*
Y218492D01*
G01X666792Y219842D02*
X666583Y220133D01*
X666500Y220467D01*
X666583Y220800D01*
X666833Y221092D01*
X667208Y221300D01*
X667583Y221383D01*
X668042D01*
X668417Y221300D01*
X668750Y221092D01*
X668917Y220842D01*
X669000Y220550D01*
X668917Y220217D01*
X668750Y219967D01*
X668500Y219800D01*
X668167Y219717D01*
X667875Y219800D01*
X667583Y220008D01*
X667417Y220258D01*
X667375Y220550D01*
X667458Y220883D01*
X667667Y221133D01*
X668042Y221383D01*
G01X666500Y224150D02*
X669000D01*
X667208Y222608D01*
Y224692D01*
G01X646933Y223692D02*
X647183Y223817D01*
X647475Y223900D01*
X647808D01*
X648183Y223775D01*
X648475Y223567D01*
X648683Y223317D01*
X648850Y222900D01*
X648892Y222525D01*
X648808Y222150D01*
X648683Y221900D01*
X648433Y221650D01*
X648142Y221483D01*
X647850Y221400D01*
X647558D01*
X647267Y221483D01*
X647017Y221608D01*
X646808Y221775D01*
G01X645667Y221900D02*
X645417Y221608D01*
X645083Y221442D01*
X644708Y221400D01*
X644375Y221442D01*
X644042Y221650D01*
X643833Y221900D01*
X643792Y222150D01*
X643875Y222442D01*
X644167Y222650D01*
X644458Y222733D01*
X644833D01*
G01X644458D02*
X644208Y222858D01*
X644000Y223067D01*
X643917Y223317D01*
X644000Y223567D01*
X644208Y223775D01*
X644583Y223900D01*
X644958Y223858D01*
X645333Y223692D01*
G01X642567Y221775D02*
X642317Y221567D01*
X642025Y221442D01*
X641650Y221400D01*
X641275Y221483D01*
X640983Y221650D01*
X640775Y221942D01*
X640733Y222275D01*
X640817Y222608D01*
X641025Y222817D01*
X641317Y222983D01*
X641608Y223025D01*
X641900Y222983D01*
X642275Y222817D01*
X642150Y223900D01*
X641025D01*
G01X638050Y221400D02*
Y223900D01*
X639592Y222108D01*
X637508D01*
G01X646733Y227792D02*
X646983Y227917D01*
X647275Y228000D01*
X647608D01*
X647983Y227875D01*
X648275Y227667D01*
X648483Y227417D01*
X648650Y227000D01*
X648692Y226625D01*
X648608Y226250D01*
X648483Y226000D01*
X648233Y225750D01*
X647942Y225583D01*
X647650Y225500D01*
X647358D01*
X647067Y225583D01*
X646817Y225708D01*
X646608Y225875D01*
G01X645467Y226000D02*
X645217Y225708D01*
X644883Y225542D01*
X644508Y225500D01*
X644175Y225542D01*
X643842Y225750D01*
X643633Y226000D01*
X643592Y226250D01*
X643675Y226542D01*
X643967Y226750D01*
X644258Y226833D01*
X644633D01*
G01X644258D02*
X644008Y226958D01*
X643800Y227167D01*
X643717Y227417D01*
X643800Y227667D01*
X644008Y227875D01*
X644383Y228000D01*
X644758Y227958D01*
X645133Y227792D01*
G01X642367Y225875D02*
X642117Y225667D01*
X641825Y225542D01*
X641450Y225500D01*
X641075Y225583D01*
X640783Y225750D01*
X640575Y226042D01*
X640533Y226375D01*
X640617Y226708D01*
X640825Y226917D01*
X641117Y227083D01*
X641408Y227125D01*
X641700Y227083D01*
X642075Y226917D01*
X641950Y228000D01*
X640825D01*
G01X639142Y227583D02*
X638892Y227833D01*
X638600Y227958D01*
X638267Y228000D01*
X637850Y227917D01*
X637558Y227708D01*
X637475Y227458D01*
X637517Y227208D01*
X637683Y227000D01*
X638517Y226583D01*
X638892Y226292D01*
X639142Y225875D01*
X639225Y225500D01*
X637475D01*
G01X646733Y231792D02*
X646983Y231917D01*
X647275Y232000D01*
X647608D01*
X647983Y231875D01*
X648275Y231667D01*
X648483Y231417D01*
X648650Y231000D01*
X648692Y230625D01*
X648608Y230250D01*
X648483Y230000D01*
X648233Y229750D01*
X647942Y229583D01*
X647650Y229500D01*
X647358D01*
X647067Y229583D01*
X646817Y229708D01*
X646608Y229875D01*
G01X645467Y230000D02*
X645217Y229708D01*
X644883Y229542D01*
X644508Y229500D01*
X644175Y229542D01*
X643842Y229750D01*
X643633Y230000D01*
X643592Y230250D01*
X643675Y230542D01*
X643967Y230750D01*
X644258Y230833D01*
X644633D01*
G01X644258D02*
X644008Y230958D01*
X643800Y231167D01*
X643717Y231417D01*
X643800Y231667D01*
X644008Y231875D01*
X644383Y232000D01*
X644758Y231958D01*
X645133Y231792D01*
G01X642367Y229875D02*
X642117Y229667D01*
X641825Y229542D01*
X641450Y229500D01*
X641075Y229583D01*
X640783Y229750D01*
X640575Y230042D01*
X640533Y230375D01*
X640617Y230708D01*
X640825Y230917D01*
X641117Y231083D01*
X641408Y231125D01*
X641700Y231083D01*
X642075Y230917D01*
X641950Y232000D01*
X640825D01*
G01X638350Y229500D02*
Y232000D01*
X638850Y231500D01*
G01Y229500D02*
X637850D01*
G01X646733Y219792D02*
X646983Y219917D01*
X647275Y220000D01*
X647608D01*
X647983Y219875D01*
X648275Y219667D01*
X648483Y219417D01*
X648650Y219000D01*
X648692Y218625D01*
X648608Y218250D01*
X648483Y218000D01*
X648233Y217750D01*
X647942Y217583D01*
X647650Y217500D01*
X647358D01*
X647067Y217583D01*
X646817Y217708D01*
X646608Y217875D01*
G01X645467Y218000D02*
X645217Y217708D01*
X644883Y217542D01*
X644508Y217500D01*
X644175Y217542D01*
X643842Y217750D01*
X643633Y218000D01*
X643592Y218250D01*
X643675Y218542D01*
X643967Y218750D01*
X644258Y218833D01*
X644633D01*
G01X644258D02*
X644008Y218958D01*
X643800Y219167D01*
X643717Y219417D01*
X643800Y219667D01*
X644008Y219875D01*
X644383Y220000D01*
X644758Y219958D01*
X645133Y219792D01*
G01X642367Y217875D02*
X642117Y217667D01*
X641825Y217542D01*
X641450Y217500D01*
X641075Y217583D01*
X640783Y217750D01*
X640575Y218042D01*
X640533Y218375D01*
X640617Y218708D01*
X640825Y218917D01*
X641117Y219083D01*
X641408Y219125D01*
X641700Y219083D01*
X642075Y218917D01*
X641950Y220000D01*
X640825D01*
G01X639267Y218000D02*
X639017Y217708D01*
X638683Y217542D01*
X638308Y217500D01*
X637975Y217542D01*
X637642Y217750D01*
X637433Y218000D01*
X637392Y218250D01*
X637475Y218542D01*
X637767Y218750D01*
X638058Y218833D01*
X638433D01*
G01X638058D02*
X637808Y218958D01*
X637600Y219167D01*
X637517Y219417D01*
X637600Y219667D01*
X637808Y219875D01*
X638183Y220000D01*
X638558Y219958D01*
X638933Y219792D01*
G01X693500Y216300D02*
X691000D01*
G01X693500Y215342D02*
Y217258D01*
G01X691000Y218567D02*
X693500D01*
Y219567D01*
X693375Y219900D01*
X693083Y220150D01*
X692750Y220233D01*
X692417Y220150D01*
X692167Y219942D01*
X692042Y219567D01*
Y218567D01*
G01X691000Y222500D02*
X693500D01*
X693000Y222000D01*
G01X691000D02*
Y223000D01*
G01X691500Y224683D02*
X691208Y224933D01*
X691042Y225267D01*
X691000Y225642D01*
X691042Y225975D01*
X691250Y226308D01*
X691500Y226517D01*
X691750Y226558D01*
X692042Y226475D01*
X692250Y226183D01*
X692333Y225892D01*
Y225517D01*
G01Y225892D02*
X692458Y226142D01*
X692667Y226350D01*
X692917Y226433D01*
X693167Y226350D01*
X693375Y226142D01*
X693500Y225767D01*
X693458Y225392D01*
X693292Y225017D01*
G01X691000Y228617D02*
X691542Y228700D01*
X692000Y228825D01*
X692417Y228992D01*
X692875Y229200D01*
X693500Y229533D01*
Y227867D01*
G01X688700Y229000D02*
Y226500D01*
G01X689658Y229000D02*
X687742D01*
G01X686433Y226500D02*
Y229000D01*
X685433D01*
X685100Y228875D01*
X684850Y228583D01*
X684767Y228250D01*
X684850Y227917D01*
X685058Y227667D01*
X685433Y227542D01*
X686433D01*
G01X682500Y226500D02*
Y229000D01*
X683000Y228500D01*
G01Y226500D02*
X682000D01*
G01X680317Y227000D02*
X680067Y226708D01*
X679733Y226542D01*
X679358Y226500D01*
X679025Y226542D01*
X678692Y226750D01*
X678483Y227000D01*
X678442Y227250D01*
X678525Y227542D01*
X678817Y227750D01*
X679108Y227833D01*
X679483D01*
G01X679108D02*
X678858Y227958D01*
X678650Y228167D01*
X678567Y228417D01*
X678650Y228667D01*
X678858Y228875D01*
X679233Y229000D01*
X679608Y228958D01*
X679983Y228792D01*
G01X675800Y226500D02*
Y229000D01*
X677342Y227208D01*
X675258D01*
G01X692166Y246017D02*
X694666D01*
Y247058D01*
X694541Y247392D01*
X694374Y247600D01*
X694041Y247683D01*
X693708Y247600D01*
X693499Y247350D01*
X693374Y247058D01*
Y246017D01*
G01Y247058D02*
X692166Y247683D01*
G01X692541Y249033D02*
X692333Y249283D01*
X692208Y249575D01*
X692166Y249950D01*
X692249Y250325D01*
X692416Y250617D01*
X692708Y250825D01*
X693041Y250867D01*
X693374Y250783D01*
X693583Y250575D01*
X693749Y250283D01*
X693791Y249992D01*
X693749Y249700D01*
X693583Y249325D01*
X694666Y249450D01*
Y250575D01*
G01X692166Y253550D02*
X694666D01*
X692874Y252008D01*
Y254092D01*
G01X693208Y255358D02*
X693499Y255650D01*
X693666Y255900D01*
X693749Y256233D01*
X693666Y256525D01*
X693499Y256733D01*
X693249Y256900D01*
X692958Y256942D01*
X692708Y256900D01*
X692458Y256733D01*
X692249Y256483D01*
X692166Y256192D01*
X692249Y255858D01*
X692499Y255567D01*
X692874Y255400D01*
X693291Y255358D01*
X693833Y255442D01*
X694124Y255567D01*
X694416Y255775D01*
X694624Y256067D01*
X694666Y256358D01*
X694583Y256650D01*
X694374Y256858D01*
G01X691468Y244705D02*
X687468D01*
Y252105D01*
G01X676683Y296000D02*
Y298500D01*
X675642D01*
X675308Y298375D01*
X675100Y298208D01*
X675017Y297875D01*
X675100Y297542D01*
X675350Y297333D01*
X675642Y297208D01*
X676683D01*
G01X675642D02*
X675017Y296000D01*
G01X673667Y296500D02*
X673417Y296208D01*
X673083Y296042D01*
X672708Y296000D01*
X672375Y296042D01*
X672042Y296250D01*
X671833Y296500D01*
X671792Y296750D01*
X671875Y297042D01*
X672167Y297250D01*
X672458Y297333D01*
X672833D01*
G01X672458D02*
X672208Y297458D01*
X672000Y297667D01*
X671917Y297917D01*
X672000Y298167D01*
X672208Y298375D01*
X672583Y298500D01*
X672958Y298458D01*
X673333Y298292D01*
G01X669650Y298500D02*
X669983Y298417D01*
X670233Y298208D01*
X670400Y297958D01*
X670525Y297625D01*
X670567Y297250D01*
X670525Y296875D01*
X670400Y296542D01*
X670233Y296292D01*
X669983Y296083D01*
X669650Y296000D01*
X669317Y296083D01*
X669067Y296292D01*
X668900Y296542D01*
X668775Y296875D01*
X668733Y297250D01*
X668775Y297625D01*
X668900Y297958D01*
X669067Y298208D01*
X669317Y298417D01*
X669650Y298500D01*
G01X667467Y296500D02*
X667217Y296208D01*
X666883Y296042D01*
X666508Y296000D01*
X666175Y296042D01*
X665842Y296250D01*
X665633Y296500D01*
X665592Y296750D01*
X665675Y297042D01*
X665967Y297250D01*
X666258Y297333D01*
X666633D01*
G01X666258D02*
X666008Y297458D01*
X665800Y297667D01*
X665717Y297917D01*
X665800Y298167D01*
X666008Y298375D01*
X666383Y298500D01*
X666758Y298458D01*
X667133Y298292D01*
G01X667500Y286000D02*
Y290000D01*
X674900D01*
G01X673283Y267667D02*
Y270167D01*
X672242D01*
X671908Y270042D01*
X671700Y269875D01*
X671617Y269542D01*
X671700Y269209D01*
X671950Y269000D01*
X672242Y268875D01*
X673283D01*
G01X672242D02*
X671617Y267667D01*
G01X670267Y268167D02*
X670017Y267875D01*
X669683Y267709D01*
X669308Y267667D01*
X668975Y267709D01*
X668642Y267917D01*
X668433Y268167D01*
X668392Y268417D01*
X668475Y268709D01*
X668767Y268917D01*
X669058Y269000D01*
X669433D01*
G01X669058D02*
X668808Y269125D01*
X668600Y269334D01*
X668517Y269584D01*
X668600Y269834D01*
X668808Y270042D01*
X669183Y270167D01*
X669558Y270125D01*
X669933Y269959D01*
G01X666250Y267667D02*
Y270167D01*
X666750Y269667D01*
G01Y267667D02*
X665750D01*
G01X663233D02*
X663150Y268209D01*
X663025Y268667D01*
X662858Y269084D01*
X662650Y269542D01*
X662317Y270167D01*
X663983D01*
G01X676789Y266500D02*
Y270500D01*
X684189D01*
G01X696667Y262517D02*
X699167D01*
Y263558D01*
X699042Y263892D01*
X698875Y264100D01*
X698542Y264183D01*
X698209Y264100D01*
X698000Y263850D01*
X697875Y263558D01*
Y262517D01*
G01Y263558D02*
X696667Y264183D01*
G01X698750Y265658D02*
X699000Y265908D01*
X699125Y266200D01*
X699167Y266533D01*
X699084Y266950D01*
X698875Y267242D01*
X698625Y267325D01*
X698375Y267283D01*
X698167Y267117D01*
X697750Y266283D01*
X697459Y265908D01*
X697042Y265658D01*
X696667Y265575D01*
Y267325D01*
G01Y269550D02*
X696709Y269842D01*
X696834Y270175D01*
X697042Y270383D01*
X697334Y270467D01*
X697625Y270383D01*
X697875Y270133D01*
X698000Y269758D01*
Y269342D01*
X698084Y269092D01*
X698292Y268883D01*
X698584Y268800D01*
X698875Y268925D01*
X699084Y269217D01*
X699167Y269550D01*
X699084Y269883D01*
X698875Y270175D01*
X698584Y270300D01*
X698292Y270217D01*
X698084Y270008D01*
X698000Y269758D01*
Y269342D01*
X697875Y268967D01*
X697625Y268717D01*
X697334Y268633D01*
X697042Y268717D01*
X696834Y268925D01*
X696709Y269258D01*
X696667Y269550D01*
G01Y272650D02*
X696709Y272942D01*
X696834Y273275D01*
X697042Y273483D01*
X697334Y273567D01*
X697625Y273483D01*
X697875Y273233D01*
X698000Y272858D01*
Y272442D01*
X698084Y272192D01*
X698292Y271983D01*
X698584Y271900D01*
X698875Y272025D01*
X699084Y272317D01*
X699167Y272650D01*
X699084Y272983D01*
X698875Y273275D01*
X698584Y273400D01*
X698292Y273317D01*
X698084Y273108D01*
X698000Y272858D01*
Y272442D01*
X697875Y272067D01*
X697625Y271817D01*
X697334Y271733D01*
X697042Y271817D01*
X696834Y272025D01*
X696709Y272358D01*
X696667Y272650D01*
G01X693887Y262477D02*
X689887D01*
Y269877D01*
G01X673383Y261667D02*
Y264167D01*
X672342D01*
X672008Y264042D01*
X671800Y263875D01*
X671717Y263542D01*
X671800Y263209D01*
X672050Y263000D01*
X672342Y262875D01*
X673383D01*
G01X672342D02*
X671717Y261667D01*
G01X670367Y262042D02*
X670117Y261834D01*
X669825Y261709D01*
X669450Y261667D01*
X669075Y261750D01*
X668783Y261917D01*
X668575Y262209D01*
X668533Y262542D01*
X668617Y262875D01*
X668825Y263084D01*
X669117Y263250D01*
X669408Y263292D01*
X669700Y263250D01*
X670075Y263084D01*
X669950Y264167D01*
X668825D01*
G01X665850Y261667D02*
Y264167D01*
X667392Y262375D01*
X665308D01*
G01X663333Y261667D02*
X663250Y262209D01*
X663125Y262667D01*
X662958Y263084D01*
X662750Y263542D01*
X662417Y264167D01*
X664083D01*
G01X684189Y264854D02*
Y260854D01*
X676789D01*
G01X666459Y249767D02*
X666584Y249517D01*
X666667Y249225D01*
Y248892D01*
X666542Y248517D01*
X666334Y248225D01*
X666084Y248017D01*
X665667Y247850D01*
X665292Y247808D01*
X664917Y247892D01*
X664667Y248017D01*
X664417Y248267D01*
X664250Y248558D01*
X664167Y248850D01*
Y249142D01*
X664250Y249433D01*
X664375Y249683D01*
X664542Y249892D01*
G01X666250Y251158D02*
X666500Y251408D01*
X666625Y251700D01*
X666667Y252033D01*
X666584Y252450D01*
X666375Y252742D01*
X666125Y252825D01*
X665875Y252783D01*
X665667Y252617D01*
X665250Y251783D01*
X664959Y251408D01*
X664542Y251158D01*
X664167Y251075D01*
Y252825D01*
G01Y255050D02*
X666667D01*
X666167Y254550D01*
G01X664167D02*
Y255550D01*
G01X666250Y257358D02*
X666500Y257608D01*
X666625Y257900D01*
X666667Y258233D01*
X666584Y258650D01*
X666375Y258942D01*
X666125Y259025D01*
X665875Y258983D01*
X665667Y258817D01*
X665250Y257983D01*
X664959Y257608D01*
X664542Y257358D01*
X664167Y257275D01*
Y259025D01*
G01X688550Y287167D02*
X688883Y287209D01*
X689175Y287375D01*
X689425Y287625D01*
X689592Y287917D01*
X689675Y288250D01*
Y288584D01*
X689592Y288917D01*
X689425Y289209D01*
X689175Y289459D01*
X688883Y289625D01*
X688550Y289667D01*
X688217Y289625D01*
X687925Y289459D01*
X687675Y289209D01*
X687508Y288917D01*
X687425Y288584D01*
Y288250D01*
X687508Y287917D01*
X687675Y287625D01*
X687925Y287375D01*
X688217Y287209D01*
X688550Y287167D01*
G01X688217Y287834D02*
X687717Y287167D01*
G01X685450D02*
X685158Y287209D01*
X684825Y287334D01*
X684617Y287542D01*
X684533Y287834D01*
X684617Y288125D01*
X684867Y288375D01*
X685242Y288500D01*
X685658D01*
X685908Y288584D01*
X686117Y288792D01*
X686200Y289084D01*
X686075Y289375D01*
X685783Y289584D01*
X685450Y289667D01*
X685117Y289584D01*
X684825Y289375D01*
X684700Y289084D01*
X684783Y288792D01*
X684992Y288584D01*
X685242Y288500D01*
X685658D01*
X686033Y288375D01*
X686283Y288125D01*
X686367Y287834D01*
X686283Y287542D01*
X686075Y287334D01*
X685742Y287209D01*
X685450Y287167D01*
G01X681000Y271500D02*
Y285500D01*
G01X694000Y271500D02*
X681000D01*
G01X694000Y285500D02*
Y271500D01*
G01X681000Y285500D02*
X694000D01*
G01X675600Y292000D02*
X675933Y292042D01*
X676225Y292208D01*
X676475Y292458D01*
X676642Y292750D01*
X676725Y293083D01*
Y293417D01*
X676642Y293750D01*
X676475Y294042D01*
X676225Y294292D01*
X675933Y294458D01*
X675600Y294500D01*
X675267Y294458D01*
X674975Y294292D01*
X674725Y294042D01*
X674558Y293750D01*
X674475Y293417D01*
Y293083D01*
X674558Y292750D01*
X674725Y292458D01*
X674975Y292208D01*
X675267Y292042D01*
X675600Y292000D01*
G01X675267Y292667D02*
X674767Y292000D01*
G01X672500D02*
Y294500D01*
X673000Y294000D01*
G01Y292000D02*
X672000D01*
G01X670192Y293042D02*
X669900Y293333D01*
X669650Y293500D01*
X669317Y293583D01*
X669025Y293500D01*
X668817Y293333D01*
X668650Y293083D01*
X668608Y292792D01*
X668650Y292542D01*
X668817Y292292D01*
X669067Y292083D01*
X669358Y292000D01*
X669692Y292083D01*
X669983Y292333D01*
X670150Y292708D01*
X670192Y293125D01*
X670108Y293667D01*
X669983Y293958D01*
X669775Y294250D01*
X669483Y294458D01*
X669192Y294500D01*
X668900Y294417D01*
X668692Y294208D01*
G01X679500Y285500D02*
Y271500D01*
G01X666500Y285500D02*
X679500D01*
G01X666500Y271500D02*
Y285500D01*
G01X679500Y271500D02*
X666500D01*
G01X642000Y272567D02*
X639500D01*
Y274233D01*
G01X641583Y275708D02*
X641833Y275958D01*
X641958Y276250D01*
X642000Y276583D01*
X641917Y277000D01*
X641708Y277292D01*
X641458Y277375D01*
X641208Y277333D01*
X641000Y277167D01*
X640583Y276333D01*
X640292Y275958D01*
X639875Y275708D01*
X639500Y275625D01*
Y277375D01*
G01X640000Y278683D02*
X639708Y278933D01*
X639542Y279267D01*
X639500Y279642D01*
X639542Y279975D01*
X639750Y280308D01*
X640000Y280517D01*
X640250Y280558D01*
X640542Y280475D01*
X640750Y280183D01*
X640833Y279892D01*
Y279517D01*
G01Y279892D02*
X640958Y280142D01*
X641167Y280350D01*
X641417Y280433D01*
X641667Y280350D01*
X641875Y280142D01*
X642000Y279767D01*
X641958Y279392D01*
X641792Y279017D01*
G01X636000Y256300D02*
X643000D01*
Y269700D01*
X636000D01*
Y256300D01*
G01X659500Y274567D02*
X657000D01*
Y276233D01*
G01Y278500D02*
X659500D01*
X659000Y278000D01*
G01X657000D02*
Y279000D01*
G01X657292Y280892D02*
X657083Y281183D01*
X657000Y281517D01*
X657083Y281850D01*
X657333Y282142D01*
X657708Y282350D01*
X658083Y282433D01*
X658542D01*
X658917Y282350D01*
X659250Y282142D01*
X659417Y281892D01*
X659500Y281600D01*
X659417Y281267D01*
X659250Y281017D01*
X659000Y280850D01*
X658667Y280767D01*
X658375Y280850D01*
X658083Y281058D01*
X657917Y281308D01*
X657875Y281600D01*
X657958Y281933D01*
X658167Y282183D01*
X658542Y282433D01*
G01X654500Y256300D02*
X661500D01*
Y269700D01*
X654500D01*
Y256300D01*
G01X646500Y271517D02*
X649000D01*
Y272558D01*
X648875Y272892D01*
X648708Y273100D01*
X648375Y273183D01*
X648042Y273100D01*
X647833Y272850D01*
X647708Y272558D01*
Y271517D01*
G01Y272558D02*
X646500Y273183D01*
G01X648583Y274658D02*
X648833Y274908D01*
X648958Y275200D01*
X649000Y275533D01*
X648917Y275950D01*
X648708Y276242D01*
X648458Y276325D01*
X648208Y276283D01*
X648000Y276117D01*
X647583Y275283D01*
X647292Y274908D01*
X646875Y274658D01*
X646500Y274575D01*
Y276325D01*
G01Y278550D02*
X646542Y278842D01*
X646667Y279175D01*
X646875Y279383D01*
X647167Y279467D01*
X647458Y279383D01*
X647708Y279133D01*
X647833Y278758D01*
Y278342D01*
X647917Y278092D01*
X648125Y277883D01*
X648417Y277800D01*
X648708Y277925D01*
X648917Y278217D01*
X649000Y278550D01*
X648917Y278883D01*
X648708Y279175D01*
X648417Y279300D01*
X648125Y279217D01*
X647917Y279008D01*
X647833Y278758D01*
Y278342D01*
X647708Y277967D01*
X647458Y277717D01*
X647167Y277633D01*
X646875Y277717D01*
X646667Y277925D01*
X646542Y278258D01*
X646500Y278550D01*
G01Y281650D02*
X649000D01*
X648500Y281150D01*
G01X646500D02*
Y282150D01*
G01X643500Y266600D02*
X647500D01*
Y259200D01*
G01X650500Y271517D02*
X653000D01*
Y272558D01*
X652875Y272892D01*
X652708Y273100D01*
X652375Y273183D01*
X652042Y273100D01*
X651833Y272850D01*
X651708Y272558D01*
Y271517D01*
G01Y272558D02*
X650500Y273183D01*
G01X652583Y274658D02*
X652833Y274908D01*
X652958Y275200D01*
X653000Y275533D01*
X652917Y275950D01*
X652708Y276242D01*
X652458Y276325D01*
X652208Y276283D01*
X652000Y276117D01*
X651583Y275283D01*
X651292Y274908D01*
X650875Y274658D01*
X650500Y274575D01*
Y276325D01*
G01Y278467D02*
X651042Y278550D01*
X651500Y278675D01*
X651917Y278842D01*
X652375Y279050D01*
X653000Y279383D01*
Y277717D01*
G01X650500Y281567D02*
X651042Y281650D01*
X651500Y281775D01*
X651917Y281942D01*
X652375Y282150D01*
X653000Y282483D01*
Y280817D01*
G01X650000Y266600D02*
X654000D01*
Y259200D01*
G01X690667Y252983D02*
X688875D01*
X688500Y253150D01*
X688250Y253483D01*
X688167Y253900D01*
X688250Y254317D01*
X688500Y254650D01*
X688875Y254817D01*
X690667D01*
G01X688167Y257000D02*
X690667D01*
X690167Y256500D01*
G01X688167D02*
Y257500D01*
G01X689209Y259308D02*
X689500Y259600D01*
X689667Y259850D01*
X689750Y260183D01*
X689667Y260475D01*
X689500Y260683D01*
X689250Y260850D01*
X688959Y260892D01*
X688709Y260850D01*
X688459Y260683D01*
X688250Y260433D01*
X688167Y260142D01*
X688250Y259808D01*
X688500Y259517D01*
X688875Y259350D01*
X689292Y259308D01*
X689834Y259392D01*
X690125Y259517D01*
X690417Y259725D01*
X690625Y260017D01*
X690667Y260308D01*
X690584Y260600D01*
X690375Y260808D01*
G01X672589Y250384D02*
X670989Y251984D01*
G01Y248784D02*
X672589Y250384D01*
G01X670989Y248084D02*
Y252684D01*
G01X685489Y248084D02*
X670989D01*
G01X685489Y252684D02*
Y248084D01*
G01X670989Y252684D02*
X685489D01*
G01X645316Y359023D02*
X645566Y359148D01*
X645858Y359231D01*
X646191D01*
X646566Y359106D01*
X646858Y358898D01*
X647066Y358648D01*
X647233Y358231D01*
X647275Y357856D01*
X647191Y357481D01*
X647066Y357231D01*
X646816Y356981D01*
X646525Y356814D01*
X646233Y356731D01*
X645941D01*
X645650Y356814D01*
X645400Y356939D01*
X645191Y357106D01*
G01X643925Y357773D02*
X643633Y358064D01*
X643383Y358231D01*
X643050Y358314D01*
X642758Y358231D01*
X642550Y358064D01*
X642383Y357814D01*
X642341Y357523D01*
X642383Y357273D01*
X642550Y357023D01*
X642800Y356814D01*
X643091Y356731D01*
X643425Y356814D01*
X643716Y357064D01*
X643883Y357439D01*
X643925Y357856D01*
X643841Y358398D01*
X643716Y358689D01*
X643508Y358981D01*
X643216Y359189D01*
X642925Y359231D01*
X642633Y359148D01*
X642425Y358939D01*
G01X639533Y356731D02*
Y359231D01*
X641075Y357439D01*
X638991D01*
G01X637850Y357106D02*
X637600Y356898D01*
X637308Y356773D01*
X636933Y356731D01*
X636558Y356814D01*
X636266Y356981D01*
X636058Y357273D01*
X636016Y357606D01*
X636100Y357939D01*
X636308Y358148D01*
X636600Y358314D01*
X636891Y358356D01*
X637183Y358314D01*
X637558Y358148D01*
X637433Y359231D01*
X636308D01*
G01X636231Y375300D02*
X638731D01*
Y376341D01*
X638606Y376675D01*
X638439Y376883D01*
X638106Y376966D01*
X637773Y376883D01*
X637564Y376633D01*
X637439Y376341D01*
Y375300D01*
G01Y376341D02*
X636231Y376966D01*
G01Y379733D02*
X638731D01*
X636939Y378191D01*
Y380275D01*
G01X636231Y382333D02*
X636273Y382625D01*
X636398Y382958D01*
X636606Y383166D01*
X636898Y383250D01*
X637189Y383166D01*
X637439Y382916D01*
X637564Y382541D01*
Y382125D01*
X637648Y381875D01*
X637856Y381666D01*
X638148Y381583D01*
X638439Y381708D01*
X638648Y382000D01*
X638731Y382333D01*
X638648Y382666D01*
X638439Y382958D01*
X638148Y383083D01*
X637856Y383000D01*
X637648Y382791D01*
X637564Y382541D01*
Y382125D01*
X637439Y381750D01*
X637189Y381500D01*
X636898Y381416D01*
X636606Y381500D01*
X636398Y381708D01*
X636273Y382041D01*
X636231Y382333D01*
G01X636606Y384516D02*
X636398Y384766D01*
X636273Y385058D01*
X636231Y385433D01*
X636314Y385808D01*
X636481Y386100D01*
X636773Y386308D01*
X637106Y386350D01*
X637439Y386266D01*
X637648Y386058D01*
X637814Y385766D01*
X637856Y385475D01*
X637814Y385183D01*
X637648Y384808D01*
X638731Y384933D01*
Y386058D01*
G01X659031Y374683D02*
X655031D01*
Y382083D01*
G01X684300Y372717D02*
X686800D01*
Y373758D01*
X686675Y374092D01*
X686508Y374300D01*
X686175Y374383D01*
X685842Y374300D01*
X685633Y374050D01*
X685508Y373758D01*
Y372717D01*
G01Y373758D02*
X684300Y374383D01*
G01Y377150D02*
X686800D01*
X685008Y375608D01*
Y377692D01*
G01X684592Y379042D02*
X684383Y379333D01*
X684300Y379667D01*
X684383Y380000D01*
X684633Y380292D01*
X685008Y380500D01*
X685383Y380583D01*
X685842D01*
X686217Y380500D01*
X686550Y380292D01*
X686717Y380042D01*
X686800Y379750D01*
X686717Y379417D01*
X686550Y379167D01*
X686300Y379000D01*
X685967Y378917D01*
X685675Y379000D01*
X685383Y379208D01*
X685217Y379458D01*
X685175Y379750D01*
X685258Y380083D01*
X685467Y380333D01*
X685842Y380583D01*
G01X685342Y382058D02*
X685633Y382350D01*
X685800Y382600D01*
X685883Y382933D01*
X685800Y383225D01*
X685633Y383433D01*
X685383Y383600D01*
X685092Y383642D01*
X684842Y383600D01*
X684592Y383433D01*
X684383Y383183D01*
X684300Y382892D01*
X684383Y382558D01*
X684633Y382267D01*
X685008Y382100D01*
X685425Y382058D01*
X685967Y382142D01*
X686258Y382267D01*
X686550Y382475D01*
X686758Y382767D01*
X686800Y383058D01*
X686717Y383350D01*
X686508Y383558D01*
G01X670131Y388583D02*
X674131D01*
Y381183D01*
G01X645231Y375300D02*
X647731D01*
Y376341D01*
X647606Y376675D01*
X647439Y376883D01*
X647106Y376966D01*
X646773Y376883D01*
X646564Y376633D01*
X646439Y376341D01*
Y375300D01*
G01Y376341D02*
X645231Y376966D01*
G01Y379733D02*
X647731D01*
X645939Y378191D01*
Y380275D01*
G01X645231Y382333D02*
X645273Y382625D01*
X645398Y382958D01*
X645606Y383166D01*
X645898Y383250D01*
X646189Y383166D01*
X646439Y382916D01*
X646564Y382541D01*
Y382125D01*
X646648Y381875D01*
X646856Y381666D01*
X647148Y381583D01*
X647439Y381708D01*
X647648Y382000D01*
X647731Y382333D01*
X647648Y382666D01*
X647439Y382958D01*
X647148Y383083D01*
X646856Y383000D01*
X646648Y382791D01*
X646564Y382541D01*
Y382125D01*
X646439Y381750D01*
X646189Y381500D01*
X645898Y381416D01*
X645606Y381500D01*
X645398Y381708D01*
X645273Y382041D01*
X645231Y382333D01*
G01Y385933D02*
X647731D01*
X645939Y384391D01*
Y386475D01*
G01X668031Y374683D02*
X664031D01*
Y382083D01*
G01X640731Y375300D02*
X643231D01*
Y376341D01*
X643106Y376675D01*
X642939Y376883D01*
X642606Y376966D01*
X642273Y376883D01*
X642064Y376633D01*
X641939Y376341D01*
Y375300D01*
G01Y376341D02*
X640731Y376966D01*
G01Y379733D02*
X643231D01*
X641439Y378191D01*
Y380275D01*
G01X640731Y382333D02*
X640773Y382625D01*
X640898Y382958D01*
X641106Y383166D01*
X641398Y383250D01*
X641689Y383166D01*
X641939Y382916D01*
X642064Y382541D01*
Y382125D01*
X642148Y381875D01*
X642356Y381666D01*
X642648Y381583D01*
X642939Y381708D01*
X643148Y382000D01*
X643231Y382333D01*
X643148Y382666D01*
X642939Y382958D01*
X642648Y383083D01*
X642356Y383000D01*
X642148Y382791D01*
X642064Y382541D01*
Y382125D01*
X641939Y381750D01*
X641689Y381500D01*
X641398Y381416D01*
X641106Y381500D01*
X640898Y381708D01*
X640773Y382041D01*
X640731Y382333D01*
G01X641231Y384516D02*
X640939Y384766D01*
X640773Y385100D01*
X640731Y385475D01*
X640773Y385808D01*
X640981Y386141D01*
X641231Y386350D01*
X641481Y386391D01*
X641773Y386308D01*
X641981Y386016D01*
X642064Y385725D01*
Y385350D01*
G01Y385725D02*
X642189Y385975D01*
X642398Y386183D01*
X642648Y386266D01*
X642898Y386183D01*
X643106Y385975D01*
X643231Y385600D01*
X643189Y385225D01*
X643023Y384850D01*
G01X663531Y374683D02*
X659531D01*
Y382083D01*
G01X695233Y368292D02*
X695483Y368417D01*
X695775Y368500D01*
X696108D01*
X696483Y368375D01*
X696775Y368167D01*
X696983Y367917D01*
X697150Y367500D01*
X697192Y367125D01*
X697108Y366750D01*
X696983Y366500D01*
X696733Y366250D01*
X696442Y366083D01*
X696150Y366000D01*
X695858D01*
X695567Y366083D01*
X695317Y366208D01*
X695108Y366375D01*
G01X693842Y367042D02*
X693550Y367333D01*
X693300Y367500D01*
X692967Y367583D01*
X692675Y367500D01*
X692467Y367333D01*
X692300Y367083D01*
X692258Y366792D01*
X692300Y366542D01*
X692467Y366292D01*
X692717Y366083D01*
X693008Y366000D01*
X693342Y366083D01*
X693633Y366333D01*
X693800Y366708D01*
X693842Y367125D01*
X693758Y367667D01*
X693633Y367958D01*
X693425Y368250D01*
X693133Y368458D01*
X692842Y368500D01*
X692550Y368417D01*
X692342Y368208D01*
G01X690742Y367042D02*
X690450Y367333D01*
X690200Y367500D01*
X689867Y367583D01*
X689575Y367500D01*
X689367Y367333D01*
X689200Y367083D01*
X689158Y366792D01*
X689200Y366542D01*
X689367Y366292D01*
X689617Y366083D01*
X689908Y366000D01*
X690242Y366083D01*
X690533Y366333D01*
X690700Y366708D01*
X690742Y367125D01*
X690658Y367667D01*
X690533Y367958D01*
X690325Y368250D01*
X690033Y368458D01*
X689742Y368500D01*
X689450Y368417D01*
X689242Y368208D01*
G01X687767Y366375D02*
X687517Y366167D01*
X687225Y366042D01*
X686850Y366000D01*
X686475Y366083D01*
X686183Y366250D01*
X685975Y366542D01*
X685933Y366875D01*
X686017Y367208D01*
X686225Y367417D01*
X686517Y367583D01*
X686808Y367625D01*
X687100Y367583D01*
X687475Y367417D01*
X687350Y368500D01*
X686225D01*
G01X684000Y370779D02*
X678500D01*
G01X684000Y362779D02*
Y370779D01*
G01X678500Y362779D02*
X684000D01*
G01X666400D02*
X671900D01*
G01X666400Y370779D02*
Y362779D01*
G01X671900Y370779D02*
X666400D01*
G01X690892Y374467D02*
X691017Y374217D01*
X691100Y373925D01*
Y373592D01*
X690975Y373217D01*
X690767Y372925D01*
X690517Y372717D01*
X690100Y372550D01*
X689725Y372508D01*
X689350Y372592D01*
X689100Y372717D01*
X688850Y372967D01*
X688683Y373258D01*
X688600Y373550D01*
Y373842D01*
X688683Y374133D01*
X688808Y374383D01*
X688975Y374592D01*
G01X689642Y375858D02*
X689933Y376150D01*
X690100Y376400D01*
X690183Y376733D01*
X690100Y377025D01*
X689933Y377233D01*
X689683Y377400D01*
X689392Y377442D01*
X689142Y377400D01*
X688892Y377233D01*
X688683Y376983D01*
X688600Y376692D01*
X688683Y376358D01*
X688933Y376067D01*
X689308Y375900D01*
X689725Y375858D01*
X690267Y375942D01*
X690558Y376067D01*
X690850Y376275D01*
X691058Y376567D01*
X691100Y376858D01*
X691017Y377150D01*
X690808Y377358D01*
G01X690683Y378958D02*
X690933Y379208D01*
X691058Y379500D01*
X691100Y379833D01*
X691017Y380250D01*
X690808Y380542D01*
X690558Y380625D01*
X690308Y380583D01*
X690100Y380417D01*
X689683Y379583D01*
X689392Y379208D01*
X688975Y378958D01*
X688600Y378875D01*
Y380625D01*
G01X689642Y382058D02*
X689933Y382350D01*
X690100Y382600D01*
X690183Y382933D01*
X690100Y383225D01*
X689933Y383433D01*
X689683Y383600D01*
X689392Y383642D01*
X689142Y383600D01*
X688892Y383433D01*
X688683Y383183D01*
X688600Y382892D01*
X688683Y382558D01*
X688933Y382267D01*
X689308Y382100D01*
X689725Y382058D01*
X690267Y382142D01*
X690558Y382267D01*
X690850Y382475D01*
X691058Y382767D01*
X691100Y383058D01*
X691017Y383350D01*
X690808Y383558D01*
G01X653383Y370600D02*
Y373100D01*
X652383D01*
X652050Y372975D01*
X651800Y372683D01*
X651717Y372350D01*
X651800Y372017D01*
X652008Y371767D01*
X652383Y371642D01*
X653383D01*
G01X650325Y370933D02*
X649992Y370725D01*
X649617Y370600D01*
X649283D01*
X648950Y370725D01*
X648700Y370933D01*
X648575Y371225D01*
X648658Y371517D01*
X648867Y371767D01*
X649242Y371933D01*
X649742Y372017D01*
X650033Y372183D01*
X650158Y372475D01*
X650075Y372767D01*
X649867Y372975D01*
X649575Y373100D01*
X649283D01*
X648992Y373017D01*
X648742Y372808D01*
G01X647183Y370600D02*
Y373100D01*
X646183D01*
X645850Y372975D01*
X645600Y372683D01*
X645517Y372350D01*
X645600Y372017D01*
X645808Y371767D01*
X646183Y371642D01*
X647183D01*
G01X644042Y372683D02*
X643792Y372933D01*
X643500Y373058D01*
X643167Y373100D01*
X642750Y373017D01*
X642458Y372808D01*
X642375Y372558D01*
X642417Y372308D01*
X642583Y372100D01*
X643417Y371683D01*
X643792Y371392D01*
X644042Y370975D01*
X644125Y370600D01*
X642375D01*
G01X683868Y459173D02*
X684118Y459298D01*
X684410Y459381D01*
X684743D01*
X685118Y459256D01*
X685410Y459048D01*
X685618Y458798D01*
X685785Y458381D01*
X685827Y458006D01*
X685743Y457631D01*
X685618Y457381D01*
X685368Y457131D01*
X685077Y456964D01*
X684785Y456881D01*
X684493D01*
X684202Y456964D01*
X683952Y457089D01*
X683743Y457256D01*
G01X682477Y457923D02*
X682185Y458214D01*
X681935Y458381D01*
X681602Y458464D01*
X681310Y458381D01*
X681102Y458214D01*
X680935Y457964D01*
X680893Y457673D01*
X680935Y457423D01*
X681102Y457173D01*
X681352Y456964D01*
X681643Y456881D01*
X681977Y456964D01*
X682268Y457214D01*
X682435Y457589D01*
X682477Y458006D01*
X682393Y458548D01*
X682268Y458839D01*
X682060Y459131D01*
X681768Y459339D01*
X681477Y459381D01*
X681185Y459298D01*
X680977Y459089D01*
G01X678585Y459381D02*
X678918Y459298D01*
X679168Y459089D01*
X679335Y458839D01*
X679460Y458506D01*
X679502Y458131D01*
X679460Y457756D01*
X679335Y457423D01*
X679168Y457173D01*
X678918Y456964D01*
X678585Y456881D01*
X678252Y456964D01*
X678002Y457173D01*
X677835Y457423D01*
X677710Y457756D01*
X677668Y458131D01*
X677710Y458506D01*
X677835Y458839D01*
X678002Y459089D01*
X678252Y459298D01*
X678585Y459381D01*
G01X675485D02*
X675818Y459298D01*
X676068Y459089D01*
X676235Y458839D01*
X676360Y458506D01*
X676402Y458131D01*
X676360Y457756D01*
X676235Y457423D01*
X676068Y457173D01*
X675818Y456964D01*
X675485Y456881D01*
X675152Y456964D01*
X674902Y457173D01*
X674735Y457423D01*
X674610Y457756D01*
X674568Y458131D01*
X674610Y458506D01*
X674735Y458839D01*
X674902Y459089D01*
X675152Y459298D01*
X675485Y459381D01*
G01X643550Y450967D02*
X646050D01*
Y452008D01*
X645925Y452342D01*
X645758Y452550D01*
X645425Y452633D01*
X645092Y452550D01*
X644883Y452300D01*
X644758Y452008D01*
Y450967D01*
G01Y452008D02*
X643550Y452633D01*
G01X645633Y454108D02*
X645883Y454358D01*
X646008Y454650D01*
X646050Y454983D01*
X645967Y455400D01*
X645758Y455692D01*
X645508Y455775D01*
X645258Y455733D01*
X645050Y455567D01*
X644633Y454733D01*
X644342Y454358D01*
X643925Y454108D01*
X643550Y454025D01*
Y455775D01*
G01Y458000D02*
X643592Y458292D01*
X643717Y458625D01*
X643925Y458833D01*
X644217Y458917D01*
X644508Y458833D01*
X644758Y458583D01*
X644883Y458208D01*
Y457792D01*
X644967Y457542D01*
X645175Y457333D01*
X645467Y457250D01*
X645758Y457375D01*
X645967Y457667D01*
X646050Y458000D01*
X645967Y458333D01*
X645758Y458625D01*
X645467Y458750D01*
X645175Y458667D01*
X644967Y458458D01*
X644883Y458208D01*
Y457792D01*
X644758Y457417D01*
X644508Y457167D01*
X644217Y457083D01*
X643925Y457167D01*
X643717Y457375D01*
X643592Y457708D01*
X643550Y458000D01*
G01X683668Y448873D02*
X683918Y448998D01*
X684210Y449081D01*
X684543D01*
X684918Y448956D01*
X685210Y448748D01*
X685418Y448498D01*
X685585Y448081D01*
X685627Y447706D01*
X685543Y447331D01*
X685418Y447081D01*
X685168Y446831D01*
X684877Y446664D01*
X684585Y446581D01*
X684293D01*
X684002Y446664D01*
X683752Y446789D01*
X683543Y446956D01*
G01X681568Y446581D02*
X681485Y447123D01*
X681360Y447581D01*
X681193Y447998D01*
X680985Y448456D01*
X680652Y449081D01*
X682318D01*
G01X678385D02*
X678718Y448998D01*
X678968Y448789D01*
X679135Y448539D01*
X679260Y448206D01*
X679302Y447831D01*
X679260Y447456D01*
X679135Y447123D01*
X678968Y446873D01*
X678718Y446664D01*
X678385Y446581D01*
X678052Y446664D01*
X677802Y446873D01*
X677635Y447123D01*
X677510Y447456D01*
X677468Y447831D01*
X677510Y448206D01*
X677635Y448539D01*
X677802Y448789D01*
X678052Y448998D01*
X678385Y449081D01*
G01X675368Y446581D02*
X675285Y447123D01*
X675160Y447581D01*
X674993Y447998D01*
X674785Y448456D01*
X674452Y449081D01*
X676118D01*
G01X683668Y454039D02*
X683918Y454164D01*
X684210Y454247D01*
X684543D01*
X684918Y454122D01*
X685210Y453914D01*
X685418Y453664D01*
X685585Y453247D01*
X685627Y452872D01*
X685543Y452497D01*
X685418Y452247D01*
X685168Y451997D01*
X684877Y451830D01*
X684585Y451747D01*
X684293D01*
X684002Y451830D01*
X683752Y451955D01*
X683543Y452122D01*
G01X681568Y451747D02*
X681485Y452289D01*
X681360Y452747D01*
X681193Y453164D01*
X680985Y453622D01*
X680652Y454247D01*
X682318D01*
G01X678385D02*
X678718Y454164D01*
X678968Y453955D01*
X679135Y453705D01*
X679260Y453372D01*
X679302Y452997D01*
X679260Y452622D01*
X679135Y452289D01*
X678968Y452039D01*
X678718Y451830D01*
X678385Y451747D01*
X678052Y451830D01*
X677802Y452039D01*
X677635Y452289D01*
X677510Y452622D01*
X677468Y452997D01*
X677510Y453372D01*
X677635Y453705D01*
X677802Y453955D01*
X678052Y454164D01*
X678385Y454247D01*
G01X676077Y452789D02*
X675785Y453080D01*
X675535Y453247D01*
X675202Y453330D01*
X674910Y453247D01*
X674702Y453080D01*
X674535Y452830D01*
X674493Y452539D01*
X674535Y452289D01*
X674702Y452039D01*
X674952Y451830D01*
X675243Y451747D01*
X675577Y451830D01*
X675868Y452080D01*
X676035Y452455D01*
X676077Y452872D01*
X675993Y453414D01*
X675868Y453705D01*
X675660Y453997D01*
X675368Y454205D01*
X675077Y454247D01*
X674785Y454164D01*
X674577Y453955D01*
G01X706657Y103500D02*
X716000D01*
Y101000D01*
X750000D01*
Y134000D01*
G01X742574Y82699D02*
X742824Y82824D01*
X743116Y82907D01*
X743449D01*
X743824Y82782D01*
X744116Y82574D01*
X744324Y82324D01*
X744491Y81907D01*
X744533Y81532D01*
X744449Y81157D01*
X744324Y80907D01*
X744074Y80657D01*
X743783Y80490D01*
X743491Y80407D01*
X743199D01*
X742908Y80490D01*
X742658Y80615D01*
X742449Y80782D01*
G01X741308Y80907D02*
X741058Y80615D01*
X740724Y80449D01*
X740349Y80407D01*
X740016Y80449D01*
X739683Y80657D01*
X739474Y80907D01*
X739433Y81157D01*
X739516Y81449D01*
X739808Y81657D01*
X740099Y81740D01*
X740474D01*
G01X740099D02*
X739849Y81865D01*
X739641Y82074D01*
X739558Y82324D01*
X739641Y82574D01*
X739849Y82782D01*
X740224Y82907D01*
X740599Y82865D01*
X740974Y82699D01*
G01X738083Y82490D02*
X737833Y82740D01*
X737541Y82865D01*
X737208Y82907D01*
X736791Y82824D01*
X736499Y82615D01*
X736416Y82365D01*
X736458Y82115D01*
X736624Y81907D01*
X737458Y81490D01*
X737833Y81199D01*
X738083Y80782D01*
X738166Y80407D01*
X736416D01*
G01X735108Y80782D02*
X734858Y80574D01*
X734566Y80449D01*
X734191Y80407D01*
X733816Y80490D01*
X733524Y80657D01*
X733316Y80949D01*
X733274Y81282D01*
X733358Y81615D01*
X733566Y81824D01*
X733858Y81990D01*
X734149Y82032D01*
X734441Y81990D01*
X734816Y81824D01*
X734691Y82907D01*
X733566D01*
G01X742574Y86699D02*
X742824Y86824D01*
X743116Y86907D01*
X743449D01*
X743824Y86782D01*
X744116Y86574D01*
X744324Y86324D01*
X744491Y85907D01*
X744533Y85532D01*
X744449Y85157D01*
X744324Y84907D01*
X744074Y84657D01*
X743783Y84490D01*
X743491Y84407D01*
X743199D01*
X742908Y84490D01*
X742658Y84615D01*
X742449Y84782D01*
G01X741308Y84907D02*
X741058Y84615D01*
X740724Y84449D01*
X740349Y84407D01*
X740016Y84449D01*
X739683Y84657D01*
X739474Y84907D01*
X739433Y85157D01*
X739516Y85449D01*
X739808Y85657D01*
X740099Y85740D01*
X740474D01*
G01X740099D02*
X739849Y85865D01*
X739641Y86074D01*
X739558Y86324D01*
X739641Y86574D01*
X739849Y86782D01*
X740224Y86907D01*
X740599Y86865D01*
X740974Y86699D01*
G01X738083Y86490D02*
X737833Y86740D01*
X737541Y86865D01*
X737208Y86907D01*
X736791Y86824D01*
X736499Y86615D01*
X736416Y86365D01*
X736458Y86115D01*
X736624Y85907D01*
X737458Y85490D01*
X737833Y85199D01*
X738083Y84782D01*
X738166Y84407D01*
X736416D01*
G01X734983Y85449D02*
X734691Y85740D01*
X734441Y85907D01*
X734108Y85990D01*
X733816Y85907D01*
X733608Y85740D01*
X733441Y85490D01*
X733399Y85199D01*
X733441Y84949D01*
X733608Y84699D01*
X733858Y84490D01*
X734149Y84407D01*
X734483Y84490D01*
X734774Y84740D01*
X734941Y85115D01*
X734983Y85532D01*
X734899Y86074D01*
X734774Y86365D01*
X734566Y86657D01*
X734274Y86865D01*
X733983Y86907D01*
X733691Y86824D01*
X733483Y86615D01*
G01X765803Y67410D02*
Y69910D01*
X764762D01*
X764428Y69785D01*
X764220Y69618D01*
X764137Y69285D01*
X764220Y68952D01*
X764470Y68743D01*
X764762Y68618D01*
X765803D01*
G01X764762D02*
X764137Y67410D01*
G01X762662Y69493D02*
X762412Y69743D01*
X762120Y69868D01*
X761787Y69910D01*
X761370Y69827D01*
X761078Y69618D01*
X760995Y69368D01*
X761037Y69118D01*
X761203Y68910D01*
X762037Y68493D01*
X762412Y68202D01*
X762662Y67785D01*
X762745Y67410D01*
X760995D01*
G01X758270D02*
Y69910D01*
X759812Y68118D01*
X757728D01*
G01X756462Y69493D02*
X756212Y69743D01*
X755920Y69868D01*
X755587Y69910D01*
X755170Y69827D01*
X754878Y69618D01*
X754795Y69368D01*
X754837Y69118D01*
X755003Y68910D01*
X755837Y68493D01*
X756212Y68202D01*
X756462Y67785D01*
X756545Y67410D01*
X754795D01*
G01X757170Y79900D02*
Y83900D01*
X764570D01*
G01X753031Y96989D02*
Y99489D01*
X751990D01*
X751656Y99364D01*
X751448Y99197D01*
X751365Y98864D01*
X751448Y98531D01*
X751698Y98322D01*
X751990Y98197D01*
X753031D01*
G01X751990D02*
X751365Y96989D01*
G01X749890Y99072D02*
X749640Y99322D01*
X749348Y99447D01*
X749015Y99489D01*
X748598Y99406D01*
X748306Y99197D01*
X748223Y98947D01*
X748265Y98697D01*
X748431Y98489D01*
X749265Y98072D01*
X749640Y97781D01*
X749890Y97364D01*
X749973Y96989D01*
X748223D01*
G01X746915Y97489D02*
X746665Y97197D01*
X746331Y97031D01*
X745956Y96989D01*
X745623Y97031D01*
X745290Y97239D01*
X745081Y97489D01*
X745040Y97739D01*
X745123Y98031D01*
X745415Y98239D01*
X745706Y98322D01*
X746081D01*
G01X745706D02*
X745456Y98447D01*
X745248Y98656D01*
X745165Y98906D01*
X745248Y99156D01*
X745456Y99364D01*
X745831Y99489D01*
X746206Y99447D01*
X746581Y99281D01*
G01X742398Y96989D02*
Y99489D01*
X743940Y97697D01*
X741856D01*
G01X740500Y99900D02*
Y95900D01*
X733100D01*
G01X765773Y63320D02*
Y65820D01*
X764732D01*
X764398Y65695D01*
X764190Y65528D01*
X764107Y65195D01*
X764190Y64862D01*
X764440Y64653D01*
X764732Y64528D01*
X765773D01*
G01X764732D02*
X764107Y63320D01*
G01X762632Y65403D02*
X762382Y65653D01*
X762090Y65778D01*
X761757Y65820D01*
X761340Y65737D01*
X761048Y65528D01*
X760965Y65278D01*
X761007Y65028D01*
X761173Y64820D01*
X762007Y64403D01*
X762382Y64112D01*
X762632Y63695D01*
X762715Y63320D01*
X760965D01*
G01X758240D02*
Y65820D01*
X759782Y64028D01*
X757698D01*
G01X756557Y63820D02*
X756307Y63528D01*
X755973Y63362D01*
X755598Y63320D01*
X755265Y63362D01*
X754932Y63570D01*
X754723Y63820D01*
X754682Y64070D01*
X754765Y64362D01*
X755057Y64570D01*
X755348Y64653D01*
X755723D01*
G01X755348D02*
X755098Y64778D01*
X754890Y64987D01*
X754807Y65237D01*
X754890Y65487D01*
X755098Y65695D01*
X755473Y65820D01*
X755848Y65778D01*
X756223Y65612D01*
G01X757140Y75810D02*
Y79810D01*
X764540D01*
G01X765803Y71610D02*
Y74110D01*
X764762D01*
X764428Y73985D01*
X764220Y73818D01*
X764137Y73485D01*
X764220Y73152D01*
X764470Y72943D01*
X764762Y72818D01*
X765803D01*
G01X764762D02*
X764137Y71610D01*
G01X762662Y73693D02*
X762412Y73943D01*
X762120Y74068D01*
X761787Y74110D01*
X761370Y74027D01*
X761078Y73818D01*
X760995Y73568D01*
X761037Y73318D01*
X761203Y73110D01*
X762037Y72693D01*
X762412Y72402D01*
X762662Y71985D01*
X762745Y71610D01*
X760995D01*
G01X758270D02*
Y74110D01*
X759812Y72318D01*
X757728D01*
G01X755670Y71610D02*
Y74110D01*
X756170Y73610D01*
G01Y71610D02*
X755170D01*
G01X757170Y84100D02*
Y88100D01*
X764570D01*
G01X751000Y89950D02*
X751042Y89617D01*
X751208Y89325D01*
X751458Y89075D01*
X751750Y88908D01*
X752083Y88825D01*
X752417D01*
X752750Y88908D01*
X753042Y89075D01*
X753292Y89325D01*
X753458Y89617D01*
X753500Y89950D01*
X753458Y90283D01*
X753292Y90575D01*
X753042Y90825D01*
X752750Y90992D01*
X752417Y91075D01*
X752083D01*
X751750Y90992D01*
X751458Y90825D01*
X751208Y90575D01*
X751042Y90283D01*
X751000Y89950D01*
G01X751667Y90283D02*
X751000Y90783D01*
G01X751500Y92133D02*
X751208Y92383D01*
X751042Y92717D01*
X751000Y93092D01*
X751042Y93425D01*
X751250Y93758D01*
X751500Y93967D01*
X751750Y94008D01*
X752042Y93925D01*
X752250Y93633D01*
X752333Y93342D01*
Y92967D01*
G01Y93342D02*
X752458Y93592D01*
X752667Y93800D01*
X752917Y93883D01*
X753167Y93800D01*
X753375Y93592D01*
X753500Y93217D01*
X753458Y92842D01*
X753292Y92467D01*
G01X768400Y89230D02*
X754400D01*
G01Y102230D02*
X768400D01*
G01X754400Y89230D02*
Y102230D01*
G01X760792Y108267D02*
X760917Y108017D01*
X761000Y107725D01*
Y107392D01*
X760875Y107017D01*
X760667Y106725D01*
X760417Y106517D01*
X760000Y106350D01*
X759625Y106308D01*
X759250Y106392D01*
X759000Y106517D01*
X758750Y106767D01*
X758583Y107058D01*
X758500Y107350D01*
Y107642D01*
X758583Y107933D01*
X758708Y108183D01*
X758875Y108392D01*
G01X759000Y109533D02*
X758708Y109783D01*
X758542Y110117D01*
X758500Y110492D01*
X758542Y110825D01*
X758750Y111158D01*
X759000Y111367D01*
X759250Y111408D01*
X759542Y111325D01*
X759750Y111033D01*
X759833Y110742D01*
Y110367D01*
G01Y110742D02*
X759958Y110992D01*
X760167Y111200D01*
X760417Y111283D01*
X760667Y111200D01*
X760875Y110992D01*
X761000Y110617D01*
X760958Y110242D01*
X760792Y109867D01*
G01X758500Y113467D02*
X759042Y113550D01*
X759500Y113675D01*
X759917Y113842D01*
X760375Y114050D01*
X761000Y114383D01*
Y112717D01*
G01X758500Y116567D02*
X759042Y116650D01*
X759500Y116775D01*
X759917Y116942D01*
X760375Y117150D01*
X761000Y117483D01*
Y115817D01*
G01X756792Y108267D02*
X756917Y108017D01*
X757000Y107725D01*
Y107392D01*
X756875Y107017D01*
X756667Y106725D01*
X756417Y106517D01*
X756000Y106350D01*
X755625Y106308D01*
X755250Y106392D01*
X755000Y106517D01*
X754750Y106767D01*
X754583Y107058D01*
X754500Y107350D01*
Y107642D01*
X754583Y107933D01*
X754708Y108183D01*
X754875Y108392D01*
G01X755000Y109533D02*
X754708Y109783D01*
X754542Y110117D01*
X754500Y110492D01*
X754542Y110825D01*
X754750Y111158D01*
X755000Y111367D01*
X755250Y111408D01*
X755542Y111325D01*
X755750Y111033D01*
X755833Y110742D01*
Y110367D01*
G01Y110742D02*
X755958Y110992D01*
X756167Y111200D01*
X756417Y111283D01*
X756667Y111200D01*
X756875Y110992D01*
X757000Y110617D01*
X756958Y110242D01*
X756792Y109867D01*
G01X754500Y113467D02*
X755042Y113550D01*
X755500Y113675D01*
X755917Y113842D01*
X756375Y114050D01*
X757000Y114383D01*
Y112717D01*
G01X754792Y115942D02*
X754583Y116233D01*
X754500Y116567D01*
X754583Y116900D01*
X754833Y117192D01*
X755208Y117400D01*
X755583Y117483D01*
X756042D01*
X756417Y117400D01*
X756750Y117192D01*
X756917Y116942D01*
X757000Y116650D01*
X756917Y116317D01*
X756750Y116067D01*
X756500Y115900D01*
X756167Y115817D01*
X755875Y115900D01*
X755583Y116108D01*
X755417Y116358D01*
X755375Y116650D01*
X755458Y116983D01*
X755667Y117233D01*
X756042Y117483D01*
G01X743607Y94421D02*
Y91921D01*
G01X744565Y94421D02*
X742649D01*
G01X741340Y91921D02*
Y94421D01*
X740340D01*
X740007Y94296D01*
X739757Y94004D01*
X739674Y93671D01*
X739757Y93338D01*
X739965Y93088D01*
X740340Y92963D01*
X741340D01*
G01X738199D02*
X737907Y93254D01*
X737657Y93421D01*
X737324Y93504D01*
X737032Y93421D01*
X736824Y93254D01*
X736657Y93004D01*
X736615Y92713D01*
X736657Y92463D01*
X736824Y92213D01*
X737074Y92004D01*
X737365Y91921D01*
X737699Y92004D01*
X737990Y92254D01*
X738157Y92629D01*
X738199Y93046D01*
X738115Y93588D01*
X737990Y93879D01*
X737782Y94171D01*
X737490Y94379D01*
X737199Y94421D01*
X736907Y94338D01*
X736699Y94129D01*
G01X734390Y91921D02*
X734307Y92463D01*
X734182Y92921D01*
X734015Y93338D01*
X733807Y93796D01*
X733474Y94421D01*
X735140D01*
G01X743607Y90421D02*
Y87921D01*
G01X744565Y90421D02*
X742649D01*
G01X741340Y87921D02*
Y90421D01*
X740340D01*
X740007Y90296D01*
X739757Y90004D01*
X739674Y89671D01*
X739757Y89338D01*
X739965Y89088D01*
X740340Y88963D01*
X741340D01*
G01X737407Y87921D02*
Y90421D01*
X737907Y89921D01*
G01Y87921D02*
X736907D01*
G01X733807D02*
Y90421D01*
X735349Y88629D01*
X733265D01*
G01X732124Y88296D02*
X731874Y88088D01*
X731582Y87963D01*
X731207Y87921D01*
X730832Y88004D01*
X730540Y88171D01*
X730332Y88463D01*
X730290Y88796D01*
X730374Y89129D01*
X730582Y89338D01*
X730874Y89504D01*
X731165Y89546D01*
X731457Y89504D01*
X731832Y89338D01*
X731707Y90421D01*
X730582D01*
G01X727573Y93981D02*
Y91481D01*
G01X728531Y93981D02*
X726615D01*
G01X725306Y91481D02*
Y93981D01*
X724306D01*
X723973Y93856D01*
X723723Y93564D01*
X723640Y93231D01*
X723723Y92898D01*
X723931Y92648D01*
X724306Y92523D01*
X725306D01*
G01X721373Y91481D02*
Y93981D01*
X721873Y93481D01*
G01Y91481D02*
X720873D01*
G01X719065Y93564D02*
X718815Y93814D01*
X718523Y93939D01*
X718190Y93981D01*
X717773Y93898D01*
X717481Y93689D01*
X717398Y93439D01*
X717440Y93189D01*
X717606Y92981D01*
X718440Y92564D01*
X718815Y92273D01*
X719065Y91856D01*
X719148Y91481D01*
X717398D01*
G01X715881Y91773D02*
X715590Y91564D01*
X715256Y91481D01*
X714923Y91564D01*
X714631Y91814D01*
X714423Y92189D01*
X714340Y92564D01*
Y93023D01*
X714423Y93398D01*
X714631Y93731D01*
X714881Y93898D01*
X715173Y93981D01*
X715506Y93898D01*
X715756Y93731D01*
X715923Y93481D01*
X716006Y93148D01*
X715923Y92856D01*
X715715Y92564D01*
X715465Y92398D01*
X715173Y92356D01*
X714840Y92439D01*
X714590Y92648D01*
X714340Y93023D01*
G01X717833Y165500D02*
X714500Y172500D01*
X711167Y165500D01*
G01X712367Y167950D02*
X716633D01*
G01X750983Y162500D02*
Y165000D01*
X749942D01*
X749608Y164875D01*
X749400Y164708D01*
X749317Y164375D01*
X749400Y164042D01*
X749650Y163833D01*
X749942Y163708D01*
X750983D01*
G01X749942D02*
X749317Y162500D01*
G01X747050D02*
Y165000D01*
X747550Y164500D01*
G01Y162500D02*
X746550D01*
G01X744658Y162792D02*
X744367Y162583D01*
X744033Y162500D01*
X743700Y162583D01*
X743408Y162833D01*
X743200Y163208D01*
X743117Y163583D01*
Y164042D01*
X743200Y164417D01*
X743408Y164750D01*
X743658Y164917D01*
X743950Y165000D01*
X744283Y164917D01*
X744533Y164750D01*
X744700Y164500D01*
X744783Y164167D01*
X744700Y163875D01*
X744492Y163583D01*
X744242Y163417D01*
X743950Y163375D01*
X743617Y163458D01*
X743367Y163667D01*
X743117Y164042D01*
G01X740850Y162500D02*
Y165000D01*
X741350Y164500D01*
G01Y162500D02*
X740350D01*
G01X739652Y162315D02*
Y158315D01*
X732252D01*
G01X762515Y138383D02*
Y134383D01*
X755115D01*
G01X759200Y171500D02*
Y167500D01*
X751800D01*
G01X762515Y142433D02*
Y138433D01*
X755115D01*
G01X759421Y147050D02*
Y143050D01*
X752021D01*
G01X759700Y162800D02*
Y158800D01*
X752300D01*
G01X766983Y126667D02*
Y129167D01*
X765942D01*
X765608Y129042D01*
X765400Y128875D01*
X765317Y128542D01*
X765400Y128209D01*
X765650Y128000D01*
X765942Y127875D01*
X766983D01*
G01X765942D02*
X765317Y126667D01*
G01X763842Y128750D02*
X763592Y129000D01*
X763300Y129125D01*
X762967Y129167D01*
X762550Y129084D01*
X762258Y128875D01*
X762175Y128625D01*
X762217Y128375D01*
X762383Y128167D01*
X763217Y127750D01*
X763592Y127459D01*
X763842Y127042D01*
X763925Y126667D01*
X762175D01*
G01X760867Y127167D02*
X760617Y126875D01*
X760283Y126709D01*
X759908Y126667D01*
X759575Y126709D01*
X759242Y126917D01*
X759033Y127167D01*
X758992Y127417D01*
X759075Y127709D01*
X759367Y127917D01*
X759658Y128000D01*
X760033D01*
G01X759658D02*
X759408Y128125D01*
X759200Y128334D01*
X759117Y128584D01*
X759200Y128834D01*
X759408Y129042D01*
X759783Y129167D01*
X760158Y129125D01*
X760533Y128959D01*
G01X757767Y127167D02*
X757517Y126875D01*
X757183Y126709D01*
X756808Y126667D01*
X756475Y126709D01*
X756142Y126917D01*
X755933Y127167D01*
X755892Y127417D01*
X755975Y127709D01*
X756267Y127917D01*
X756558Y128000D01*
X756933D01*
G01X756558D02*
X756308Y128125D01*
X756100Y128334D01*
X756017Y128584D01*
X756100Y128834D01*
X756308Y129042D01*
X756683Y129167D01*
X757058Y129125D01*
X757433Y128959D01*
G01X762515Y134181D02*
Y130181D01*
X755115D01*
G01X711447Y140406D02*
Y136406D01*
X704047D01*
G01X715500Y140650D02*
X719500D01*
Y133250D01*
G01X711500Y140650D02*
X715500D01*
Y133250D01*
G01X756483Y150000D02*
Y152500D01*
X755442D01*
X755108Y152375D01*
X754900Y152208D01*
X754817Y151875D01*
X754900Y151542D01*
X755150Y151333D01*
X755442Y151208D01*
X756483D01*
G01X755442D02*
X754817Y150000D01*
G01X752550D02*
Y152500D01*
X753050Y152000D01*
G01Y150000D02*
X752050D01*
G01X749533D02*
X749450Y150542D01*
X749325Y151000D01*
X749158Y151417D01*
X748950Y151875D01*
X748617Y152500D01*
X750283D01*
G01X747142Y151042D02*
X746850Y151333D01*
X746600Y151500D01*
X746267Y151583D01*
X745975Y151500D01*
X745767Y151333D01*
X745600Y151083D01*
X745558Y150792D01*
X745600Y150542D01*
X745767Y150292D01*
X746017Y150083D01*
X746308Y150000D01*
X746642Y150083D01*
X746933Y150333D01*
X747100Y150708D01*
X747142Y151125D01*
X747058Y151667D01*
X746933Y151958D01*
X746725Y152250D01*
X746433Y152458D01*
X746142Y152500D01*
X745850Y152417D01*
X745642Y152208D01*
G01X742279Y153899D02*
Y149899D01*
X734879D01*
G01X755983Y154000D02*
Y156500D01*
X754942D01*
X754608Y156375D01*
X754400Y156208D01*
X754317Y155875D01*
X754400Y155542D01*
X754650Y155333D01*
X754942Y155208D01*
X755983D01*
G01X754942D02*
X754317Y154000D01*
G01X752050D02*
Y156500D01*
X752550Y156000D01*
G01Y154000D02*
X751550D01*
G01X749033D02*
X748950Y154542D01*
X748825Y155000D01*
X748658Y155417D01*
X748450Y155875D01*
X748117Y156500D01*
X749783D01*
G01X746642Y156083D02*
X746392Y156333D01*
X746100Y156458D01*
X745767Y156500D01*
X745350Y156417D01*
X745058Y156208D01*
X744975Y155958D01*
X745017Y155708D01*
X745183Y155500D01*
X746017Y155083D01*
X746392Y154792D01*
X746642Y154375D01*
X746725Y154000D01*
X744975D01*
G01X734879Y153899D02*
Y157899D01*
X742279D01*
G01X748650Y171500D02*
Y169000D01*
G01X749608Y171500D02*
X747692D01*
G01X746383Y169000D02*
Y171500D01*
X745383D01*
X745050Y171375D01*
X744800Y171083D01*
X744717Y170750D01*
X744800Y170417D01*
X745008Y170167D01*
X745383Y170042D01*
X746383D01*
G01X743158Y169292D02*
X742867Y169083D01*
X742533Y169000D01*
X742200Y169083D01*
X741908Y169333D01*
X741700Y169708D01*
X741617Y170083D01*
Y170542D01*
X741700Y170917D01*
X741908Y171250D01*
X742158Y171417D01*
X742450Y171500D01*
X742783Y171417D01*
X743033Y171250D01*
X743200Y171000D01*
X743283Y170667D01*
X743200Y170375D01*
X742992Y170083D01*
X742742Y169917D01*
X742450Y169875D01*
X742117Y169958D01*
X741867Y170167D01*
X741617Y170542D01*
G01X739350Y169000D02*
Y171500D01*
X739850Y171000D01*
G01Y169000D02*
X738850D01*
G01X764200Y124000D02*
Y121500D01*
G01X765158Y124000D02*
X763242D01*
G01X761933Y121500D02*
Y124000D01*
X760933D01*
X760600Y123875D01*
X760350Y123583D01*
X760267Y123250D01*
X760350Y122917D01*
X760558Y122667D01*
X760933Y122542D01*
X761933D01*
G01X758000Y121500D02*
Y124000D01*
X758500Y123500D01*
G01Y121500D02*
X757500D01*
G01X754900D02*
Y124000D01*
X755400Y123500D01*
G01Y121500D02*
X754400D01*
G01X751883D02*
X751800Y122042D01*
X751675Y122500D01*
X751508Y122917D01*
X751300Y123375D01*
X750967Y124000D01*
X752633D01*
G01X761700Y177667D02*
Y175167D01*
G01X762658Y177667D02*
X760742D01*
G01X759433Y175167D02*
Y177667D01*
X758433D01*
X758100Y177542D01*
X757850Y177250D01*
X757767Y176917D01*
X757850Y176584D01*
X758058Y176334D01*
X758433Y176209D01*
X759433D01*
G01X755500Y175167D02*
Y177667D01*
X756000Y177167D01*
G01Y175167D02*
X755000D01*
G01X752400Y177667D02*
X752733Y177584D01*
X752983Y177375D01*
X753150Y177125D01*
X753275Y176792D01*
X753317Y176417D01*
X753275Y176042D01*
X753150Y175709D01*
X752983Y175459D01*
X752733Y175250D01*
X752400Y175167D01*
X752067Y175250D01*
X751817Y175459D01*
X751650Y175709D01*
X751525Y176042D01*
X751483Y176417D01*
X751525Y176792D01*
X751650Y177125D01*
X751817Y177375D01*
X752067Y177584D01*
X752400Y177667D01*
G01X750008Y175459D02*
X749717Y175250D01*
X749383Y175167D01*
X749050Y175250D01*
X748758Y175500D01*
X748550Y175875D01*
X748467Y176250D01*
Y176709D01*
X748550Y177084D01*
X748758Y177417D01*
X749008Y177584D01*
X749300Y177667D01*
X749633Y177584D01*
X749883Y177417D01*
X750050Y177167D01*
X750133Y176834D01*
X750050Y176542D01*
X749842Y176250D01*
X749592Y176084D01*
X749300Y176042D01*
X748967Y176125D01*
X748717Y176334D01*
X748467Y176709D01*
G01X709167Y221017D02*
X711667D01*
Y222058D01*
X711542Y222392D01*
X711375Y222600D01*
X711042Y222683D01*
X710709Y222600D01*
X710500Y222350D01*
X710375Y222058D01*
Y221017D01*
G01Y222058D02*
X709167Y222683D01*
G01X709667Y224033D02*
X709375Y224283D01*
X709209Y224617D01*
X709167Y224992D01*
X709209Y225325D01*
X709417Y225658D01*
X709667Y225867D01*
X709917Y225908D01*
X710209Y225825D01*
X710417Y225533D01*
X710500Y225242D01*
Y224867D01*
G01Y225242D02*
X710625Y225492D01*
X710834Y225700D01*
X711084Y225783D01*
X711334Y225700D01*
X711542Y225492D01*
X711667Y225117D01*
X711625Y224742D01*
X711459Y224367D01*
G01X709459Y227342D02*
X709250Y227633D01*
X709167Y227967D01*
X709250Y228300D01*
X709500Y228592D01*
X709875Y228800D01*
X710250Y228883D01*
X710709D01*
X711084Y228800D01*
X711417Y228592D01*
X711584Y228342D01*
X711667Y228050D01*
X711584Y227717D01*
X711417Y227467D01*
X711167Y227300D01*
X710834Y227217D01*
X710542Y227300D01*
X710250Y227508D01*
X710084Y227758D01*
X710042Y228050D01*
X710125Y228383D01*
X710334Y228633D01*
X710709Y228883D01*
G01X709167Y231650D02*
X711667D01*
X709875Y230108D01*
Y232192D01*
G01X708800Y220000D02*
X712800D01*
Y212600D01*
G01X718167Y221017D02*
X720667D01*
Y222058D01*
X720542Y222392D01*
X720375Y222600D01*
X720042Y222683D01*
X719709Y222600D01*
X719500Y222350D01*
X719375Y222058D01*
Y221017D01*
G01Y222058D02*
X718167Y222683D01*
G01X720250Y224158D02*
X720500Y224408D01*
X720625Y224700D01*
X720667Y225033D01*
X720584Y225450D01*
X720375Y225742D01*
X720125Y225825D01*
X719875Y225783D01*
X719667Y225617D01*
X719250Y224783D01*
X718959Y224408D01*
X718542Y224158D01*
X718167Y224075D01*
Y225825D01*
G01Y228050D02*
X720667D01*
X720167Y227550D01*
G01X718167D02*
Y228550D01*
G01Y231150D02*
X718209Y231442D01*
X718334Y231775D01*
X718542Y231983D01*
X718834Y232067D01*
X719125Y231983D01*
X719375Y231733D01*
X719500Y231358D01*
Y230942D01*
X719584Y230692D01*
X719792Y230483D01*
X720084Y230400D01*
X720375Y230525D01*
X720584Y230817D01*
X720667Y231150D01*
X720584Y231483D01*
X720375Y231775D01*
X720084Y231900D01*
X719792Y231817D01*
X719584Y231608D01*
X719500Y231358D01*
Y230942D01*
X719375Y230567D01*
X719125Y230317D01*
X718834Y230233D01*
X718542Y230317D01*
X718334Y230525D01*
X718209Y230858D01*
X718167Y231150D01*
G01X717700Y220000D02*
X721700D01*
Y212600D01*
G01X728530Y235171D02*
Y291771D01*
G01X795930Y235171D02*
X728530D01*
G01X737700Y203167D02*
Y200667D01*
G01X738658Y203167D02*
X736742D01*
G01X735433Y200667D02*
Y203167D01*
X734433D01*
X734100Y203042D01*
X733850Y202750D01*
X733767Y202417D01*
X733850Y202084D01*
X734058Y201834D01*
X734433Y201709D01*
X735433D01*
G01X731500Y200667D02*
Y203167D01*
X732000Y202667D01*
G01Y200667D02*
X731000D01*
G01X728400D02*
Y203167D01*
X728900Y202667D01*
G01Y200667D02*
X727900D01*
G01X726217Y201167D02*
X725967Y200875D01*
X725633Y200709D01*
X725258Y200667D01*
X724925Y200709D01*
X724592Y200917D01*
X724383Y201167D01*
X724342Y201417D01*
X724425Y201709D01*
X724717Y201917D01*
X725008Y202000D01*
X725383D01*
G01X725008D02*
X724758Y202125D01*
X724550Y202334D01*
X724467Y202584D01*
X724550Y202834D01*
X724758Y203042D01*
X725133Y203167D01*
X725508Y203125D01*
X725883Y202959D01*
G01X707867Y200900D02*
X705367D01*
G01X707867Y199942D02*
Y201858D01*
G01X705367Y203167D02*
X707867D01*
Y204167D01*
X707742Y204500D01*
X707450Y204750D01*
X707117Y204833D01*
X706784Y204750D01*
X706534Y204542D01*
X706409Y204167D01*
Y203167D01*
G01X705367Y207100D02*
X707867D01*
X707367Y206600D01*
G01X705367D02*
Y207600D01*
G01Y210200D02*
X707867D01*
X707367Y209700D01*
G01X705367D02*
Y210700D01*
G01X707450Y212508D02*
X707700Y212758D01*
X707825Y213050D01*
X707867Y213383D01*
X707784Y213800D01*
X707575Y214092D01*
X707325Y214175D01*
X707075Y214133D01*
X706867Y213967D01*
X706450Y213133D01*
X706159Y212758D01*
X705742Y212508D01*
X705367Y212425D01*
Y214175D01*
G01X739200Y214500D02*
Y212000D01*
G01X740158Y214500D02*
X738242D01*
G01X736933Y212000D02*
Y214500D01*
X735933D01*
X735600Y214375D01*
X735350Y214083D01*
X735267Y213750D01*
X735350Y213417D01*
X735558Y213167D01*
X735933Y213042D01*
X736933D01*
G01X733000Y212000D02*
Y214500D01*
X733500Y214000D01*
G01Y212000D02*
X732500D01*
G01X729900D02*
Y214500D01*
X730400Y214000D01*
G01Y212000D02*
X729400D01*
G01X726800D02*
Y214500D01*
X727300Y214000D01*
G01Y212000D02*
X726300D01*
G01X761700Y185500D02*
Y183000D01*
G01X762658Y185500D02*
X760742D01*
G01X759433Y183000D02*
Y185500D01*
X758433D01*
X758100Y185375D01*
X757850Y185083D01*
X757767Y184750D01*
X757850Y184417D01*
X758058Y184167D01*
X758433Y184042D01*
X759433D01*
G01X755500Y183000D02*
Y185500D01*
X756000Y185000D01*
G01Y183000D02*
X755000D01*
G01X752400D02*
Y185500D01*
X752900Y185000D01*
G01Y183000D02*
X751900D01*
G01X749300Y185500D02*
X749633Y185417D01*
X749883Y185208D01*
X750050Y184958D01*
X750175Y184625D01*
X750217Y184250D01*
X750175Y183875D01*
X750050Y183542D01*
X749883Y183292D01*
X749633Y183083D01*
X749300Y183000D01*
X748967Y183083D01*
X748717Y183292D01*
X748550Y183542D01*
X748425Y183875D01*
X748383Y184250D01*
X748425Y184625D01*
X748550Y184958D01*
X748717Y185208D01*
X748967Y185417D01*
X749300Y185500D01*
G01X751667Y190800D02*
X749167D01*
G01X751667Y189842D02*
Y191758D01*
G01X749167Y193067D02*
X751667D01*
Y194067D01*
X751542Y194400D01*
X751250Y194650D01*
X750917Y194733D01*
X750584Y194650D01*
X750334Y194442D01*
X750209Y194067D01*
Y193067D01*
G01X749167Y197000D02*
X751667D01*
X751167Y196500D01*
G01X749167D02*
Y197500D01*
G01X751667Y200100D02*
X751584Y199767D01*
X751375Y199517D01*
X751125Y199350D01*
X750792Y199225D01*
X750417Y199183D01*
X750042Y199225D01*
X749709Y199350D01*
X749459Y199517D01*
X749250Y199767D01*
X749167Y200100D01*
X749250Y200433D01*
X749459Y200683D01*
X749709Y200850D01*
X750042Y200975D01*
X750417Y201017D01*
X750792Y200975D01*
X751125Y200850D01*
X751375Y200683D01*
X751584Y200433D01*
X751667Y200100D01*
G01X749167Y203117D02*
X749709Y203200D01*
X750167Y203325D01*
X750584Y203492D01*
X751042Y203700D01*
X751667Y204033D01*
Y202367D01*
G01X739600Y185300D02*
X737100D01*
G01X739600Y184342D02*
Y186258D01*
G01X737100Y187567D02*
X739600D01*
Y188567D01*
X739475Y188900D01*
X739183Y189150D01*
X738850Y189233D01*
X738517Y189150D01*
X738267Y188942D01*
X738142Y188567D01*
Y187567D01*
G01X737100Y191500D02*
X739600D01*
X739100Y191000D01*
G01X737100D02*
Y192000D01*
G01X739600Y194600D02*
X739517Y194267D01*
X739308Y194017D01*
X739058Y193850D01*
X738725Y193725D01*
X738350Y193683D01*
X737975Y193725D01*
X737642Y193850D01*
X737392Y194017D01*
X737183Y194267D01*
X737100Y194600D01*
X737183Y194933D01*
X737392Y195183D01*
X737642Y195350D01*
X737975Y195475D01*
X738350Y195517D01*
X738725Y195475D01*
X739058Y195350D01*
X739308Y195183D01*
X739517Y194933D01*
X739600Y194600D01*
G01X738142Y196908D02*
X738433Y197200D01*
X738600Y197450D01*
X738683Y197783D01*
X738600Y198075D01*
X738433Y198283D01*
X738183Y198450D01*
X737892Y198492D01*
X737642Y198450D01*
X737392Y198283D01*
X737183Y198033D01*
X737100Y197742D01*
X737183Y197408D01*
X737433Y197117D01*
X737808Y196950D01*
X738225Y196908D01*
X738767Y196992D01*
X739058Y197117D01*
X739350Y197325D01*
X739558Y197617D01*
X739600Y197908D01*
X739517Y198200D01*
X739308Y198408D01*
G01X754700Y211667D02*
Y209167D01*
G01X755658Y211667D02*
X753742D01*
G01X752433Y209167D02*
Y211667D01*
X751433D01*
X751100Y211542D01*
X750850Y211250D01*
X750767Y210917D01*
X750850Y210584D01*
X751058Y210334D01*
X751433Y210209D01*
X752433D01*
G01X748500Y209167D02*
Y211667D01*
X749000Y211167D01*
G01Y209167D02*
X748000D01*
G01X745400Y211667D02*
X745733Y211584D01*
X745983Y211375D01*
X746150Y211125D01*
X746275Y210792D01*
X746317Y210417D01*
X746275Y210042D01*
X746150Y209709D01*
X745983Y209459D01*
X745733Y209250D01*
X745400Y209167D01*
X745067Y209250D01*
X744817Y209459D01*
X744650Y209709D01*
X744525Y210042D01*
X744483Y210417D01*
X744525Y210792D01*
X744650Y211125D01*
X744817Y211375D01*
X745067Y211584D01*
X745400Y211667D01*
G01X741800Y209167D02*
Y211667D01*
X743342Y209875D01*
X741258D01*
G01X716167Y218300D02*
X713667D01*
G01X716167Y217342D02*
Y219258D01*
G01X713667Y220567D02*
X716167D01*
Y221567D01*
X716042Y221900D01*
X715750Y222150D01*
X715417Y222233D01*
X715084Y222150D01*
X714834Y221942D01*
X714709Y221567D01*
Y220567D01*
G01X713667Y224500D02*
X716167D01*
X715667Y224000D01*
G01X713667D02*
Y225000D01*
G01X716167Y227600D02*
X716084Y227267D01*
X715875Y227017D01*
X715625Y226850D01*
X715292Y226725D01*
X714917Y226683D01*
X714542Y226725D01*
X714209Y226850D01*
X713959Y227017D01*
X713750Y227267D01*
X713667Y227600D01*
X713750Y227933D01*
X713959Y228183D01*
X714209Y228350D01*
X714542Y228475D01*
X714917Y228517D01*
X715292Y228475D01*
X715625Y228350D01*
X715875Y228183D01*
X716084Y227933D01*
X716167Y227600D01*
G01X715750Y229908D02*
X716000Y230158D01*
X716125Y230450D01*
X716167Y230783D01*
X716084Y231200D01*
X715875Y231492D01*
X715625Y231575D01*
X715375Y231533D01*
X715167Y231367D01*
X714750Y230533D01*
X714459Y230158D01*
X714042Y229908D01*
X713667Y229825D01*
Y231575D01*
G01X717983Y280500D02*
Y283000D01*
X716942D01*
X716608Y282875D01*
X716400Y282708D01*
X716317Y282375D01*
X716400Y282042D01*
X716650Y281833D01*
X716942Y281708D01*
X717983D01*
G01X716942D02*
X716317Y280500D01*
G01X714842Y282583D02*
X714592Y282833D01*
X714300Y282958D01*
X713967Y283000D01*
X713550Y282917D01*
X713258Y282708D01*
X713175Y282458D01*
X713217Y282208D01*
X713383Y282000D01*
X714217Y281583D01*
X714592Y281292D01*
X714842Y280875D01*
X714925Y280500D01*
X713175D01*
G01X711867Y281000D02*
X711617Y280708D01*
X711283Y280542D01*
X710908Y280500D01*
X710575Y280542D01*
X710242Y280750D01*
X710033Y281000D01*
X709992Y281250D01*
X710075Y281542D01*
X710367Y281750D01*
X710658Y281833D01*
X711033D01*
G01X710658D02*
X710408Y281958D01*
X710200Y282167D01*
X710117Y282417D01*
X710200Y282667D01*
X710408Y282875D01*
X710783Y283000D01*
X711158Y282958D01*
X711533Y282792D01*
G01X707850Y280500D02*
Y283000D01*
X708350Y282500D01*
G01Y280500D02*
X707350D01*
G01X710646Y274558D02*
Y278558D01*
X718046D01*
G01X765517Y298500D02*
Y296708D01*
X765350Y296333D01*
X765017Y296083D01*
X764600Y296000D01*
X764183Y296083D01*
X763850Y296333D01*
X763683Y296708D01*
Y298500D01*
G01X761500Y296000D02*
Y298500D01*
X762000Y298000D01*
G01Y296000D02*
X761000D01*
G01X758400D02*
X758108Y296042D01*
X757775Y296167D01*
X757567Y296375D01*
X757483Y296667D01*
X757567Y296958D01*
X757817Y297208D01*
X758192Y297333D01*
X758608D01*
X758858Y297417D01*
X759067Y297625D01*
X759150Y297917D01*
X759025Y298208D01*
X758733Y298417D01*
X758400Y298500D01*
X758067Y298417D01*
X757775Y298208D01*
X757650Y297917D01*
X757733Y297625D01*
X757942Y297417D01*
X758192Y297333D01*
X758608D01*
X758983Y297208D01*
X759233Y296958D01*
X759317Y296667D01*
X759233Y296375D01*
X759025Y296167D01*
X758692Y296042D01*
X758400Y296000D01*
G01X728530Y291771D02*
X795930D01*
G01X756587Y333538D02*
Y336038D01*
X755546D01*
X755212Y335913D01*
X755004Y335746D01*
X754921Y335413D01*
X755004Y335080D01*
X755254Y334871D01*
X755546Y334746D01*
X756587D01*
G01X755546D02*
X754921Y333538D01*
G01X752154D02*
Y336038D01*
X753696Y334246D01*
X751612D01*
G01X749554Y333538D02*
X749262Y333580D01*
X748929Y333705D01*
X748721Y333913D01*
X748637Y334205D01*
X748721Y334496D01*
X748971Y334746D01*
X749346Y334871D01*
X749762D01*
X750012Y334955D01*
X750221Y335163D01*
X750304Y335455D01*
X750179Y335746D01*
X749887Y335955D01*
X749554Y336038D01*
X749221Y335955D01*
X748929Y335746D01*
X748804Y335455D01*
X748887Y335163D01*
X749096Y334955D01*
X749346Y334871D01*
X749762D01*
X750137Y334746D01*
X750387Y334496D01*
X750471Y334205D01*
X750387Y333913D01*
X750179Y333705D01*
X749846Y333580D01*
X749554Y333538D01*
G01X746454D02*
X746162Y333580D01*
X745829Y333705D01*
X745621Y333913D01*
X745537Y334205D01*
X745621Y334496D01*
X745871Y334746D01*
X746246Y334871D01*
X746662D01*
X746912Y334955D01*
X747121Y335163D01*
X747204Y335455D01*
X747079Y335746D01*
X746787Y335955D01*
X746454Y336038D01*
X746121Y335955D01*
X745829Y335746D01*
X745704Y335455D01*
X745787Y335163D01*
X745996Y334955D01*
X746246Y334871D01*
X746662D01*
X747037Y334746D01*
X747287Y334496D01*
X747371Y334205D01*
X747287Y333913D01*
X747079Y333705D01*
X746746Y333580D01*
X746454Y333538D01*
G01X726804Y335538D02*
Y331538D01*
X719404D01*
G01X754837Y331930D02*
X755087Y332055D01*
X755379Y332138D01*
X755712D01*
X756087Y332013D01*
X756379Y331805D01*
X756587Y331555D01*
X756754Y331138D01*
X756796Y330763D01*
X756712Y330388D01*
X756587Y330138D01*
X756337Y329888D01*
X756046Y329721D01*
X755754Y329638D01*
X755462D01*
X755171Y329721D01*
X754921Y329846D01*
X754712Y330013D01*
G01X753446Y330680D02*
X753154Y330971D01*
X752904Y331138D01*
X752571Y331221D01*
X752279Y331138D01*
X752071Y330971D01*
X751904Y330721D01*
X751862Y330430D01*
X751904Y330180D01*
X752071Y329930D01*
X752321Y329721D01*
X752612Y329638D01*
X752946Y329721D01*
X753237Y329971D01*
X753404Y330346D01*
X753446Y330763D01*
X753362Y331305D01*
X753237Y331596D01*
X753029Y331888D01*
X752737Y332096D01*
X752446Y332138D01*
X752154Y332055D01*
X751946Y331846D01*
G01X750471Y330013D02*
X750221Y329805D01*
X749929Y329680D01*
X749554Y329638D01*
X749179Y329721D01*
X748887Y329888D01*
X748679Y330180D01*
X748637Y330513D01*
X748721Y330846D01*
X748929Y331055D01*
X749221Y331221D01*
X749512Y331263D01*
X749804Y331221D01*
X750179Y331055D01*
X750054Y332138D01*
X748929D01*
G01X747162Y329930D02*
X746871Y329721D01*
X746537Y329638D01*
X746204Y329721D01*
X745912Y329971D01*
X745704Y330346D01*
X745621Y330721D01*
Y331180D01*
X745704Y331555D01*
X745912Y331888D01*
X746162Y332055D01*
X746454Y332138D01*
X746787Y332055D01*
X747037Y331888D01*
X747204Y331638D01*
X747287Y331305D01*
X747204Y331013D01*
X746996Y330721D01*
X746746Y330555D01*
X746454Y330513D01*
X746121Y330596D01*
X745871Y330805D01*
X745621Y331180D01*
G01X754837Y347330D02*
X755087Y347455D01*
X755379Y347538D01*
X755712D01*
X756087Y347413D01*
X756379Y347205D01*
X756587Y346955D01*
X756754Y346538D01*
X756796Y346163D01*
X756712Y345788D01*
X756587Y345538D01*
X756337Y345288D01*
X756046Y345121D01*
X755754Y345038D01*
X755462D01*
X755171Y345121D01*
X754921Y345246D01*
X754712Y345413D01*
G01X753446Y346080D02*
X753154Y346371D01*
X752904Y346538D01*
X752571Y346621D01*
X752279Y346538D01*
X752071Y346371D01*
X751904Y346121D01*
X751862Y345830D01*
X751904Y345580D01*
X752071Y345330D01*
X752321Y345121D01*
X752612Y345038D01*
X752946Y345121D01*
X753237Y345371D01*
X753404Y345746D01*
X753446Y346163D01*
X753362Y346705D01*
X753237Y346996D01*
X753029Y347288D01*
X752737Y347496D01*
X752446Y347538D01*
X752154Y347455D01*
X751946Y347246D01*
G01X750346Y347121D02*
X750096Y347371D01*
X749804Y347496D01*
X749471Y347538D01*
X749054Y347455D01*
X748762Y347246D01*
X748679Y346996D01*
X748721Y346746D01*
X748887Y346538D01*
X749721Y346121D01*
X750096Y345830D01*
X750346Y345413D01*
X750429Y345038D01*
X748679D01*
G01X747162Y345330D02*
X746871Y345121D01*
X746537Y345038D01*
X746204Y345121D01*
X745912Y345371D01*
X745704Y345746D01*
X745621Y346121D01*
Y346580D01*
X745704Y346955D01*
X745912Y347288D01*
X746162Y347455D01*
X746454Y347538D01*
X746787Y347455D01*
X747037Y347288D01*
X747204Y347038D01*
X747287Y346705D01*
X747204Y346413D01*
X746996Y346121D01*
X746746Y345955D01*
X746454Y345913D01*
X746121Y345996D01*
X745871Y346205D01*
X745621Y346580D01*
G01X754837Y355330D02*
X755087Y355455D01*
X755379Y355538D01*
X755712D01*
X756087Y355413D01*
X756379Y355205D01*
X756587Y354955D01*
X756754Y354538D01*
X756796Y354163D01*
X756712Y353788D01*
X756587Y353538D01*
X756337Y353288D01*
X756046Y353121D01*
X755754Y353038D01*
X755462D01*
X755171Y353121D01*
X754921Y353246D01*
X754712Y353413D01*
G01X753446Y354080D02*
X753154Y354371D01*
X752904Y354538D01*
X752571Y354621D01*
X752279Y354538D01*
X752071Y354371D01*
X751904Y354121D01*
X751862Y353830D01*
X751904Y353580D01*
X752071Y353330D01*
X752321Y353121D01*
X752612Y353038D01*
X752946Y353121D01*
X753237Y353371D01*
X753404Y353746D01*
X753446Y354163D01*
X753362Y354705D01*
X753237Y354996D01*
X753029Y355288D01*
X752737Y355496D01*
X752446Y355538D01*
X752154Y355455D01*
X751946Y355246D01*
G01X750346Y355121D02*
X750096Y355371D01*
X749804Y355496D01*
X749471Y355538D01*
X749054Y355455D01*
X748762Y355246D01*
X748679Y354996D01*
X748721Y354746D01*
X748887Y354538D01*
X749721Y354121D01*
X750096Y353830D01*
X750346Y353413D01*
X750429Y353038D01*
X748679D01*
G01X746454D02*
X746162Y353080D01*
X745829Y353205D01*
X745621Y353413D01*
X745537Y353705D01*
X745621Y353996D01*
X745871Y354246D01*
X746246Y354371D01*
X746662D01*
X746912Y354455D01*
X747121Y354663D01*
X747204Y354955D01*
X747079Y355246D01*
X746787Y355455D01*
X746454Y355538D01*
X746121Y355455D01*
X745829Y355246D01*
X745704Y354955D01*
X745787Y354663D01*
X745996Y354455D01*
X746246Y354371D01*
X746662D01*
X747037Y354246D01*
X747287Y353996D01*
X747371Y353705D01*
X747287Y353413D01*
X747079Y353205D01*
X746746Y353080D01*
X746454Y353038D01*
G01X754837Y340830D02*
X755087Y340955D01*
X755379Y341038D01*
X755712D01*
X756087Y340913D01*
X756379Y340705D01*
X756587Y340455D01*
X756754Y340038D01*
X756796Y339663D01*
X756712Y339288D01*
X756587Y339038D01*
X756337Y338788D01*
X756046Y338621D01*
X755754Y338538D01*
X755462D01*
X755171Y338621D01*
X754921Y338746D01*
X754712Y338913D01*
G01X753446Y339580D02*
X753154Y339871D01*
X752904Y340038D01*
X752571Y340121D01*
X752279Y340038D01*
X752071Y339871D01*
X751904Y339621D01*
X751862Y339330D01*
X751904Y339080D01*
X752071Y338830D01*
X752321Y338621D01*
X752612Y338538D01*
X752946Y338621D01*
X753237Y338871D01*
X753404Y339246D01*
X753446Y339663D01*
X753362Y340205D01*
X753237Y340496D01*
X753029Y340788D01*
X752737Y340996D01*
X752446Y341038D01*
X752154Y340955D01*
X751946Y340746D01*
G01X750346Y339580D02*
X750054Y339871D01*
X749804Y340038D01*
X749471Y340121D01*
X749179Y340038D01*
X748971Y339871D01*
X748804Y339621D01*
X748762Y339330D01*
X748804Y339080D01*
X748971Y338830D01*
X749221Y338621D01*
X749512Y338538D01*
X749846Y338621D01*
X750137Y338871D01*
X750304Y339246D01*
X750346Y339663D01*
X750262Y340205D01*
X750137Y340496D01*
X749929Y340788D01*
X749637Y340996D01*
X749346Y341038D01*
X749054Y340955D01*
X748846Y340746D01*
G01X746454Y341038D02*
X746787Y340955D01*
X747037Y340746D01*
X747204Y340496D01*
X747329Y340163D01*
X747371Y339788D01*
X747329Y339413D01*
X747204Y339080D01*
X747037Y338830D01*
X746787Y338621D01*
X746454Y338538D01*
X746121Y338621D01*
X745871Y338830D01*
X745704Y339080D01*
X745579Y339413D01*
X745537Y339788D01*
X745579Y340163D01*
X745704Y340496D01*
X745871Y340746D01*
X746121Y340955D01*
X746454Y341038D01*
G01X721000Y476400D02*
X721333Y476442D01*
X721625Y476608D01*
X721875Y476858D01*
X722042Y477150D01*
X722125Y477483D01*
Y477817D01*
X722042Y478150D01*
X721875Y478442D01*
X721625Y478692D01*
X721333Y478858D01*
X721000Y478900D01*
X720667Y478858D01*
X720375Y478692D01*
X720125Y478442D01*
X719958Y478150D01*
X719875Y477817D01*
Y477483D01*
X719958Y477150D01*
X720125Y476858D01*
X720375Y476608D01*
X720667Y476442D01*
X721000Y476400D01*
G01X720667Y477067D02*
X720167Y476400D01*
G01X718817Y476900D02*
X718567Y476608D01*
X718233Y476442D01*
X717858Y476400D01*
X717525Y476442D01*
X717192Y476650D01*
X716983Y476900D01*
X716942Y477150D01*
X717025Y477442D01*
X717317Y477650D01*
X717608Y477733D01*
X717983D01*
G01X717608D02*
X717358Y477858D01*
X717150Y478067D01*
X717067Y478317D01*
X717150Y478567D01*
X717358Y478775D01*
X717733Y478900D01*
X718108Y478858D01*
X718483Y478692D01*
G01X715717Y476775D02*
X715467Y476567D01*
X715175Y476442D01*
X714800Y476400D01*
X714425Y476483D01*
X714133Y476650D01*
X713925Y476942D01*
X713883Y477275D01*
X713967Y477608D01*
X714175Y477817D01*
X714467Y477983D01*
X714758Y478025D01*
X715050Y477983D01*
X715425Y477817D01*
X715300Y478900D01*
X714175D01*
G01X721712Y474071D02*
X723512Y471971D01*
X725712Y474071D01*
G01X729312Y474171D02*
Y454971D01*
X718112D01*
Y474171D01*
X729312D01*
Y473771D01*
G01X741967Y443667D02*
Y446167D01*
X741133D01*
X740800Y446042D01*
X740550Y445875D01*
X740342Y445625D01*
X740175Y445334D01*
X740133Y444917D01*
X740175Y444500D01*
X740342Y444209D01*
X740550Y443959D01*
X740800Y443792D01*
X741133Y443667D01*
X741967D01*
G01X738742Y445750D02*
X738492Y446000D01*
X738200Y446125D01*
X737867Y446167D01*
X737450Y446084D01*
X737158Y445875D01*
X737075Y445625D01*
X737117Y445375D01*
X737283Y445167D01*
X738117Y444750D01*
X738492Y444459D01*
X738742Y444042D01*
X738825Y443667D01*
X737075D01*
G01X736180Y442140D02*
Y426040D01*
G01X743180Y442140D02*
X736180D01*
G01X743180Y426040D02*
Y442140D01*
G01X736180Y426040D02*
X743180D01*
G01X785167Y49017D02*
X787667D01*
Y50058D01*
X787542Y50392D01*
X787375Y50600D01*
X787042Y50683D01*
X786709Y50600D01*
X786500Y50350D01*
X786375Y50058D01*
Y49017D01*
G01Y50058D02*
X785167Y50683D01*
G01X787250Y52158D02*
X787500Y52408D01*
X787625Y52700D01*
X787667Y53033D01*
X787584Y53450D01*
X787375Y53742D01*
X787125Y53825D01*
X786875Y53783D01*
X786667Y53617D01*
X786250Y52783D01*
X785959Y52408D01*
X785542Y52158D01*
X785167Y52075D01*
Y53825D01*
G01Y56550D02*
X787667D01*
X785875Y55008D01*
Y57092D01*
G01X785167Y59650D02*
X787667D01*
X785875Y58108D01*
Y60192D01*
G01X784880Y62687D02*
X787380D01*
Y63728D01*
X787255Y64062D01*
X787088Y64270D01*
X786755Y64353D01*
X786422Y64270D01*
X786213Y64020D01*
X786088Y63728D01*
Y62687D01*
G01Y63728D02*
X784880Y64353D01*
G01X786963Y65828D02*
X787213Y66078D01*
X787338Y66370D01*
X787380Y66703D01*
X787297Y67120D01*
X787088Y67412D01*
X786838Y67495D01*
X786588Y67453D01*
X786380Y67287D01*
X785963Y66453D01*
X785672Y66078D01*
X785255Y65828D01*
X784880Y65745D01*
Y67495D01*
G01X785380Y68803D02*
X785088Y69053D01*
X784922Y69387D01*
X784880Y69762D01*
X784922Y70095D01*
X785130Y70428D01*
X785380Y70637D01*
X785630Y70678D01*
X785922Y70595D01*
X786130Y70303D01*
X786213Y70012D01*
Y69637D01*
G01Y70012D02*
X786338Y70262D01*
X786547Y70470D01*
X786797Y70553D01*
X787047Y70470D01*
X787255Y70262D01*
X787380Y69887D01*
X787338Y69512D01*
X787172Y69137D01*
G01X785172Y72112D02*
X784963Y72403D01*
X784880Y72737D01*
X784963Y73070D01*
X785213Y73362D01*
X785588Y73570D01*
X785963Y73653D01*
X786422D01*
X786797Y73570D01*
X787130Y73362D01*
X787297Y73112D01*
X787380Y72820D01*
X787297Y72487D01*
X787130Y72237D01*
X786880Y72070D01*
X786547Y71987D01*
X786255Y72070D01*
X785963Y72278D01*
X785797Y72528D01*
X785755Y72820D01*
X785838Y73153D01*
X786047Y73403D01*
X786422Y73653D01*
G01X787350Y89800D02*
X783350D01*
Y97200D01*
G01X781090Y62507D02*
X783590D01*
Y63548D01*
X783465Y63882D01*
X783298Y64090D01*
X782965Y64173D01*
X782632Y64090D01*
X782423Y63840D01*
X782298Y63548D01*
Y62507D01*
G01Y63548D02*
X781090Y64173D01*
G01X783173Y65648D02*
X783423Y65898D01*
X783548Y66190D01*
X783590Y66523D01*
X783507Y66940D01*
X783298Y67232D01*
X783048Y67315D01*
X782798Y67273D01*
X782590Y67107D01*
X782173Y66273D01*
X781882Y65898D01*
X781465Y65648D01*
X781090Y65565D01*
Y67315D01*
G01X781590Y68623D02*
X781298Y68873D01*
X781132Y69207D01*
X781090Y69582D01*
X781132Y69915D01*
X781340Y70248D01*
X781590Y70457D01*
X781840Y70498D01*
X782132Y70415D01*
X782340Y70123D01*
X782423Y69832D01*
Y69457D01*
G01Y69832D02*
X782548Y70082D01*
X782757Y70290D01*
X783007Y70373D01*
X783257Y70290D01*
X783465Y70082D01*
X783590Y69707D01*
X783548Y69332D01*
X783382Y68957D01*
G01X781090Y72640D02*
X781132Y72932D01*
X781257Y73265D01*
X781465Y73473D01*
X781757Y73557D01*
X782048Y73473D01*
X782298Y73223D01*
X782423Y72848D01*
Y72432D01*
X782507Y72182D01*
X782715Y71973D01*
X783007Y71890D01*
X783298Y72015D01*
X783507Y72307D01*
X783590Y72640D01*
X783507Y72973D01*
X783298Y73265D01*
X783007Y73390D01*
X782715Y73307D01*
X782507Y73098D01*
X782423Y72848D01*
Y72432D01*
X782298Y72057D01*
X782048Y71807D01*
X781757Y71723D01*
X781465Y71807D01*
X781257Y72015D01*
X781132Y72348D01*
X781090Y72640D01*
G01X783000Y89800D02*
X779000D01*
Y97200D01*
G01X783350Y89700D02*
X787350D01*
Y82300D01*
G01X796050Y68167D02*
X796383Y68209D01*
X796675Y68375D01*
X796925Y68625D01*
X797092Y68917D01*
X797175Y69250D01*
Y69584D01*
X797092Y69917D01*
X796925Y70209D01*
X796675Y70459D01*
X796383Y70625D01*
X796050Y70667D01*
X795717Y70625D01*
X795425Y70459D01*
X795175Y70209D01*
X795008Y69917D01*
X794925Y69584D01*
Y69250D01*
X795008Y68917D01*
X795175Y68625D01*
X795425Y68375D01*
X795717Y68209D01*
X796050Y68167D01*
G01X795717Y68834D02*
X795217Y68167D01*
G01X793742Y69209D02*
X793450Y69500D01*
X793200Y69667D01*
X792867Y69750D01*
X792575Y69667D01*
X792367Y69500D01*
X792200Y69250D01*
X792158Y68959D01*
X792200Y68709D01*
X792367Y68459D01*
X792617Y68250D01*
X792908Y68167D01*
X793242Y68250D01*
X793533Y68500D01*
X793700Y68875D01*
X793742Y69292D01*
X793658Y69834D01*
X793533Y70125D01*
X793325Y70417D01*
X793033Y70625D01*
X792742Y70667D01*
X792450Y70584D01*
X792242Y70375D01*
G01X788500Y85000D02*
X802500D01*
G01X788500Y72000D02*
Y85000D01*
G01X802500Y72000D02*
X788500D01*
G01X802500Y85000D02*
Y72000D01*
G01X777050Y71000D02*
X777383Y71042D01*
X777675Y71208D01*
X777925Y71458D01*
X778092Y71750D01*
X778175Y72083D01*
Y72417D01*
X778092Y72750D01*
X777925Y73042D01*
X777675Y73292D01*
X777383Y73458D01*
X777050Y73500D01*
X776717Y73458D01*
X776425Y73292D01*
X776175Y73042D01*
X776008Y72750D01*
X775925Y72417D01*
Y72083D01*
X776008Y71750D01*
X776175Y71458D01*
X776425Y71208D01*
X776717Y71042D01*
X777050Y71000D01*
G01X776717Y71667D02*
X776217Y71000D01*
G01X774867Y71375D02*
X774617Y71167D01*
X774325Y71042D01*
X773950Y71000D01*
X773575Y71083D01*
X773283Y71250D01*
X773075Y71542D01*
X773033Y71875D01*
X773117Y72208D01*
X773325Y72417D01*
X773617Y72583D01*
X773908Y72625D01*
X774200Y72583D01*
X774575Y72417D01*
X774450Y73500D01*
X773325D01*
G01X782500Y89000D02*
Y75000D01*
G01X769500Y89000D02*
X782500D01*
G01X769500Y75000D02*
Y89000D01*
G01X782500Y75000D02*
X769500D01*
G01X811550Y96667D02*
X811883Y96709D01*
X812175Y96875D01*
X812425Y97125D01*
X812592Y97417D01*
X812675Y97750D01*
Y98084D01*
X812592Y98417D01*
X812425Y98709D01*
X812175Y98959D01*
X811883Y99125D01*
X811550Y99167D01*
X811217Y99125D01*
X810925Y98959D01*
X810675Y98709D01*
X810508Y98417D01*
X810425Y98084D01*
Y97750D01*
X810508Y97417D01*
X810675Y97125D01*
X810925Y96875D01*
X811217Y96709D01*
X811550Y96667D01*
G01X811217Y97334D02*
X810717Y96667D01*
G01X807950D02*
Y99167D01*
X809492Y97375D01*
X807408D01*
G01X806000Y104000D02*
Y90000D01*
G01X793000Y104000D02*
X806000D01*
G01X793000Y90000D02*
Y104000D01*
G01X806000Y90000D02*
X793000D01*
G01X768400Y102230D02*
Y89230D01*
G01X817433Y112500D02*
Y110000D01*
X815767D01*
G01X814292Y112083D02*
X814042Y112333D01*
X813750Y112458D01*
X813417Y112500D01*
X813000Y112417D01*
X812708Y112208D01*
X812625Y111958D01*
X812667Y111708D01*
X812833Y111500D01*
X813667Y111083D01*
X814042Y110792D01*
X814292Y110375D01*
X814375Y110000D01*
X812625D01*
G01X811317Y110375D02*
X811067Y110167D01*
X810775Y110042D01*
X810400Y110000D01*
X810025Y110083D01*
X809733Y110250D01*
X809525Y110542D01*
X809483Y110875D01*
X809567Y111208D01*
X809775Y111417D01*
X810067Y111583D01*
X810358Y111625D01*
X810650Y111583D01*
X811025Y111417D01*
X810900Y112500D01*
X809775D01*
G01X787300Y116000D02*
Y109000D01*
X800700D01*
Y116000D01*
X787300D01*
G01X817983Y105500D02*
Y108000D01*
X816942D01*
X816608Y107875D01*
X816400Y107708D01*
X816317Y107375D01*
X816400Y107042D01*
X816650Y106833D01*
X816942Y106708D01*
X817983D01*
G01X816942D02*
X816317Y105500D01*
G01X814842Y107583D02*
X814592Y107833D01*
X814300Y107958D01*
X813967Y108000D01*
X813550Y107917D01*
X813258Y107708D01*
X813175Y107458D01*
X813217Y107208D01*
X813383Y107000D01*
X814217Y106583D01*
X814592Y106292D01*
X814842Y105875D01*
X814925Y105500D01*
X813175D01*
G01X810950D02*
X810658Y105542D01*
X810325Y105667D01*
X810117Y105875D01*
X810033Y106167D01*
X810117Y106458D01*
X810367Y106708D01*
X810742Y106833D01*
X811158D01*
X811408Y106917D01*
X811617Y107125D01*
X811700Y107417D01*
X811575Y107708D01*
X811283Y107917D01*
X810950Y108000D01*
X810617Y107917D01*
X810325Y107708D01*
X810200Y107417D01*
X810283Y107125D01*
X810492Y106917D01*
X810742Y106833D01*
X811158D01*
X811533Y106708D01*
X811783Y106458D01*
X811867Y106167D01*
X811783Y105875D01*
X811575Y105667D01*
X811242Y105542D01*
X810950Y105500D01*
G01X808767Y106000D02*
X808517Y105708D01*
X808183Y105542D01*
X807808Y105500D01*
X807475Y105542D01*
X807142Y105750D01*
X806933Y106000D01*
X806892Y106250D01*
X806975Y106542D01*
X807267Y106750D01*
X807558Y106833D01*
X807933D01*
G01X807558D02*
X807308Y106958D01*
X807100Y107167D01*
X807017Y107417D01*
X807100Y107667D01*
X807308Y107875D01*
X807683Y108000D01*
X808058Y107958D01*
X808433Y107792D01*
G01X797200Y108500D02*
Y104500D01*
X789800D01*
G01X764792Y108267D02*
X764917Y108017D01*
X765000Y107725D01*
Y107392D01*
X764875Y107017D01*
X764667Y106725D01*
X764417Y106517D01*
X764000Y106350D01*
X763625Y106308D01*
X763250Y106392D01*
X763000Y106517D01*
X762750Y106767D01*
X762583Y107058D01*
X762500Y107350D01*
Y107642D01*
X762583Y107933D01*
X762708Y108183D01*
X762875Y108392D01*
G01X763000Y109533D02*
X762708Y109783D01*
X762542Y110117D01*
X762500Y110492D01*
X762542Y110825D01*
X762750Y111158D01*
X763000Y111367D01*
X763250Y111408D01*
X763542Y111325D01*
X763750Y111033D01*
X763833Y110742D01*
Y110367D01*
G01Y110742D02*
X763958Y110992D01*
X764167Y111200D01*
X764417Y111283D01*
X764667Y111200D01*
X764875Y110992D01*
X765000Y110617D01*
X764958Y110242D01*
X764792Y109867D01*
G01X762500Y113467D02*
X763042Y113550D01*
X763500Y113675D01*
X763917Y113842D01*
X764375Y114050D01*
X765000Y114383D01*
Y112717D01*
G01X762500Y116650D02*
X762542Y116942D01*
X762667Y117275D01*
X762875Y117483D01*
X763167Y117567D01*
X763458Y117483D01*
X763708Y117233D01*
X763833Y116858D01*
Y116442D01*
X763917Y116192D01*
X764125Y115983D01*
X764417Y115900D01*
X764708Y116025D01*
X764917Y116317D01*
X765000Y116650D01*
X764917Y116983D01*
X764708Y117275D01*
X764417Y117400D01*
X764125Y117317D01*
X763917Y117108D01*
X763833Y116858D01*
Y116442D01*
X763708Y116067D01*
X763458Y115817D01*
X763167Y115733D01*
X762875Y115817D01*
X762667Y116025D01*
X762542Y116358D01*
X762500Y116650D01*
G01X799483Y89167D02*
Y86667D01*
X797817D01*
G01X794717D02*
X796383D01*
Y89167D01*
X794717D01*
G01X795383Y87959D02*
X796383D01*
G01X793367Y86667D02*
Y89167D01*
X792533D01*
X792200Y89042D01*
X791950Y88875D01*
X791742Y88625D01*
X791575Y88334D01*
X791533Y87917D01*
X791575Y87500D01*
X791742Y87209D01*
X791950Y86959D01*
X792200Y86792D01*
X792533Y86667D01*
X793367D01*
G01X790142Y88750D02*
X789892Y89000D01*
X789600Y89125D01*
X789267Y89167D01*
X788850Y89084D01*
X788558Y88875D01*
X788475Y88625D01*
X788517Y88375D01*
X788683Y88167D01*
X789517Y87750D01*
X789892Y87459D01*
X790142Y87042D01*
X790225Y86667D01*
X788475D01*
G01X787400Y100900D02*
Y90100D01*
X792600D01*
Y100900D01*
X787400D01*
G01X778483Y105800D02*
Y103300D01*
X776817D01*
G01X773717D02*
X775383D01*
Y105800D01*
X773717D01*
G01X774383Y104592D02*
X775383D01*
G01X772367Y103300D02*
Y105800D01*
X771533D01*
X771200Y105675D01*
X770950Y105508D01*
X770742Y105258D01*
X770575Y104967D01*
X770533Y104550D01*
X770575Y104133D01*
X770742Y103842D01*
X770950Y103592D01*
X771200Y103425D01*
X771533Y103300D01*
X772367D01*
G01X768350D02*
Y105800D01*
X768850Y105300D01*
G01Y103300D02*
X767850D01*
G01X773900Y100900D02*
Y90100D01*
X779100D01*
Y100900D01*
X773900D01*
G01X814000Y136017D02*
X816500D01*
Y137058D01*
X816375Y137392D01*
X816208Y137600D01*
X815875Y137683D01*
X815542Y137600D01*
X815333Y137350D01*
X815208Y137058D01*
Y136017D01*
G01Y137058D02*
X814000Y137683D01*
G01X816083Y139158D02*
X816333Y139408D01*
X816458Y139700D01*
X816500Y140033D01*
X816417Y140450D01*
X816208Y140742D01*
X815958Y140825D01*
X815708Y140783D01*
X815500Y140617D01*
X815083Y139783D01*
X814792Y139408D01*
X814375Y139158D01*
X814000Y139075D01*
Y140825D01*
G01X816500Y143050D02*
X816417Y142717D01*
X816208Y142467D01*
X815958Y142300D01*
X815625Y142175D01*
X815250Y142133D01*
X814875Y142175D01*
X814542Y142300D01*
X814292Y142467D01*
X814083Y142717D01*
X814000Y143050D01*
X814083Y143383D01*
X814292Y143633D01*
X814542Y143800D01*
X814875Y143925D01*
X815250Y143967D01*
X815625Y143925D01*
X815958Y143800D01*
X816208Y143633D01*
X816417Y143383D01*
X816500Y143050D01*
G01X814292Y145442D02*
X814083Y145733D01*
X814000Y146067D01*
X814083Y146400D01*
X814333Y146692D01*
X814708Y146900D01*
X815083Y146983D01*
X815542D01*
X815917Y146900D01*
X816250Y146692D01*
X816417Y146442D01*
X816500Y146150D01*
X816417Y145817D01*
X816250Y145567D01*
X816000Y145400D01*
X815667Y145317D01*
X815375Y145400D01*
X815083Y145608D01*
X814917Y145858D01*
X814875Y146150D01*
X814958Y146483D01*
X815167Y146733D01*
X815542Y146983D01*
G01X804696Y135400D02*
X800696D01*
Y142800D01*
G01X774983Y147500D02*
Y150000D01*
X773942D01*
X773608Y149875D01*
X773400Y149708D01*
X773317Y149375D01*
X773400Y149042D01*
X773650Y148833D01*
X773942Y148708D01*
X774983D01*
G01X773942D02*
X773317Y147500D01*
G01X771050D02*
Y150000D01*
X771550Y149500D01*
G01Y147500D02*
X770550D01*
G01X768658Y147792D02*
X768367Y147583D01*
X768033Y147500D01*
X767700Y147583D01*
X767408Y147833D01*
X767200Y148208D01*
X767117Y148583D01*
Y149042D01*
X767200Y149417D01*
X767408Y149750D01*
X767658Y149917D01*
X767950Y150000D01*
X768283Y149917D01*
X768533Y149750D01*
X768700Y149500D01*
X768783Y149167D01*
X768700Y148875D01*
X768492Y148583D01*
X768242Y148417D01*
X767950Y148375D01*
X767617Y148458D01*
X767367Y148667D01*
X767117Y149042D01*
G01X764850Y150000D02*
X765183Y149917D01*
X765433Y149708D01*
X765600Y149458D01*
X765725Y149125D01*
X765767Y148750D01*
X765725Y148375D01*
X765600Y148042D01*
X765433Y147792D01*
X765183Y147583D01*
X764850Y147500D01*
X764517Y147583D01*
X764267Y147792D01*
X764100Y148042D01*
X763975Y148375D01*
X763933Y148750D01*
X763975Y149125D01*
X764100Y149458D01*
X764267Y149708D01*
X764517Y149917D01*
X764850Y150000D01*
G01X773983Y168500D02*
Y171000D01*
X772942D01*
X772608Y170875D01*
X772400Y170708D01*
X772317Y170375D01*
X772400Y170042D01*
X772650Y169833D01*
X772942Y169708D01*
X773983D01*
G01X772942D02*
X772317Y168500D01*
G01X770050D02*
Y171000D01*
X770550Y170500D01*
G01Y168500D02*
X769550D01*
G01X766950D02*
X766658Y168542D01*
X766325Y168667D01*
X766117Y168875D01*
X766033Y169167D01*
X766117Y169458D01*
X766367Y169708D01*
X766742Y169833D01*
X767158D01*
X767408Y169917D01*
X767617Y170125D01*
X767700Y170417D01*
X767575Y170708D01*
X767283Y170917D01*
X766950Y171000D01*
X766617Y170917D01*
X766325Y170708D01*
X766200Y170417D01*
X766283Y170125D01*
X766492Y169917D01*
X766742Y169833D01*
X767158D01*
X767533Y169708D01*
X767783Y169458D01*
X767867Y169167D01*
X767783Y168875D01*
X767575Y168667D01*
X767242Y168542D01*
X766950Y168500D01*
G01X763850D02*
X763558Y168542D01*
X763225Y168667D01*
X763017Y168875D01*
X762933Y169167D01*
X763017Y169458D01*
X763267Y169708D01*
X763642Y169833D01*
X764058D01*
X764308Y169917D01*
X764517Y170125D01*
X764600Y170417D01*
X764475Y170708D01*
X764183Y170917D01*
X763850Y171000D01*
X763517Y170917D01*
X763225Y170708D01*
X763100Y170417D01*
X763183Y170125D01*
X763392Y169917D01*
X763642Y169833D01*
X764058D01*
X764433Y169708D01*
X764683Y169458D01*
X764767Y169167D01*
X764683Y168875D01*
X764475Y168667D01*
X764142Y168542D01*
X763850Y168500D01*
G01X774983Y151500D02*
Y154000D01*
X773942D01*
X773608Y153875D01*
X773400Y153708D01*
X773317Y153375D01*
X773400Y153042D01*
X773650Y152833D01*
X773942Y152708D01*
X774983D01*
G01X773942D02*
X773317Y151500D01*
G01X771050D02*
Y154000D01*
X771550Y153500D01*
G01Y151500D02*
X770550D01*
G01X767950D02*
X767658Y151542D01*
X767325Y151667D01*
X767117Y151875D01*
X767033Y152167D01*
X767117Y152458D01*
X767367Y152708D01*
X767742Y152833D01*
X768158D01*
X768408Y152917D01*
X768617Y153125D01*
X768700Y153417D01*
X768575Y153708D01*
X768283Y153917D01*
X767950Y154000D01*
X767617Y153917D01*
X767325Y153708D01*
X767200Y153417D01*
X767283Y153125D01*
X767492Y152917D01*
X767742Y152833D01*
X768158D01*
X768533Y152708D01*
X768783Y152458D01*
X768867Y152167D01*
X768783Y151875D01*
X768575Y151667D01*
X768242Y151542D01*
X767950Y151500D01*
G01X764933D02*
X764850Y152042D01*
X764725Y152500D01*
X764558Y152917D01*
X764350Y153375D01*
X764017Y154000D01*
X765683D01*
G01X771983Y156000D02*
Y158500D01*
X770942D01*
X770608Y158375D01*
X770400Y158208D01*
X770317Y157875D01*
X770400Y157542D01*
X770650Y157333D01*
X770942Y157208D01*
X771983D01*
G01X770942D02*
X770317Y156000D01*
G01X768050D02*
Y158500D01*
X768550Y158000D01*
G01Y156000D02*
X767550D01*
G01X764950D02*
X764658Y156042D01*
X764325Y156167D01*
X764117Y156375D01*
X764033Y156667D01*
X764117Y156958D01*
X764367Y157208D01*
X764742Y157333D01*
X765158D01*
X765408Y157417D01*
X765617Y157625D01*
X765700Y157917D01*
X765575Y158208D01*
X765283Y158417D01*
X764950Y158500D01*
X764617Y158417D01*
X764325Y158208D01*
X764200Y157917D01*
X764283Y157625D01*
X764492Y157417D01*
X764742Y157333D01*
X765158D01*
X765533Y157208D01*
X765783Y156958D01*
X765867Y156667D01*
X765783Y156375D01*
X765575Y156167D01*
X765242Y156042D01*
X764950Y156000D01*
G01X762767Y156375D02*
X762517Y156167D01*
X762225Y156042D01*
X761850Y156000D01*
X761475Y156083D01*
X761183Y156250D01*
X760975Y156542D01*
X760933Y156875D01*
X761017Y157208D01*
X761225Y157417D01*
X761517Y157583D01*
X761808Y157625D01*
X762100Y157583D01*
X762475Y157417D01*
X762350Y158500D01*
X761225D01*
G01X771983Y160500D02*
Y163000D01*
X770942D01*
X770608Y162875D01*
X770400Y162708D01*
X770317Y162375D01*
X770400Y162042D01*
X770650Y161833D01*
X770942Y161708D01*
X771983D01*
G01X770942D02*
X770317Y160500D01*
G01X768050D02*
Y163000D01*
X768550Y162500D01*
G01Y160500D02*
X767550D01*
G01X764950D02*
X764658Y160542D01*
X764325Y160667D01*
X764117Y160875D01*
X764033Y161167D01*
X764117Y161458D01*
X764367Y161708D01*
X764742Y161833D01*
X765158D01*
X765408Y161917D01*
X765617Y162125D01*
X765700Y162417D01*
X765575Y162708D01*
X765283Y162917D01*
X764950Y163000D01*
X764617Y162917D01*
X764325Y162708D01*
X764200Y162417D01*
X764283Y162125D01*
X764492Y161917D01*
X764742Y161833D01*
X765158D01*
X765533Y161708D01*
X765783Y161458D01*
X765867Y161167D01*
X765783Y160875D01*
X765575Y160667D01*
X765242Y160542D01*
X764950Y160500D01*
G01X762642Y162583D02*
X762392Y162833D01*
X762100Y162958D01*
X761767Y163000D01*
X761350Y162917D01*
X761058Y162708D01*
X760975Y162458D01*
X761017Y162208D01*
X761183Y162000D01*
X762017Y161583D01*
X762392Y161292D01*
X762642Y160875D01*
X762725Y160500D01*
X760975D01*
G01X806000Y136117D02*
X808500D01*
Y137158D01*
X808375Y137492D01*
X808208Y137700D01*
X807875Y137783D01*
X807542Y137700D01*
X807333Y137450D01*
X807208Y137158D01*
Y136117D01*
G01Y137158D02*
X806000Y137783D01*
G01X808083Y139258D02*
X808333Y139508D01*
X808458Y139800D01*
X808500Y140133D01*
X808417Y140550D01*
X808208Y140842D01*
X807958Y140925D01*
X807708Y140883D01*
X807500Y140717D01*
X807083Y139883D01*
X806792Y139508D01*
X806375Y139258D01*
X806000Y139175D01*
Y140925D01*
G01X808500Y143150D02*
X808417Y142817D01*
X808208Y142567D01*
X807958Y142400D01*
X807625Y142275D01*
X807250Y142233D01*
X806875Y142275D01*
X806542Y142400D01*
X806292Y142567D01*
X806083Y142817D01*
X806000Y143150D01*
X806083Y143483D01*
X806292Y143733D01*
X806542Y143900D01*
X806875Y144025D01*
X807250Y144067D01*
X807625Y144025D01*
X807958Y143900D01*
X808208Y143733D01*
X808417Y143483D01*
X808500Y143150D01*
G01X806000Y146250D02*
X808500D01*
X808000Y145750D01*
G01X806000D02*
Y146750D01*
G01X792500Y142800D02*
X796500D01*
Y135400D01*
G01X769000Y135017D02*
X771500D01*
Y136058D01*
X771375Y136392D01*
X771208Y136600D01*
X770875Y136683D01*
X770542Y136600D01*
X770333Y136350D01*
X770208Y136058D01*
Y135017D01*
G01Y136058D02*
X769000Y136683D01*
G01Y138950D02*
X771500D01*
X771000Y138450D01*
G01X769000D02*
Y139450D01*
G01X769292Y141342D02*
X769083Y141633D01*
X769000Y141967D01*
X769083Y142300D01*
X769333Y142592D01*
X769708Y142800D01*
X770083Y142883D01*
X770542D01*
X770917Y142800D01*
X771250Y142592D01*
X771417Y142342D01*
X771500Y142050D01*
X771417Y141717D01*
X771250Y141467D01*
X771000Y141300D01*
X770667Y141217D01*
X770375Y141300D01*
X770083Y141508D01*
X769917Y141758D01*
X769875Y142050D01*
X769958Y142383D01*
X770167Y142633D01*
X770542Y142883D01*
G01X769292Y144442D02*
X769083Y144733D01*
X769000Y145067D01*
X769083Y145400D01*
X769333Y145692D01*
X769708Y145900D01*
X770083Y145983D01*
X770542D01*
X770917Y145900D01*
X771250Y145692D01*
X771417Y145442D01*
X771500Y145150D01*
X771417Y144817D01*
X771250Y144567D01*
X771000Y144400D01*
X770667Y144317D01*
X770375Y144400D01*
X770083Y144608D01*
X769917Y144858D01*
X769875Y145150D01*
X769958Y145483D01*
X770167Y145733D01*
X770542Y145983D01*
G01X780500Y142800D02*
X784500D01*
Y135400D01*
G01X773000Y135017D02*
X775500D01*
Y136058D01*
X775375Y136392D01*
X775208Y136600D01*
X774875Y136683D01*
X774542Y136600D01*
X774333Y136350D01*
X774208Y136058D01*
Y135017D01*
G01Y136058D02*
X773000Y136683D01*
G01Y138950D02*
X775500D01*
X775000Y138450D01*
G01X773000D02*
Y139450D01*
G01Y142050D02*
X773042Y142342D01*
X773167Y142675D01*
X773375Y142883D01*
X773667Y142967D01*
X773958Y142883D01*
X774208Y142633D01*
X774333Y142258D01*
Y141842D01*
X774417Y141592D01*
X774625Y141383D01*
X774917Y141300D01*
X775208Y141425D01*
X775417Y141717D01*
X775500Y142050D01*
X775417Y142383D01*
X775208Y142675D01*
X774917Y142800D01*
X774625Y142717D01*
X774417Y142508D01*
X774333Y142258D01*
Y141842D01*
X774208Y141467D01*
X773958Y141217D01*
X773667Y141133D01*
X773375Y141217D01*
X773167Y141425D01*
X773042Y141758D01*
X773000Y142050D01*
G01X774042Y144358D02*
X774333Y144650D01*
X774500Y144900D01*
X774583Y145233D01*
X774500Y145525D01*
X774333Y145733D01*
X774083Y145900D01*
X773792Y145942D01*
X773542Y145900D01*
X773292Y145733D01*
X773083Y145483D01*
X773000Y145192D01*
X773083Y144858D01*
X773333Y144567D01*
X773708Y144400D01*
X774125Y144358D01*
X774667Y144442D01*
X774958Y144567D01*
X775250Y144775D01*
X775458Y145067D01*
X775500Y145358D01*
X775417Y145650D01*
X775208Y145858D01*
G01X788500Y135400D02*
X784500D01*
Y142800D01*
G01X810000Y136117D02*
X812500D01*
Y137158D01*
X812375Y137492D01*
X812208Y137700D01*
X811875Y137783D01*
X811542Y137700D01*
X811333Y137450D01*
X811208Y137158D01*
Y136117D01*
G01Y137158D02*
X810000Y137783D01*
G01Y140050D02*
X812500D01*
X812000Y139550D01*
G01X810000D02*
Y140550D01*
G01X810292Y142442D02*
X810083Y142733D01*
X810000Y143067D01*
X810083Y143400D01*
X810333Y143692D01*
X810708Y143900D01*
X811083Y143983D01*
X811542D01*
X811917Y143900D01*
X812250Y143692D01*
X812417Y143442D01*
X812500Y143150D01*
X812417Y142817D01*
X812250Y142567D01*
X812000Y142400D01*
X811667Y142317D01*
X811375Y142400D01*
X811083Y142608D01*
X810917Y142858D01*
X810875Y143150D01*
X810958Y143483D01*
X811167Y143733D01*
X811542Y143983D01*
G01X810000Y146250D02*
X810042Y146542D01*
X810167Y146875D01*
X810375Y147083D01*
X810667Y147167D01*
X810958Y147083D01*
X811208Y146833D01*
X811333Y146458D01*
Y146042D01*
X811417Y145792D01*
X811625Y145583D01*
X811917Y145500D01*
X812208Y145625D01*
X812417Y145917D01*
X812500Y146250D01*
X812417Y146583D01*
X812208Y146875D01*
X811917Y147000D01*
X811625Y146917D01*
X811417Y146708D01*
X811333Y146458D01*
Y146042D01*
X811208Y145667D01*
X810958Y145417D01*
X810667Y145333D01*
X810375Y145417D01*
X810167Y145625D01*
X810042Y145958D01*
X810000Y146250D01*
G01X796500Y142800D02*
X800500D01*
Y135400D01*
G01X777000Y135017D02*
X779500D01*
Y136058D01*
X779375Y136392D01*
X779208Y136600D01*
X778875Y136683D01*
X778542Y136600D01*
X778333Y136350D01*
X778208Y136058D01*
Y135017D01*
G01Y136058D02*
X777000Y136683D01*
G01X779083Y138158D02*
X779333Y138408D01*
X779458Y138700D01*
X779500Y139033D01*
X779417Y139450D01*
X779208Y139742D01*
X778958Y139825D01*
X778708Y139783D01*
X778500Y139617D01*
X778083Y138783D01*
X777792Y138408D01*
X777375Y138158D01*
X777000Y138075D01*
Y139825D01*
G01X779500Y142050D02*
X779417Y141717D01*
X779208Y141467D01*
X778958Y141300D01*
X778625Y141175D01*
X778250Y141133D01*
X777875Y141175D01*
X777542Y141300D01*
X777292Y141467D01*
X777083Y141717D01*
X777000Y142050D01*
X777083Y142383D01*
X777292Y142633D01*
X777542Y142800D01*
X777875Y142925D01*
X778250Y142967D01*
X778625Y142925D01*
X778958Y142800D01*
X779208Y142633D01*
X779417Y142383D01*
X779500Y142050D01*
G01X777000Y145150D02*
X777042Y145442D01*
X777167Y145775D01*
X777375Y145983D01*
X777667Y146067D01*
X777958Y145983D01*
X778208Y145733D01*
X778333Y145358D01*
Y144942D01*
X778417Y144692D01*
X778625Y144483D01*
X778917Y144400D01*
X779208Y144525D01*
X779417Y144817D01*
X779500Y145150D01*
X779417Y145483D01*
X779208Y145775D01*
X778917Y145900D01*
X778625Y145817D01*
X778417Y145608D01*
X778333Y145358D01*
Y144942D01*
X778208Y144567D01*
X777958Y144317D01*
X777667Y144233D01*
X777375Y144317D01*
X777167Y144525D01*
X777042Y144858D01*
X777000Y145150D01*
G01X792500Y135400D02*
X788500D01*
Y142800D01*
G01X808159Y116767D02*
X808284Y116517D01*
X808367Y116225D01*
Y115892D01*
X808242Y115517D01*
X808034Y115225D01*
X807784Y115017D01*
X807367Y114850D01*
X806992Y114808D01*
X806617Y114892D01*
X806367Y115017D01*
X806117Y115267D01*
X805950Y115558D01*
X805867Y115850D01*
Y116142D01*
X805950Y116433D01*
X806075Y116683D01*
X806242Y116892D01*
G01X806367Y118033D02*
X806075Y118283D01*
X805909Y118617D01*
X805867Y118992D01*
X805909Y119325D01*
X806117Y119658D01*
X806367Y119867D01*
X806617Y119908D01*
X806909Y119825D01*
X807117Y119533D01*
X807200Y119242D01*
Y118867D01*
G01Y119242D02*
X807325Y119492D01*
X807534Y119700D01*
X807784Y119783D01*
X808034Y119700D01*
X808242Y119492D01*
X808367Y119117D01*
X808325Y118742D01*
X808159Y118367D01*
G01X806909Y121258D02*
X807200Y121550D01*
X807367Y121800D01*
X807450Y122133D01*
X807367Y122425D01*
X807200Y122633D01*
X806950Y122800D01*
X806659Y122842D01*
X806409Y122800D01*
X806159Y122633D01*
X805950Y122383D01*
X805867Y122092D01*
X805950Y121758D01*
X806200Y121467D01*
X806575Y121300D01*
X806992Y121258D01*
X807534Y121342D01*
X807825Y121467D01*
X808117Y121675D01*
X808325Y121967D01*
X808367Y122258D01*
X808284Y122550D01*
X808075Y122758D01*
G01X806909Y124358D02*
X807200Y124650D01*
X807367Y124900D01*
X807450Y125233D01*
X807367Y125525D01*
X807200Y125733D01*
X806950Y125900D01*
X806659Y125942D01*
X806409Y125900D01*
X806159Y125733D01*
X805950Y125483D01*
X805867Y125192D01*
X805950Y124858D01*
X806200Y124567D01*
X806575Y124400D01*
X806992Y124358D01*
X807534Y124442D01*
X807825Y124567D01*
X808117Y124775D01*
X808325Y125067D01*
X808367Y125358D01*
X808284Y125650D01*
X808075Y125858D01*
G01X817433Y130000D02*
Y127500D01*
X815767D01*
G01X814292Y129583D02*
X814042Y129833D01*
X813750Y129958D01*
X813417Y130000D01*
X813000Y129917D01*
X812708Y129708D01*
X812625Y129458D01*
X812667Y129208D01*
X812833Y129000D01*
X813667Y128583D01*
X814042Y128292D01*
X814292Y127875D01*
X814375Y127500D01*
X812625D01*
G01X811192Y129583D02*
X810942Y129833D01*
X810650Y129958D01*
X810317Y130000D01*
X809900Y129917D01*
X809608Y129708D01*
X809525Y129458D01*
X809567Y129208D01*
X809733Y129000D01*
X810567Y128583D01*
X810942Y128292D01*
X811192Y127875D01*
X811275Y127500D01*
X809525D01*
G01X791807Y128093D02*
Y121093D01*
X805207D01*
Y128093D01*
X791807D01*
G01X817483Y131500D02*
Y134000D01*
X816442D01*
X816108Y133875D01*
X815900Y133708D01*
X815817Y133375D01*
X815900Y133042D01*
X816150Y132833D01*
X816442Y132708D01*
X817483D01*
G01X816442D02*
X815817Y131500D01*
G01X814342Y133583D02*
X814092Y133833D01*
X813800Y133958D01*
X813467Y134000D01*
X813050Y133917D01*
X812758Y133708D01*
X812675Y133458D01*
X812717Y133208D01*
X812883Y133000D01*
X813717Y132583D01*
X814092Y132292D01*
X814342Y131875D01*
X814425Y131500D01*
X812675D01*
G01X810450D02*
X810158Y131542D01*
X809825Y131667D01*
X809617Y131875D01*
X809533Y132167D01*
X809617Y132458D01*
X809867Y132708D01*
X810242Y132833D01*
X810658D01*
X810908Y132917D01*
X811117Y133125D01*
X811200Y133417D01*
X811075Y133708D01*
X810783Y133917D01*
X810450Y134000D01*
X810117Y133917D01*
X809825Y133708D01*
X809700Y133417D01*
X809783Y133125D01*
X809992Y132917D01*
X810242Y132833D01*
X810658D01*
X811033Y132708D01*
X811283Y132458D01*
X811367Y132167D01*
X811283Y131875D01*
X811075Y131667D01*
X810742Y131542D01*
X810450Y131500D01*
G01X807350Y134000D02*
X807683Y133917D01*
X807933Y133708D01*
X808100Y133458D01*
X808225Y133125D01*
X808267Y132750D01*
X808225Y132375D01*
X808100Y132042D01*
X807933Y131792D01*
X807683Y131583D01*
X807350Y131500D01*
X807017Y131583D01*
X806767Y131792D01*
X806600Y132042D01*
X806475Y132375D01*
X806433Y132750D01*
X806475Y133125D01*
X806600Y133458D01*
X806767Y133708D01*
X807017Y133917D01*
X807350Y134000D01*
G01X802207Y132593D02*
Y128593D01*
X794807D01*
G01X807167Y157483D02*
X805375D01*
X805000Y157650D01*
X804750Y157983D01*
X804667Y158400D01*
X804750Y158817D01*
X805000Y159150D01*
X805375Y159317D01*
X807167D01*
G01X804667Y161500D02*
X807167D01*
X806667Y161000D01*
G01X804667D02*
Y162000D01*
G01X805042Y163683D02*
X804834Y163933D01*
X804709Y164225D01*
X804667Y164600D01*
X804750Y164975D01*
X804917Y165267D01*
X805209Y165475D01*
X805542Y165517D01*
X805875Y165433D01*
X806084Y165225D01*
X806250Y164933D01*
X806292Y164642D01*
X806250Y164350D01*
X806084Y163975D01*
X807167Y164100D01*
Y165225D01*
G01X803200Y164000D02*
X801100Y162200D01*
X803200Y160000D01*
G01X803300Y156400D02*
X784100D01*
Y167600D01*
X803300D01*
Y156400D01*
X802900D01*
G01X815392Y116767D02*
X815517Y116517D01*
X815600Y116225D01*
Y115892D01*
X815475Y115517D01*
X815267Y115225D01*
X815017Y115017D01*
X814600Y114850D01*
X814225Y114808D01*
X813850Y114892D01*
X813600Y115017D01*
X813350Y115267D01*
X813183Y115558D01*
X813100Y115850D01*
Y116142D01*
X813183Y116433D01*
X813308Y116683D01*
X813475Y116892D01*
G01X813600Y118033D02*
X813308Y118283D01*
X813142Y118617D01*
X813100Y118992D01*
X813142Y119325D01*
X813350Y119658D01*
X813600Y119867D01*
X813850Y119908D01*
X814142Y119825D01*
X814350Y119533D01*
X814433Y119242D01*
Y118867D01*
G01Y119242D02*
X814558Y119492D01*
X814767Y119700D01*
X815017Y119783D01*
X815267Y119700D01*
X815475Y119492D01*
X815600Y119117D01*
X815558Y118742D01*
X815392Y118367D01*
G01X814142Y121258D02*
X814433Y121550D01*
X814600Y121800D01*
X814683Y122133D01*
X814600Y122425D01*
X814433Y122633D01*
X814183Y122800D01*
X813892Y122842D01*
X813642Y122800D01*
X813392Y122633D01*
X813183Y122383D01*
X813100Y122092D01*
X813183Y121758D01*
X813433Y121467D01*
X813808Y121300D01*
X814225Y121258D01*
X814767Y121342D01*
X815058Y121467D01*
X815350Y121675D01*
X815558Y121967D01*
X815600Y122258D01*
X815517Y122550D01*
X815308Y122758D01*
G01X813100Y125650D02*
X815600D01*
X813808Y124108D01*
Y126192D01*
G01X819092Y116767D02*
X819217Y116517D01*
X819300Y116225D01*
Y115892D01*
X819175Y115517D01*
X818967Y115225D01*
X818717Y115017D01*
X818300Y114850D01*
X817925Y114808D01*
X817550Y114892D01*
X817300Y115017D01*
X817050Y115267D01*
X816883Y115558D01*
X816800Y115850D01*
Y116142D01*
X816883Y116433D01*
X817008Y116683D01*
X817175Y116892D01*
G01X817300Y118033D02*
X817008Y118283D01*
X816842Y118617D01*
X816800Y118992D01*
X816842Y119325D01*
X817050Y119658D01*
X817300Y119867D01*
X817550Y119908D01*
X817842Y119825D01*
X818050Y119533D01*
X818133Y119242D01*
Y118867D01*
G01Y119242D02*
X818258Y119492D01*
X818467Y119700D01*
X818717Y119783D01*
X818967Y119700D01*
X819175Y119492D01*
X819300Y119117D01*
X819258Y118742D01*
X819092Y118367D01*
G01X817842Y121258D02*
X818133Y121550D01*
X818300Y121800D01*
X818383Y122133D01*
X818300Y122425D01*
X818133Y122633D01*
X817883Y122800D01*
X817592Y122842D01*
X817342Y122800D01*
X817092Y122633D01*
X816883Y122383D01*
X816800Y122092D01*
X816883Y121758D01*
X817133Y121467D01*
X817508Y121300D01*
X817925Y121258D01*
X818467Y121342D01*
X818758Y121467D01*
X819050Y121675D01*
X819258Y121967D01*
X819300Y122258D01*
X819217Y122550D01*
X819008Y122758D01*
G01X817300Y124233D02*
X817008Y124483D01*
X816842Y124817D01*
X816800Y125192D01*
X816842Y125525D01*
X817050Y125858D01*
X817300Y126067D01*
X817550Y126108D01*
X817842Y126025D01*
X818050Y125733D01*
X818133Y125442D01*
Y125067D01*
G01Y125442D02*
X818258Y125692D01*
X818467Y125900D01*
X818717Y125983D01*
X818967Y125900D01*
X819175Y125692D01*
X819300Y125317D01*
X819258Y124942D01*
X819092Y124567D01*
G01X811692Y116767D02*
X811817Y116517D01*
X811900Y116225D01*
Y115892D01*
X811775Y115517D01*
X811567Y115225D01*
X811317Y115017D01*
X810900Y114850D01*
X810525Y114808D01*
X810150Y114892D01*
X809900Y115017D01*
X809650Y115267D01*
X809483Y115558D01*
X809400Y115850D01*
Y116142D01*
X809483Y116433D01*
X809608Y116683D01*
X809775Y116892D01*
G01X809900Y118033D02*
X809608Y118283D01*
X809442Y118617D01*
X809400Y118992D01*
X809442Y119325D01*
X809650Y119658D01*
X809900Y119867D01*
X810150Y119908D01*
X810442Y119825D01*
X810650Y119533D01*
X810733Y119242D01*
Y118867D01*
G01Y119242D02*
X810858Y119492D01*
X811067Y119700D01*
X811317Y119783D01*
X811567Y119700D01*
X811775Y119492D01*
X811900Y119117D01*
X811858Y118742D01*
X811692Y118367D01*
G01X810442Y121258D02*
X810733Y121550D01*
X810900Y121800D01*
X810983Y122133D01*
X810900Y122425D01*
X810733Y122633D01*
X810483Y122800D01*
X810192Y122842D01*
X809942Y122800D01*
X809692Y122633D01*
X809483Y122383D01*
X809400Y122092D01*
X809483Y121758D01*
X809733Y121467D01*
X810108Y121300D01*
X810525Y121258D01*
X811067Y121342D01*
X811358Y121467D01*
X811650Y121675D01*
X811858Y121967D01*
X811900Y122258D01*
X811817Y122550D01*
X811608Y122758D01*
G01X809775Y124233D02*
X809567Y124483D01*
X809442Y124775D01*
X809400Y125150D01*
X809483Y125525D01*
X809650Y125817D01*
X809942Y126025D01*
X810275Y126067D01*
X810608Y125983D01*
X810817Y125775D01*
X810983Y125483D01*
X811025Y125192D01*
X810983Y124900D01*
X810817Y124525D01*
X811900Y124650D01*
Y125775D01*
G01X777200Y177667D02*
Y175167D01*
G01X778158Y177667D02*
X776242D01*
G01X774933Y175167D02*
Y177667D01*
X773933D01*
X773600Y177542D01*
X773350Y177250D01*
X773267Y176917D01*
X773350Y176584D01*
X773558Y176334D01*
X773933Y176209D01*
X774933D01*
G01X771000Y175167D02*
Y177667D01*
X771500Y177167D01*
G01Y175167D02*
X770500D01*
G01X767900Y177667D02*
X768233Y177584D01*
X768483Y177375D01*
X768650Y177125D01*
X768775Y176792D01*
X768817Y176417D01*
X768775Y176042D01*
X768650Y175709D01*
X768483Y175459D01*
X768233Y175250D01*
X767900Y175167D01*
X767567Y175250D01*
X767317Y175459D01*
X767150Y175709D01*
X767025Y176042D01*
X766983Y176417D01*
X767025Y176792D01*
X767150Y177125D01*
X767317Y177375D01*
X767567Y177584D01*
X767900Y177667D01*
G01X765717Y175542D02*
X765467Y175334D01*
X765175Y175209D01*
X764800Y175167D01*
X764425Y175250D01*
X764133Y175417D01*
X763925Y175709D01*
X763883Y176042D01*
X763967Y176375D01*
X764175Y176584D01*
X764467Y176750D01*
X764758Y176792D01*
X765050Y176750D01*
X765425Y176584D01*
X765300Y177667D01*
X764175D01*
G01X780483Y187167D02*
Y189667D01*
X779442D01*
X779108Y189542D01*
X778900Y189375D01*
X778817Y189042D01*
X778900Y188709D01*
X779150Y188500D01*
X779442Y188375D01*
X780483D01*
G01X779442D02*
X778817Y187167D01*
G01X777342Y189250D02*
X777092Y189500D01*
X776800Y189625D01*
X776467Y189667D01*
X776050Y189584D01*
X775758Y189375D01*
X775675Y189125D01*
X775717Y188875D01*
X775883Y188667D01*
X776717Y188250D01*
X777092Y187959D01*
X777342Y187542D01*
X777425Y187167D01*
X775675D01*
G01X773450Y189667D02*
X773783Y189584D01*
X774033Y189375D01*
X774200Y189125D01*
X774325Y188792D01*
X774367Y188417D01*
X774325Y188042D01*
X774200Y187709D01*
X774033Y187459D01*
X773783Y187250D01*
X773450Y187167D01*
X773117Y187250D01*
X772867Y187459D01*
X772700Y187709D01*
X772575Y188042D01*
X772533Y188417D01*
X772575Y188792D01*
X772700Y189125D01*
X772867Y189375D01*
X773117Y189584D01*
X773450Y189667D01*
G01X771267Y187542D02*
X771017Y187334D01*
X770725Y187209D01*
X770350Y187167D01*
X769975Y187250D01*
X769683Y187417D01*
X769475Y187709D01*
X769433Y188042D01*
X769517Y188375D01*
X769725Y188584D01*
X770017Y188750D01*
X770308Y188792D01*
X770600Y188750D01*
X770975Y188584D01*
X770850Y189667D01*
X769725D01*
G01X785241Y184831D02*
Y180831D01*
X777841D01*
G01X792983Y187167D02*
Y189667D01*
X791942D01*
X791608Y189542D01*
X791400Y189375D01*
X791317Y189042D01*
X791400Y188709D01*
X791650Y188500D01*
X791942Y188375D01*
X792983D01*
G01X791942D02*
X791317Y187167D01*
G01X789842Y189250D02*
X789592Y189500D01*
X789300Y189625D01*
X788967Y189667D01*
X788550Y189584D01*
X788258Y189375D01*
X788175Y189125D01*
X788217Y188875D01*
X788383Y188667D01*
X789217Y188250D01*
X789592Y187959D01*
X789842Y187542D01*
X789925Y187167D01*
X788175D01*
G01X785950Y189667D02*
X786283Y189584D01*
X786533Y189375D01*
X786700Y189125D01*
X786825Y188792D01*
X786867Y188417D01*
X786825Y188042D01*
X786700Y187709D01*
X786533Y187459D01*
X786283Y187250D01*
X785950Y187167D01*
X785617Y187250D01*
X785367Y187459D01*
X785200Y187709D01*
X785075Y188042D01*
X785033Y188417D01*
X785075Y188792D01*
X785200Y189125D01*
X785367Y189375D01*
X785617Y189584D01*
X785950Y189667D01*
G01X783642Y189250D02*
X783392Y189500D01*
X783100Y189625D01*
X782767Y189667D01*
X782350Y189584D01*
X782058Y189375D01*
X781975Y189125D01*
X782017Y188875D01*
X782183Y188667D01*
X783017Y188250D01*
X783392Y187959D01*
X783642Y187542D01*
X783725Y187167D01*
X781975D01*
G01X793150Y184850D02*
Y180850D01*
X785750D01*
G01X795000Y190017D02*
X797500D01*
Y191058D01*
X797375Y191392D01*
X797208Y191600D01*
X796875Y191683D01*
X796542Y191600D01*
X796333Y191350D01*
X796208Y191058D01*
Y190017D01*
G01Y191058D02*
X795000Y191683D01*
G01Y193950D02*
X797500D01*
X797000Y193450D01*
G01X795000D02*
Y194450D01*
G01X795292Y196342D02*
X795083Y196633D01*
X795000Y196967D01*
X795083Y197300D01*
X795333Y197592D01*
X795708Y197800D01*
X796083Y197883D01*
X796542D01*
X796917Y197800D01*
X797250Y197592D01*
X797417Y197342D01*
X797500Y197050D01*
X797417Y196717D01*
X797250Y196467D01*
X797000Y196300D01*
X796667Y196217D01*
X796375Y196300D01*
X796083Y196508D01*
X795917Y196758D01*
X795875Y197050D01*
X795958Y197383D01*
X796167Y197633D01*
X796542Y197883D01*
G01X795500Y199233D02*
X795208Y199483D01*
X795042Y199817D01*
X795000Y200192D01*
X795042Y200525D01*
X795250Y200858D01*
X795500Y201067D01*
X795750Y201108D01*
X796042Y201025D01*
X796250Y200733D01*
X796333Y200442D01*
Y200067D01*
G01Y200442D02*
X796458Y200692D01*
X796667Y200900D01*
X796917Y200983D01*
X797167Y200900D01*
X797375Y200692D01*
X797500Y200317D01*
X797458Y199942D01*
X797292Y199567D01*
G01X798110Y180900D02*
X794110D01*
Y188300D01*
G01X795000Y214517D02*
X797500D01*
Y215558D01*
X797375Y215892D01*
X797208Y216100D01*
X796875Y216183D01*
X796542Y216100D01*
X796333Y215850D01*
X796208Y215558D01*
Y214517D01*
G01Y215558D02*
X795000Y216183D01*
G01X795500Y217533D02*
X795208Y217783D01*
X795042Y218117D01*
X795000Y218492D01*
X795042Y218825D01*
X795250Y219158D01*
X795500Y219367D01*
X795750Y219408D01*
X796042Y219325D01*
X796250Y219033D01*
X796333Y218742D01*
Y218367D01*
G01Y218742D02*
X796458Y218992D01*
X796667Y219200D01*
X796917Y219283D01*
X797167Y219200D01*
X797375Y218992D01*
X797500Y218617D01*
X797458Y218242D01*
X797292Y217867D01*
G01X797500Y221550D02*
X797417Y221217D01*
X797208Y220967D01*
X796958Y220800D01*
X796625Y220675D01*
X796250Y220633D01*
X795875Y220675D01*
X795542Y220800D01*
X795292Y220967D01*
X795083Y221217D01*
X795000Y221550D01*
X795083Y221883D01*
X795292Y222133D01*
X795542Y222300D01*
X795875Y222425D01*
X796250Y222467D01*
X796625Y222425D01*
X796958Y222300D01*
X797208Y222133D01*
X797417Y221883D01*
X797500Y221550D01*
G01X795000Y225150D02*
X797500D01*
X795708Y223608D01*
Y225692D01*
G01X794500Y234700D02*
X798500D01*
Y227300D01*
G01X790000Y214517D02*
X792500D01*
Y215558D01*
X792375Y215892D01*
X792208Y216100D01*
X791875Y216183D01*
X791542Y216100D01*
X791333Y215850D01*
X791208Y215558D01*
Y214517D01*
G01Y215558D02*
X790000Y216183D01*
G01X790500Y217533D02*
X790208Y217783D01*
X790042Y218117D01*
X790000Y218492D01*
X790042Y218825D01*
X790250Y219158D01*
X790500Y219367D01*
X790750Y219408D01*
X791042Y219325D01*
X791250Y219033D01*
X791333Y218742D01*
Y218367D01*
G01Y218742D02*
X791458Y218992D01*
X791667Y219200D01*
X791917Y219283D01*
X792167Y219200D01*
X792375Y218992D01*
X792500Y218617D01*
X792458Y218242D01*
X792292Y217867D01*
G01X792500Y221550D02*
X792417Y221217D01*
X792208Y220967D01*
X791958Y220800D01*
X791625Y220675D01*
X791250Y220633D01*
X790875Y220675D01*
X790542Y220800D01*
X790292Y220967D01*
X790083Y221217D01*
X790000Y221550D01*
X790083Y221883D01*
X790292Y222133D01*
X790542Y222300D01*
X790875Y222425D01*
X791250Y222467D01*
X791625Y222425D01*
X791958Y222300D01*
X792208Y222133D01*
X792417Y221883D01*
X792500Y221550D01*
G01Y224650D02*
X792417Y224317D01*
X792208Y224067D01*
X791958Y223900D01*
X791625Y223775D01*
X791250Y223733D01*
X790875Y223775D01*
X790542Y223900D01*
X790292Y224067D01*
X790083Y224317D01*
X790000Y224650D01*
X790083Y224983D01*
X790292Y225233D01*
X790542Y225400D01*
X790875Y225525D01*
X791250Y225567D01*
X791625Y225525D01*
X791958Y225400D01*
X792208Y225233D01*
X792417Y224983D01*
X792500Y224650D01*
G01X794000Y227300D02*
X790000D01*
Y234700D01*
G01X801792Y191767D02*
X801917Y191517D01*
X802000Y191225D01*
Y190892D01*
X801875Y190517D01*
X801667Y190225D01*
X801417Y190017D01*
X801000Y189850D01*
X800625Y189808D01*
X800250Y189892D01*
X800000Y190017D01*
X799750Y190267D01*
X799583Y190558D01*
X799500Y190850D01*
Y191142D01*
X799583Y191433D01*
X799708Y191683D01*
X799875Y191892D01*
G01X800000Y193033D02*
X799708Y193283D01*
X799542Y193617D01*
X799500Y193992D01*
X799542Y194325D01*
X799750Y194658D01*
X800000Y194867D01*
X800250Y194908D01*
X800542Y194825D01*
X800750Y194533D01*
X800833Y194242D01*
Y193867D01*
G01Y194242D02*
X800958Y194492D01*
X801167Y194700D01*
X801417Y194783D01*
X801667Y194700D01*
X801875Y194492D01*
X802000Y194117D01*
X801958Y193742D01*
X801792Y193367D01*
G01X799500Y197550D02*
X802000D01*
X800208Y196008D01*
Y198092D01*
G01X800542Y199358D02*
X800833Y199650D01*
X801000Y199900D01*
X801083Y200233D01*
X801000Y200525D01*
X800833Y200733D01*
X800583Y200900D01*
X800292Y200942D01*
X800042Y200900D01*
X799792Y200733D01*
X799583Y200483D01*
X799500Y200192D01*
X799583Y199858D01*
X799833Y199567D01*
X800208Y199400D01*
X800625Y199358D01*
X801167Y199442D01*
X801458Y199567D01*
X801750Y199775D01*
X801958Y200067D01*
X802000Y200358D01*
X801917Y200650D01*
X801708Y200858D01*
G01X806292Y191767D02*
X806417Y191517D01*
X806500Y191225D01*
Y190892D01*
X806375Y190517D01*
X806167Y190225D01*
X805917Y190017D01*
X805500Y189850D01*
X805125Y189808D01*
X804750Y189892D01*
X804500Y190017D01*
X804250Y190267D01*
X804083Y190558D01*
X804000Y190850D01*
Y191142D01*
X804083Y191433D01*
X804208Y191683D01*
X804375Y191892D01*
G01X804500Y193033D02*
X804208Y193283D01*
X804042Y193617D01*
X804000Y193992D01*
X804042Y194325D01*
X804250Y194658D01*
X804500Y194867D01*
X804750Y194908D01*
X805042Y194825D01*
X805250Y194533D01*
X805333Y194242D01*
Y193867D01*
G01Y194242D02*
X805458Y194492D01*
X805667Y194700D01*
X805917Y194783D01*
X806167Y194700D01*
X806375Y194492D01*
X806500Y194117D01*
X806458Y193742D01*
X806292Y193367D01*
G01X804000Y197550D02*
X806500D01*
X804708Y196008D01*
Y198092D01*
G01X804375Y199233D02*
X804167Y199483D01*
X804042Y199775D01*
X804000Y200150D01*
X804083Y200525D01*
X804250Y200817D01*
X804542Y201025D01*
X804875Y201067D01*
X805208Y200983D01*
X805417Y200775D01*
X805583Y200483D01*
X805625Y200192D01*
X805583Y199900D01*
X805417Y199525D01*
X806500Y199650D01*
Y200775D01*
G01X795930Y291771D02*
Y235171D01*
G01X763930D02*
X762230Y236871D01*
G01D02*
X760530Y235171D01*
G01X777200Y185667D02*
Y183167D01*
G01X778158Y185667D02*
X776242D01*
G01X774933Y183167D02*
Y185667D01*
X773933D01*
X773600Y185542D01*
X773350Y185250D01*
X773267Y184917D01*
X773350Y184584D01*
X773558Y184334D01*
X773933Y184209D01*
X774933D01*
G01X771000Y183167D02*
Y185667D01*
X771500Y185167D01*
G01Y183167D02*
X770500D01*
G01X767900Y185667D02*
X768233Y185584D01*
X768483Y185375D01*
X768650Y185125D01*
X768775Y184792D01*
X768817Y184417D01*
X768775Y184042D01*
X768650Y183709D01*
X768483Y183459D01*
X768233Y183250D01*
X767900Y183167D01*
X767567Y183250D01*
X767317Y183459D01*
X767150Y183709D01*
X767025Y184042D01*
X766983Y184417D01*
X767025Y184792D01*
X767150Y185125D01*
X767317Y185375D01*
X767567Y185584D01*
X767900Y185667D01*
G01X764800Y183167D02*
X764508Y183209D01*
X764175Y183334D01*
X763967Y183542D01*
X763883Y183834D01*
X763967Y184125D01*
X764217Y184375D01*
X764592Y184500D01*
X765008D01*
X765258Y184584D01*
X765467Y184792D01*
X765550Y185084D01*
X765425Y185375D01*
X765133Y185584D01*
X764800Y185667D01*
X764467Y185584D01*
X764175Y185375D01*
X764050Y185084D01*
X764133Y184792D01*
X764342Y184584D01*
X764592Y184500D01*
X765008D01*
X765383Y184375D01*
X765633Y184125D01*
X765717Y183834D01*
X765633Y183542D01*
X765425Y183334D01*
X765092Y183209D01*
X764800Y183167D01*
G54D16*
G01X168938Y434870D02*
Y430870D01*
G01X253500Y366500D02*
X252400D01*
G01X256200D02*
X255100D01*
G01X260700Y413900D02*
X261800D01*
G01X278000Y140200D02*
Y139100D01*
G01Y142900D02*
Y141800D01*
G01X277500Y162200D02*
Y161100D01*
G01Y164900D02*
Y163800D01*
G01X298500Y141500D02*
X302500D01*
G01X303000Y162000D02*
X299000D01*
G01X278000Y203700D02*
Y202600D01*
G01Y206400D02*
Y205300D01*
G01Y223700D02*
Y222600D01*
G01Y226400D02*
Y225300D01*
G01X277500Y182200D02*
Y181100D01*
G01Y184900D02*
Y183800D01*
G01X302500Y202000D02*
X298500D01*
G01X299000Y226000D02*
X303000D01*
G01X298500Y183500D02*
X302500D01*
G01X277500Y245200D02*
Y244100D01*
G01Y247900D02*
Y246800D01*
G01X302500Y244500D02*
X298500D01*
G01X263400Y413900D02*
X264500D01*
G01X360810Y252140D02*
X364810D01*
G01X360868Y280287D02*
X364868D01*
G01Y266241D02*
X360868D01*
G01X364689Y294341D02*
X360689D01*
G01X360677Y308062D02*
X364677D01*
G01X545295Y473383D02*
Y469383D01*
G01X633781Y131508D02*
X629781D01*
G01X621526Y250452D02*
Y254452D01*
G01X607026D02*
Y250452D01*
G01X580700Y462000D02*
X579600D01*
G01X583400D02*
X582300D01*
G01X642000Y254000D02*
Y250000D01*
G01X656500D02*
Y254000D01*
G01X674531Y382633D02*
X678531D01*
G01X639920Y455130D02*
X641020D01*
G01X637220D02*
X638320D01*
G01X723104Y336538D02*
Y340538D01*
G01X778500Y111500D02*
X774500D01*
G01X786107Y125393D02*
X790107D01*
M02*
